(kicad_pcb (version 20221018) (generator pcbnew)

  (general
    (thickness 1.656)
  )

  (paper "A4")
  (title_block
    (title "SDI-MIPI Bridge")
    (date "2023-08-09")
    (rev "1.3.4")
    (company "Antmicro")
  )

  (layers
    (0 "F.Cu" signal)
    (1 "In1.Cu" power)
    (2 "In2.Cu" power)
    (3 "In3.Cu" signal)
    (4 "In4.Cu" signal)
    (31 "B.Cu" signal)
    (32 "B.Adhes" user "B.Adhesive")
    (33 "F.Adhes" user "F.Adhesive")
    (34 "B.Paste" user)
    (35 "F.Paste" user)
    (36 "B.SilkS" user "B.Silkscreen")
    (37 "F.SilkS" user "F.Silkscreen")
    (38 "B.Mask" user)
    (39 "F.Mask" user)
    (40 "Dwgs.User" user "User.Drawings")
    (41 "Cmts.User" user "User.Comments")
    (42 "Eco1.User" user "User.Eco1")
    (43 "Eco2.User" user "User.Eco2")
    (44 "Edge.Cuts" user)
    (45 "Margin" user)
    (46 "B.CrtYd" user "B.Courtyard")
    (47 "F.CrtYd" user "F.Courtyard")
    (48 "B.Fab" user)
    (49 "F.Fab" user)
  )

  (setup
    (stackup
      (layer "F.SilkS" (type "Top Silk Screen") (color "White"))
      (layer "F.Paste" (type "Top Solder Paste"))
      (layer "F.Mask" (type "Top Solder Mask") (color "Black") (thickness 0.02))
      (layer "F.Cu" (type "copper") (thickness 0.018))
      (layer "dielectric 1" (type "prepreg") (thickness 0.24) (material "FR4") (epsilon_r 4.2) (loss_tangent 0.02))
      (layer "In1.Cu" (type "copper") (thickness 0.035))
      (layer "dielectric 2" (type "core") (thickness 0.36) (material "FR4") (epsilon_r 4.2) (loss_tangent 0.02))
      (layer "In2.Cu" (type "copper") (thickness 0.035))
      (layer "dielectric 3" (type "prepreg") (thickness 0.24) (material "FR4") (epsilon_r 4.2) (loss_tangent 0.02))
      (layer "In3.Cu" (type "copper") (thickness 0.035))
      (layer "dielectric 4" (type "core") (thickness 0.36) (material "FR4") (epsilon_r 4.5) (loss_tangent 0.02))
      (layer "In4.Cu" (type "copper") (thickness 0.035))
      (layer "dielectric 5" (type "prepreg") (thickness 0.24) (material "FR4") (epsilon_r 4.2) (loss_tangent 0.02))
      (layer "B.Cu" (type "copper") (thickness 0.018))
      (layer "B.Mask" (type "Bottom Solder Mask") (color "Black") (thickness 0.02))
      (layer "B.Paste" (type "Bottom Solder Paste"))
      (layer "B.SilkS" (type "Bottom Silk Screen") (color "White"))
      (copper_finish "None")
      (dielectric_constraints yes)
    )
    (pad_to_mask_clearance 0.051)
    (solder_mask_min_width 0.25)
    (pcbplotparams
      (layerselection 0x00010fc_ffffffff)
      (plot_on_all_layers_selection 0x0000000_00000000)
      (disableapertmacros false)
      (usegerberextensions false)
      (usegerberattributes false)
      (usegerberadvancedattributes false)
      (creategerberjobfile false)
      (dashed_line_dash_ratio 12.000000)
      (dashed_line_gap_ratio 3.000000)
      (svgprecision 6)
      (plotframeref false)
      (viasonmask false)
      (mode 1)
      (useauxorigin false)
      (hpglpennumber 1)
      (hpglpenspeed 20)
      (hpglpendiameter 15.000000)
      (dxfpolygonmode true)
      (dxfimperialunits true)
      (dxfusepcbnewfont true)
      (psnegative false)
      (psa4output false)
      (plotreference true)
      (plotvalue true)
      (plotinvisibletext false)
      (sketchpadsonfab false)
      (subtractmaskfromsilk false)
      (outputformat 1)
      (mirror false)
      (drillshape 0)
      (scaleselection 1)
      (outputdirectory "./pcb")
    )
  )

  (net 0 "")
  (net 1 "GNDREF")
  (net 2 "+1V2")
  (net 3 "GNDA")
  (net 4 "VPP")
  (net 5 "+3.3VA")
  (net 6 "+3V3")
  (net 7 "/XTAL2")
  (net 8 "/XTAL1")
  (net 9 "/AGCP")
  (net 10 "/LF")
  (net 11 "/VBG")
  (net 12 "/AGCN")
  (net 13 "/PCLK")
  (net 14 "/H_HSYNC")
  (net 15 "/V_VSYNC")
  (net 16 "/20bit_~{10bit}")
  (net 17 "/~{SMPTE_BYPASS}")
  (net 18 "/DVB_ASI")
  (net 19 "/F_DE")
  (net 20 "/LOCKED")
  (net 21 "/Y_1ANC")
  (net 22 "/~{DATA_ERROR}")
  (net 23 "/TIM_861")
  (net 24 "/~{RC_BYP}")
  (net 25 "Net-(U1-BYP)")
  (net 26 "/AUDIO_MASTER_CLK")
  (net 27 "Net-(U3-SDO+)")
  (net 28 "/AUDIO_SERIAL_BIT_CLK")
  (net 29 "Net-(U3-SDO-)")
  (net 30 "/D0")
  (net 31 "/D1")
  (net 32 "/D2")
  (net 33 "/D3")
  (net 34 "/D4")
  (net 35 "/D5")
  (net 36 "/D6")
  (net 37 "/D7")
  (net 38 "/D8")
  (net 39 "/D9")
  (net 40 "/LB_CONT")
  (net 41 "/IOPROC_EN_~{DIS}")
  (net 42 "/SCLK_TCK")
  (net 43 "/SDIN_TDI")
  (net 44 "/JTAG_~{HOST}")
  (net 45 "/~{CS}_TMS")
  (net 46 "/SDOUT_TDO")
  (net 47 "/SW_EN")
  (net 48 "unconnected-(J3-Pad13)")
  (net 49 "/AUDIO_OUTPUT_CH7_8")
  (net 50 "/AUDIO_OUTPUT_CH5_6")
  (net 51 "/AUDIO_OUTPUT_CH3_4")
  (net 52 "/AUDIO_OUTPUT_CH1_2")
  (net 53 "/Audio_EN_~{DIS}")
  (net 54 "/STANDBY")
  (net 55 "/SDO_EN_DIS")
  (net 56 "Net-(D1-Pad1)")
  (net 57 "VDD")
  (net 58 "/GNDPLL_DPHY")
  (net 59 "/GNDGPLL")
  (net 60 "/AUDIO_WORD_CLK")
  (net 61 "/SCL_GS")
  (net 62 "/SDA_GS")
  (net 63 "Net-(U2A-AMCLK)")
  (net 64 "Net-(U2A-ACLK)")
  (net 65 "Net-(C23-Pad1)")
  (net 66 "Net-(U2A-WCLK)")
  (net 67 "Net-(U3-RSET)")
  (net 68 "Net-(C27-Pad2)")
  (net 69 "Net-(C43-Pad1)")
  (net 70 "Net-(C43-Pad2)")
  (net 71 "Net-(U1-FB)")
  (net 72 "Net-(U5-~{RESET})")
  (net 73 "Net-(U3-~{EQ_EN})")
  (net 74 "Net-(U5-A0)")
  (net 75 "Net-(U5-A1)")
  (net 76 "IO_VDD")
  (net 77 "VCCA_DPHY")
  (net 78 "VCO_VDD")
  (net 79 "VCC_IO")
  (net 80 "/SCL2")
  (net 81 "/SDA2")
  (net 82 "/SCL1")
  (net 83 "/SDA1")
  (net 84 "Net-(U5-A2)")
  (net 85 "Net-(U4-VCCA_DPHY1)")
  (net 86 "Net-(D2-Pad1)")
  (net 87 "/LOCKED_CL")
  (net 88 "/CDONE")
  (net 89 "VCCGPLL")
  (net 90 "/SDI_P")
  (net 91 "Net-(D4-Pad1)")
  (net 92 "/SDI_N")
  (net 93 "/SDO_N")
  (net 94 "/SDO_P")
  (net 95 "Net-(D5-Pad1)")
  (net 96 "/MISO")
  (net 97 "/MOSI")
  (net 98 "Net-(R67-Pad2)")
  (net 99 "/SPI_SS(SCL)")
  (net 100 "/CRESET_B")
  (net 101 "/USER_SCL")
  (net 102 "/SPI_SCK(SDA)")
  (net 103 "/USER_SDA")
  (net 104 "Net-(U4-VCCA_DPHY0)")
  (net 105 "/USER_SW")
  (net 106 "/USER_LED")
  (net 107 "unconnected-(J3-Pad14)")
  (net 108 "unconnected-(J3-Pad16)")
  (net 109 "unconnected-(J3-Pad17)")
  (net 110 "unconnected-(J3-Pad31)")
  (net 111 "unconnected-(J3-Pad32)")
  (net 112 "unconnected-(J3-Pad34)")
  (net 113 "/RST")
  (net 114 "unconnected-(J3-Pad35)")
  (net 115 "unconnected-(J3-Pad36)")
  (net 116 "unconnected-(J3-Pad37)")
  (net 117 "unconnected-(J3-Pad38)")
  (net 118 "unconnected-(J3-Pad43)")
  (net 119 "unconnected-(J3-Pad44)")
  (net 120 "unconnected-(J3-Pad45)")
  (net 121 "unconnected-(J3-Pad46)")
  (net 122 "unconnected-(J3-Pad49)")
  (net 123 "unconnected-(J3-Pad50)")
  (net 124 "unconnected-(J6-Pad6)")
  (net 125 "Net-(R82-Pad2)")
  (net 126 "/~{RST_TRST}")
  (net 127 "/~{RST_TRST_SOFT}")
  (net 128 "Net-(U4-PB53{slash}SPI_SCK{slash}MCK{slash}SDA)")
  (net 129 "Net-(U1-~{POK})")
  (net 130 "Net-(U2B-XTAL_OUT)")
  (net 131 "Net-(U3-~{OSP})")
  (net 132 "unconnected-(U2B-RSV-PadB3)")
  (net 133 "unconnected-(U2B-RSV-PadF2)")
  (net 134 "unconnected-(U3-NC-Pad5)")
  (net 135 "unconnected-(U3-NC-Pad7)")
  (net 136 "Net-(J3-Pad47)")
  (net 137 "unconnected-(U3-NC-Pad8)")
  (net 138 "unconnected-(U3-NC-Pad13)")
  (net 139 "unconnected-(U3-NC-Pad15)")
  (net 140 "Net-(C31-Pad2)")
  (net 141 "Net-(C45-Pad2)")
  (net 142 "Net-(C56-Pad1)")
  (net 143 "/MIPI0_D3_N")
  (net 144 "/MIPI0_D3_P")
  (net 145 "/MIPI0_D2_N")
  (net 146 "/MIPI0_D2_P")
  (net 147 "/MIPI0_D1_N")
  (net 148 "/MIPI0_D1_P")
  (net 149 "/MIPI0_D0_N")
  (net 150 "/MIPI0_D0_P")
  (net 151 "/MIPI0_CLK_N")
  (net 152 "/MIPI0_CLK_P")
  (net 153 "/MIPI1_D3_N")
  (net 154 "/MIPI1_D3_P")
  (net 155 "/MIPI1_D2_N")
  (net 156 "/MIPI1_D2_P")
  (net 157 "/MIPI1_D1_N")
  (net 158 "/MIPI1_D1_P")
  (net 159 "/MIPI1_D0_N")
  (net 160 "/MIPI1_D0_P")
  (net 161 "/MIPI1_CLK_N")
  (net 162 "/MIPI1_CLK_P")
  (net 163 "unconnected-(U5-GPIO1{slash}~{SS1}-Pad2)")
  (net 164 "unconnected-(U5-~{INT}-Pad9)")
  (net 165 "unconnected-(U5-GPIO3{slash}~{SS3}-Pad13)")
  (net 166 "/DOUT18")
  (net 167 "/DOUT17")
  (net 168 "/DOUT19")
  (net 169 "/DOUT16")
  (net 170 "/DOUT15")
  (net 171 "/DOUT12")
  (net 172 "/DOUT14")
  (net 173 "/DOUT13")
  (net 174 "/DOUT10")
  (net 175 "/DOUT11")

  (footprint "sdi-mipi-bridge-footprints:BGA100_11x11mm_SEMTECH" locked (layer "F.Cu")
    (at 121 115.4)
    (property "Author" "Antmicro")
    (property "License" "Apache-2.0")
    (property "MPN" "GS2971A")
    (property "Manufacturer" "Semtech")
    (property "Sheetfile" "sdi-mipi-bridge.kicad_sch")
    (property "Sheetname" "")
    (property "ki_description" "3Gb/s, HD, SD SDI Receiver, with Integrated Adaptive Cable Equalizer complete\nwith SMPTE Audio and Video Processing")
    (attr smd)
    (fp_text reference "U2" (at 0 -6.15) (layer "F.SilkS")
        (effects (font (size 0.7 0.7) (thickness 0.15)) (justify left bottom))
    )
    (fp_text value "GS2971A" (at 0 7) (layer "F.Fab")
        (effects (font (size 0.7 0.7) (thickness 0.15)) (justify left bottom))
    )
    (fp_text user "${REFERENCE}" (at -6 9) (layer "F.Fab") hide
        (effects (font (size 0.7 0.7) (thickness 0.15)) (justify left bottom))
    )
    (fp_text user "Author: Antmicro" (at -6 10.2) (layer "F.Fab") hide
        (effects (font (size 0.7 0.7) (thickness 0.15)) (justify left bottom))
    )
    (fp_text user "License: Apache-2.0" (at -6 11.4) (layer "F.Fab") hide
        (effects (font (size 0.7 0.7) (thickness 0.15)) (justify left bottom))
    )
    (fp_line (start -5.65 -5.65) (end -5.65 -2.894)
      (stroke (width 0.15) (type solid)) (layer "F.SilkS"))
    (fp_line (start -5.65 5.65) (end -5.65 2.9)
      (stroke (width 0.15) (type solid)) (layer "F.SilkS"))
    (fp_line (start -2.919 -5.65) (end -5.65 -5.65)
      (stroke (width 0.15) (type solid)) (layer "F.SilkS"))
    (fp_line (start -2.9 5.65) (end -5.65 5.65)
      (stroke (width 0.15) (type solid)) (layer "F.SilkS"))
    (fp_line (start 2.901 -5.65) (end 5.65 -5.65)
      (stroke (width 0.15) (type solid)) (layer "F.SilkS"))
    (fp_line (start 2.901 5.65) (end 5.65 5.65)
      (stroke (width 0.15) (type solid)) (layer "F.SilkS"))
    (fp_line (start 5.65 -5.65) (end 5.65 -2.901)
      (stroke (width 0.15) (type solid)) (layer "F.SilkS"))
    (fp_line (start 5.65 5.65) (end 5.65 2.9)
      (stroke (width 0.15) (type solid)) (layer "F.SilkS"))
    (fp_circle (center -5.8 -5.8) (end -5.75 -5.8)
      (stroke (width 0.15) (type solid)) (fill solid) (layer "F.SilkS"))
    (fp_rect (start -6 -6) (end 5.999 5.999)
      (stroke (width 0.05) (type solid)) (fill none) (layer "F.CrtYd"))
    (fp_line (start -4.5 -5.5) (end -5.5 -4.5)
      (stroke (width 0.15) (type solid)) (layer "F.Fab"))
    (fp_rect (start 5.5 5.5) (end -5.5 -5.5)
      (stroke (width 0.15) (type solid)) (fill none) (layer "F.Fab"))
    (pad "A1" smd circle locked (at -4.518 -4.494) (size 0.5 0.5) (layers "F.Cu" "F.Paste" "F.Mask")
      (net 11 "/VBG") (pinfunction "VBG") (pintype "input"))
    (pad "A2" smd circle locked (at -3.519 -4.494) (size 0.5 0.5) (layers "F.Cu" "F.Paste" "F.Mask")
      (net 10 "/LF") (pinfunction "LF") (pintype "input"))
    (pad "A3" smd circle locked (at -2.519 -4.494) (size 0.5 0.5) (layers "F.Cu" "F.Paste" "F.Mask")
      (net 40 "/LB_CONT") (pinfunction "LB_CONT") (pintype "input"))
    (pad "A4" smd circle locked (at -1.518 -4.494) (size 0.5 0.5) (layers "F.Cu" "F.Paste" "F.Mask")
      (net 78 "VCO_VDD") (pinfunction "VCO_{VDD}") (pintype "power_in"))
    (pad "A5" smd circle locked (at -0.519 -4.494) (size 0.5 0.5) (layers "F.Cu" "F.Paste" "F.Mask")
      (net 14 "/H_HSYNC") (pinfunction "STAT0") (pintype "output"))
    (pad "A6" smd circle locked (at 0.481 -4.494) (size 0.5 0.5) (layers "F.Cu" "F.Paste" "F.Mask")
      (net 15 "/V_VSYNC") (pinfunction "STAT1") (pintype "output"))
    (pad "A7" smd circle locked (at 1.481 -4.494) (size 0.5 0.5) (layers "F.Cu" "F.Paste" "F.Mask")
      (net 76 "IO_VDD") (pinfunction "IO_{VDD}") (pintype "power_in"))
    (pad "A8" smd circle locked (at 2.482 -4.494) (size 0.5 0.5) (layers "F.Cu" "F.Paste" "F.Mask")
      (net 13 "/PCLK") (pinfunction "PCLK") (pintype "output"))
    (pad "A9" smd circle locked (at 3.482 -4.494) (size 0.5 0.5) (layers "F.Cu" "F.Paste" "F.Mask")
      (net 166 "/DOUT18") (pinfunction "DOUT18") (pintype "output"))
    (pad "A10" smd circle locked (at 4.482 -4.494) (size 0.5 0.5) (layers "F.Cu" "F.Paste" "F.Mask")
      (net 167 "/DOUT17") (pinfunction "DOUT17") (pintype "output"))
    (pad "B1" smd circle locked (at -4.518 -3.493) (size 0.5 0.5) (layers "F.Cu" "F.Paste" "F.Mask")
      (net 5 "+3.3VA") (pinfunction "A_{VDD}") (pintype "power_in"))
    (pad "B2" smd circle locked (at -3.519 -3.493) (size 0.5 0.5) (layers "F.Cu" "F.Paste" "F.Mask")
      (net 4 "VPP") (pinfunction "PLL_{VDD}") (pintype "power_in"))
    (pad "B3" smd circle locked (at -2.519 -3.493) (size 0.5 0.5) (layers "F.Cu" "F.Paste" "F.Mask")
      (net 132 "unconnected-(U2B-RSV-PadB3)") (pinfunction "RSV") (pintype "no_connect"))
    (pad "B4" smd circle locked (at -1.518 -3.493) (size 0.5 0.5) (layers "F.Cu" "F.Paste" "F.Mask")
      (net 3 "GNDA") (pinfunction "VCO_{GND}") (pintype "power_in"))
    (pad "B5" smd circle locked (at -0.519 -3.493) (size 0.5 0.5) (layers "F.Cu" "F.Paste" "F.Mask")
      (net 19 "/F_DE") (pinfunction "STAT2") (pintype "output"))
    (pad "B6" smd circle locked (at 0.481 -3.493) (size 0.5 0.5) (layers "F.Cu" "F.Paste" "F.Mask")
      (net 20 "/LOCKED") (pinfunction "STAT3") (pintype "output"))
    (pad "B7" smd circle locked (at 1.481 -3.493) (size 0.5 0.5) (layers "F.Cu" "F.Paste" "F.Mask")
      (net 1 "GNDREF") (pinfunction "IO_{GND}") (pintype "power_in"))
    (pad "B8" smd circle locked (at 2.482 -3.493) (size 0.5 0.5) (layers "F.Cu" "F.Paste" "F.Mask")
      (net 168 "/DOUT19") (pinfunction "DOUT19") (pintype "output"))
    (pad "B9" smd circle locked (at 3.482 -3.493) (size 0.5 0.5) (layers "F.Cu" "F.Paste" "F.Mask")
      (net 169 "/DOUT16") (pinfunction "DOUT16") (pintype "output"))
    (pad "B10" smd circle locked (at 4.482 -3.493) (size 0.5 0.5) (layers "F.Cu" "F.Paste" "F.Mask")
      (net 170 "/DOUT15") (pinfunction "DOUT15") (pintype "output"))
    (pad "C1" smd circle locked (at -4.518 -2.493) (size 0.5 0.5) (layers "F.Cu" "F.Paste" "F.Mask")
      (net 90 "/SDI_P") (pinfunction "SDI+") (pintype "input"))
    (pad "C2" smd circle locked (at -3.519 -2.493) (size 0.5 0.5) (layers "F.Cu" "F.Paste" "F.Mask")
      (net 3 "GNDA") (pinfunction "A_{GND}") (pintype "power_in"))
    (pad "C3" smd circle locked (at -2.519 -2.493) (size 0.5 0.5) (layers "F.Cu" "F.Paste" "F.Mask")
      (net 4 "VPP") (pinfunction "PLL_{VDD}") (pintype "passive"))
    (pad "C4" smd circle locked (at -1.518 -2.493) (size 0.5 0.5) (layers "F.Cu" "F.Paste" "F.Mask")
      (net 4 "VPP") (pinfunction "PLL_{VDD}") (pintype "passive"))
    (pad "C5" smd circle locked (at -0.519 -2.493) (size 0.5 0.5) (layers "F.Cu" "F.Paste" "F.Mask")
      (net 21 "/Y_1ANC") (pinfunction "STAT4") (pintype "output"))
    (pad "C6" smd circle locked (at 0.481 -2.493) (size 0.5 0.5) (layers "F.Cu" "F.Paste" "F.Mask")
      (net 22 "/~{DATA_ERROR}") (pinfunction "STAT5") (pintype "output"))
    (pad "C7" smd circle locked (at 1.481 -2.493) (size 0.5 0.5) (layers "F.Cu" "F.Paste" "F.Mask")
      (net 126 "/~{RST_TRST}") (pinfunction "RESET_TRST") (pintype "input"))
    (pad "C8" smd circle locked (at 2.482 -2.493) (size 0.5 0.5) (layers "F.Cu" "F.Paste" "F.Mask")
      (net 171 "/DOUT12") (pinfunction "DOUT12") (pintype "output"))
    (pad "C9" smd circle locked (at 3.482 -2.493) (size 0.5 0.5) (layers "F.Cu" "F.Paste" "F.Mask")
      (net 172 "/DOUT14") (pinfunction "DOUT14") (pintype "output"))
    (pad "C10" smd circle locked (at 4.482 -2.493) (size 0.5 0.5) (layers "F.Cu" "F.Paste" "F.Mask")
      (net 173 "/DOUT13") (pinfunction "DOUT13") (pintype "output"))
    (pad "D1" smd circle locked (at -4.518 -1.494) (size 0.5 0.5) (layers "F.Cu" "F.Paste" "F.Mask")
      (net 92 "/SDI_N") (pinfunction "SDI-") (pintype "input"))
    (pad "D2" smd circle locked (at -3.519 -1.494) (size 0.5 0.5) (layers "F.Cu" "F.Paste" "F.Mask")
      (net 3 "GNDA") (pinfunction "A_{GND}") (pintype "passive"))
    (pad "D3" smd circle locked (at -2.519 -1.494) (size 0.5 0.5) (layers "F.Cu" "F.Paste" "F.Mask")
      (net 3 "GNDA") (pinfunction "A_{GND}") (pintype "passive"))
    (pad "D4" smd circle locked (at -1.518 -1.494) (size 0.5 0.5) (layers "F.Cu" "F.Paste" "F.Mask")
      (net 3 "GNDA") (pinfunction "PLL_{GND}") (pintype "power_in"))
    (pad "D5" smd circle locked (at -0.519 -1.494) (size 0.5 0.5) (layers "F.Cu" "F.Paste" "F.Mask")
      (net 1 "GNDREF") (pinfunction "CORE_{GND}") (pintype "power_in"))
    (pad "D6" smd circle locked (at 0.481 -1.494) (size 0.5 0.5) (layers "F.Cu" "F.Paste" "F.Mask")
      (net 2 "+1V2") (pinfunction "CORE_{VDD}") (pintype "power_in"))
    (pad "D7" smd circle locked (at 1.481 -1.494) (size 0.5 0.5) (layers "F.Cu" "F.Paste" "F.Mask")
      (net 47 "/SW_EN") (pinfunction "SW_EN") (pintype "input"))
    (pad "D8" smd circle locked (at 2.482 -1.494) (size 0.5 0.5) (layers "F.Cu" "F.Paste" "F.Mask")
      (net 44 "/JTAG_~{HOST}") (pinfunction "JTAG/~{HOST}") (pintype "input"))
    (pad "D9" smd circle locked (at 3.482 -1.494) (size 0.5 0.5) (layers "F.Cu" "F.Paste" "F.Mask")
      (net 1 "GNDREF") (pinfunction "IO_{GND}") (pintype "passive"))
    (pad "D10" smd circle locked (at 4.482 -1.494) (size 0.5 0.5) (layers "F.Cu" "F.Paste" "F.Mask")
      (net 76 "IO_VDD") (pinfunction "IO_{VDD}") (pintype "passive"))
    (pad "E1" smd circle locked (at -4.518 -0.493) (size 0.5 0.5) (layers "F.Cu" "F.Paste" "F.Mask")
      (net 5 "+3.3VA") (pinfunction "EQ_{VDD}") (pintype "power_in"))
    (pad "E2" smd circle locked (at -3.519 -0.493) (size 0.5 0.5) (layers "F.Cu" "F.Paste" "F.Mask")
      (net 3 "GNDA") (pinfunction "EQ_{GND}") (pintype "power_in"))
    (pad "E3" smd circle locked (at -2.519 -0.493) (size 0.5 0.5) (layers "F.Cu" "F.Paste" "F.Mask")
      (net 3 "GNDA") (pinfunction "A_{GND}") (pintype "passive"))
    (pad "E4" smd circle locked (at -1.518 -0.493) (size 0.5 0.5) (layers "F.Cu" "F.Paste" "F.Mask")
      (net 3 "GNDA") (pinfunction "PLL_{GND}") (pintype "passive"))
    (pad "E5" smd circle locked (at -0.519 -0.493) (size 0.5 0.5) (layers "F.Cu" "F.Paste" "F.Mask")
      (net 1 "GNDREF") (pinfunction "CORE_{GND}") (pintype "passive"))
    (pad "E6" smd circle locked (at 0.481 -0.493) (size 0.5 0.5) (layers "F.Cu" "F.Paste" "F.Mask")
      (net 2 "+1V2") (pinfunction "CORE_{VDD}") (pintype "passive"))
    (pad "E7" smd circle locked (at 1.481 -0.493) (size 0.5 0.5) (layers "F.Cu" "F.Paste" "F.Mask")
      (net 46 "/SDOUT_TDO") (pinfunction "SDOUT_TDO") (pintype "output"))
    (pad "E8" smd circle locked (at 2.482 -0.493) (size 0.5 0.5) (layers "F.Cu" "F.Paste" "F.Mask")
      (net 43 "/SDIN_TDI") (pinfunction "SDIN_TDI") (pintype "input"))
    (pad "E9" smd circle locked (at 3.482 -0.493) (size 0.5 0.5) (layers "F.Cu" "F.Paste" "F.Mask")
      (net 174 "/DOUT10") (pinfunction "DOUT10") (pintype "output"))
    (pad "E10" smd circle locked (at 4.482 -0.493) (size 0.5 0.5) (layers "F.Cu" "F.Paste" "F.Mask")
      (net 175 "/DOUT11") (pinfunction "DOUT11") (pintype "output"))
    (pad "F1" smd circle locked (at -4.518 0.506) (size 0.5 0.5) (layers "F.Cu" "F.Paste" "F.Mask")
      (net 9 "/AGCP") (pinfunction "AGC+") (pintype "passive"))
    (pad "F2" smd circle locked (at -3.519 0.506) (size 0.5 0.5) (layers "F.Cu" "F.Paste" "F.Mask")
      (net 133 "unconnected-(U2B-RSV-PadF2)") (pinfunction "RSV") (pintype "no_connect"))
    (pad "F3" smd circle locked (at -2.519 0.506) (size 0.5 0.5) (layers "F.Cu" "F.Paste" "F.Mask")
      (net 3 "GNDA") (pinfunction "A_{GND}") (pintype "passive"))
    (pad "F4" smd circle locked (at -1.518 0.506) (size 0.5 0.5) (layers "F.Cu" "F.Paste" "F.Mask")
      (net 3 "GNDA") (pinfunction "PLL_{GND}") (pintype "passive"))
    (pad "F5" smd circle locked (at -0.519 0.506) (size 0.5 0.5) (layers "F.Cu" "F.Paste" "F.Mask")
      (net 1 "GNDREF") (pinfunction "CORE_{GND}") (pintype "passive"))
    (pad "F6" smd circle locked (at 0.481 0.506) (size 0.5 0.5) (layers "F.Cu" "F.Paste" "F.Mask")
      (net 2 "+1V2") (pinfunction "CORE_{VDD}") (pintype "passive"))
    (pad "F7" smd circle locked (at 1.481 0.506) (size 0.5 0.5) (layers "F.Cu" "F.Paste" "F.Mask")
      (net 45 "/~{CS}_TMS") (pinfunction "~{CS}_TMS") (pintype "input"))
    (pad "F8" smd circle locked (at 2.482 0.506) (size 0.5 0.5) (layers "F.Cu" "F.Paste" "F.Mask")
      (net 42 "/SCLK_TCK") (pinfunction "SCLK_TCK") (pintype "input"))
    (pad "F9" smd circle locked (at 3.482 0.506) (size 0.5 0.5) (layers "F.Cu" "F.Paste" "F.Mask")
      (net 38 "/D8") (pinfunction "DOUT08") (pintype "output"))
    (pad "F10" smd circle locked (at 4.482 0.506) (size 0.5 0.5) (layers "F.Cu" "F.Paste" "F.Mask")
      (net 39 "/D9") (pinfunction "DOUT09") (pintype "output"))
    (pad "G1" smd circle locked (at -4.518 1.507) (size 0.5 0.5) (layers "F.Cu" "F.Paste" "F.Mask")
      (net 12 "/AGCN") (pinfunction "AGC-") (pintype "passive"))
    (pad "G2" smd circle locked (at -3.519 1.507) (size 0.5 0.5) (layers "F.Cu" "F.Paste" "F.Mask")
      (net 3 "GNDA") (pinfunction "A_{GND}") (pintype "passive"))
    (pad "G3" smd circle locked (at -2.519 1.507) (size 0.5 0.5) (layers "F.Cu" "F.Paste" "F.Mask")
      (net 24 "/~{RC_BYP}") (pinfunction "~{RC_BYP}") (pintype "input"))
    (pad "G4" smd circle locked (at -1.518 1.507) (size 0.5 0.5) (layers "F.Cu" "F.Paste" "F.Mask")
      (net 1 "GNDREF") (pinfunction "CORE_{GND}") (pintype "passive"))
    (pad "G5" smd circle locked (at -0.519 1.507) (size 0.5 0.5) (layers "F.Cu" "F.Paste" "F.Mask")
      (net 1 "GNDREF") (pinfunction "CORE_{GND}") (pintype "passive"))
    (pad "G6" smd circle locked (at 0.481 1.507) (size 0.5 0.5) (layers "F.Cu" "F.Paste" "F.Mask")
      (net 2 "+1V2") (pinfunction "CORE_{VDD}") (pintype "passive"))
    (pad "G7" smd circle locked (at 1.481 1.507) (size 0.5 0.5) (layers "F.Cu" "F.Paste" "F.Mask")
      (net 17 "/~{SMPTE_BYPASS}") (pinfunction "~{SMPTE_BYPASS}") (pintype "bidirectional"))
    (pad "G8" smd circle locked (at 2.482 1.507) (size 0.5 0.5) (layers "F.Cu" "F.Paste" "F.Mask")
      (net 18 "/DVB_ASI") (pinfunction "DVB_ASI") (pintype "bidirectional"))
    (pad "G9" smd circle locked (at 3.482 1.507) (size 0.5 0.5) (layers "F.Cu" "F.Paste" "F.Mask")
      (net 1 "GNDREF") (pinfunction "IO_{GND}") (pintype "passive"))
    (pad "G10" smd circle locked (at 4.482 1.507) (size 0.5 0.5) (layers "F.Cu" "F.Paste" "F.Mask")
      (net 76 "IO_VDD") (pinfunction "IO_{VDD}") (pintype "passive"))
    (pad "H1" smd circle locked (at -4.518 2.507) (size 0.5 0.5) (layers "F.Cu" "F.Paste" "F.Mask")
      (net 5 "+3.3VA") (pinfunction "BUFF_{VDD}") (pintype "power_in"))
    (pad "H2" smd circle locked (at -3.519 2.507) (size 0.5 0.5) (layers "F.Cu" "F.Paste" "F.Mask")
      (net 3 "GNDA") (pinfunction "BUFF_{GND}") (pintype "power_in"))
    (pad "H3" smd circle locked (at -2.519 2.507) (size 0.5 0.5) (layers "F.Cu" "F.Paste" "F.Mask")
      (net 53 "/Audio_EN_~{DIS}") (pinfunction "AUDIO_EN/~{DIS}") (pintype "input"))
    (pad "H4" smd circle locked (at -1.518 2.507) (size 0.5 0.5) (layers "F.Cu" "F.Paste" "F.Mask")
      (net 66 "Net-(U2A-WCLK)") (pinfunction "WCLK") (pintype "output"))
    (pad "H5" smd circle locked (at -0.519 2.507) (size 0.5 0.5) (layers "F.Cu" "F.Paste" "F.Mask")
      (net 23 "/TIM_861") (pinfunction "TIM_861") (pintype "input"))
    (pad "H6" smd circle locked (at 0.481 2.507) (size 0.5 0.5) (layers "F.Cu" "F.Paste" "F.Mask")
      (net 130 "Net-(U2B-XTAL_OUT)") (pinfunction "XTAL_OUT") (pintype "output"))
    (pad "H7" smd circle locked (at 1.481 2.507) (size 0.5 0.5) (layers "F.Cu" "F.Paste" "F.Mask")
      (net 16 "/20bit_~{10bit}") (pinfunction "20BIT/~{10BIT}") (pintype "input"))
    (pad "H8" smd circle locked (at 2.482 2.507) (size 0.5 0.5) (layers "F.Cu" "F.Paste" "F.Mask")
      (net 41 "/IOPROC_EN_~{DIS}") (pinfunction "IOPROC_EN/~{DIS}") (pintype "input"))
    (pad "H9" smd circle locked (at 3.482 2.507) (size 0.5 0.5) (layers "F.Cu" "F.Paste" "F.Mask")
      (net 36 "/D6") (pinfunction "DOUT06") (pintype "output"))
    (pad "H10" smd circle locked (at 4.482 2.507) (size 0.5 0.5) (layers "F.Cu" "F.Paste" "F.Mask")
      (net 37 "/D7") (pinfunction "DOUT07") (pintype "output"))
    (pad "J1" smd circle locked (at -4.518 3.507) (size 0.5 0.5) (layers "F.Cu" "F.Paste" "F.Mask")
      (net 94 "/SDO_P") (pinfunction "SDO+") (pintype "output"))
    (pad "J2" smd circle locked (at -3.519 3.507) (size 0.5 0.5) (layers "F.Cu" "F.Paste" "F.Mask")
      (net 55 "/SDO_EN_DIS") (pinfunction "SDO_EN/DIS") (pintype "input"))
    (pad "J3" smd circle locked (at -2.519 3.507) (size 0.5 0.5) (layers "F.Cu" "F.Paste" "F.Mask")
      (net 52 "/AUDIO_OUTPUT_CH1_2") (pinfunction "AOUT_{1/2}") (pintype "output"))
    (pad "J4" smd circle locked (at -1.518 3.507) (size 0.5 0.5) (layers "F.Cu" "F.Paste" "F.Mask")
      (net 64 "Net-(U2A-ACLK)") (pinfunction "ACLK") (pintype "output"))
    (pad "J5" smd circle locked (at -0.519 3.507) (size 0.5 0.5) (layers "F.Cu" "F.Paste" "F.Mask")
      (net 50 "/AUDIO_OUTPUT_CH5_6") (pinfunction "AOUT_{5/6}") (pintype "output"))
    (pad "J6" smd circle locked (at 0.481 3.507) (size 0.5 0.5) (layers "F.Cu" "F.Paste" "F.Mask")
      (net 7 "/XTAL2") (pinfunction "XTAL2") (pintype "input"))
    (pad "J7" smd circle locked (at 1.481 3.507) (size 0.5 0.5) (layers "F.Cu" "F.Paste" "F.Mask")
      (net 1 "GNDREF") (pinfunction "IO_{GND}") (pintype "passive"))
    (pad "J8" smd circle locked (at 2.482 3.507) (size 0.5 0.5) (layers "F.Cu" "F.Paste" "F.Mask")
      (net 31 "/D1") (pinfunction "DOUT01") (pintype "output"))
    (pad "J9" smd circle locked (at 3.482 3.507) (size 0.5 0.5) (layers "F.Cu" "F.Paste" "F.Mask")
      (net 34 "/D4") (pinfunction "DOUT04") (pintype "output"))
    (pad "J10" smd circle locked (at 4.482 3.507) (size 0.5 0.5) (layers "F.Cu" "F.Paste" "F.Mask")
      (net 35 "/D5") (pinfunction "DOUT05") (pintype "output"))
    (pad "K1" smd circle locked (at -4.518 4.506) (size 0.5 0.5) (layers "F.Cu" "F.Paste" "F.Mask")
      (net 93 "/SDO_N") (pinfunction "SDO-") (pintype "output"))
    (pad "K2" smd circle locked (at -3.519 4.506) (size 0.5 0.5) (layers "F.Cu" "F.Paste" "F.Mask")
      (net 54 "/STANDBY") (pinfunction "STANDBY") (pintype "input"))
    (pad "K3" smd circle locked (at -2.519 4.506) (size 0.5 0.5) (layers "F.Cu" "F.Paste" "F.Mask")
      (net 51 "/AUDIO_OUTPUT_CH3_4") (pinfunction "AOUT_{3/4}") (pintype "output"))
    (pad "K4" smd circle locked (at -1.518 4.506) (size 0.5 0.5) (layers "F.Cu" "F.Paste" "F.Mask")
      (net 63 "Net-(U2A-AMCLK)") (pinfunction "AMCLK") (pintype "output"))
    (pad "K5" smd circle locked (at -0.519 4.506) (size 0.5 0.5) (layers "F.Cu" "F.Paste" "F.Mask")
      (net 49 "/AUDIO_OUTPUT_CH7_8") (pinfunction "AOUT_{7/8}") (pintype "output"))
    (pad "K6" smd circle locked (at 0.481 4.506) (size 0.5 0.5) (layers "F.Cu" "F.Paste" "F.Mask")
      (net 8 "/XTAL1") (pinfunction "XTAL1") (pintype "input"))
    (pad "K7" smd circle locked (at 1.481 4.506) (size 0.5 0.5) (layers "F.Cu" "F.Paste" "F.Mask")
      (net 76 "IO_VDD") (pinfunction "IO_{VDD}") (pintype "passive"))
    (pad "K8" smd circle locked (at 2.482 4.506) (size 0.5 0.5) (layers "F.Cu" "F.Paste" "F.Mask")
      (net 30 "/D0") (pinfunction "DOUT0") (pintype "output"))
    (pad "K9" smd circle locked (at 3.482 4.506) (size 0.5 0.5) (layers "F.Cu" "F.Paste" "F.Mask")
      (net 32 "/D2") (pinfunction "DOUT02") (pintype "output"))
    (pad "K10" smd circle locked (at 4.482 4.506) (size 0.5 0.5) (layers "F.Cu" "F.Paste" "F.Mask")
      (net 33 "/D3") (pinfunction "DOUT03") (pintype "output"))
  )

  (footprint "sdi-mipi-bridge-footprints:Testpoint_smd_1mm" (layer "F.Cu")
    (at 122.435 123.6742 180)
    (property "Author" "Antmicro")
    (property "License" "Apache-2.0")
    (property "MPN" "")
    (property "Manufacturer" "")
    (property "Sheetfile" "sdi-mipi-bridge.kicad_sch")
    (property "Sheetname" "")
    (property "ki_description" "Test Point 1mm")
    (attr smd)
    (fp_text reference "TP17" (at 0.635 -0.3258) (layer "F.SilkS")
        (effects (font (size 0.65 0.65) (thickness 0.15)) (justify right bottom))
    )
    (fp_text value "TP_1mm_SMD" (at 0 1.4) (layer "F.Fab") hide
        (effects (font (size 0.7 0.7) (thickness 0.15)) (justify right bottom))
    )
    (fp_text user "${REFERENCE}" (at -0.5 2.8) (layer "F.Fab") hide
        (effects (font (size 0.7 0.7) (thickness 0.15)) (justify right bottom))
    )
    (fp_text user "License: Apache-2.0" (at -0.5 5.2) (layer "F.Fab") hide
        (effects (font (size 0.7 0.7) (thickness 0.15)) (justify right bottom))
    )
    (fp_text user "Author: Antmicro" (at -0.5 4) (layer "F.Fab") hide
        (effects (font (size 0.7 0.7) (thickness 0.15)) (justify right bottom))
    )
    (pad "1" smd circle (at 0 0 180) (size 1 1) (layers "F.Cu" "F.Mask")
      (net 130 "Net-(U2B-XTAL_OUT)") (pinfunction "1") (pintype "passive"))
  )

  (footprint "sdi-mipi-bridge-footprints:Testpoint_smd_1mm" (layer "F.Cu")
    (at 122.5 107.3492 180)
    (property "Author" "Antmicro")
    (property "License" "Apache-2.0")
    (property "MPN" "")
    (property "Manufacturer" "")
    (property "Sheetfile" "sdi-mipi-bridge.kicad_sch")
    (property "Sheetname" "")
    (property "ki_description" "Test Point 1mm")
    (attr smd)
    (fp_text reference "TP2" (at -1.1 -0.3508 180) (layer "F.SilkS")
        (effects (font (size 0.65 0.65) (thickness 0.15)) (justify left bottom))
    )
    (fp_text value "TP_1mm_SMD" (at 0 1.4 180) (layer "F.Fab") hide
        (effects (font (size 0.7 0.7) (thickness 0.15)) (justify left bottom))
    )
    (fp_text user "${REFERENCE}" (at -0.5 2.8 180) (layer "F.Fab") hide
        (effects (font (size 0.7 0.7) (thickness 0.15)) (justify left bottom))
    )
    (fp_text user "Author: Antmicro" (at -0.5 4 180) (layer "F.Fab") hide
        (effects (font (size 0.7 0.7) (thickness 0.15)) (justify left bottom))
    )
    (fp_text user "License: Apache-2.0" (at -0.5 5.2 180) (layer "F.Fab") hide
        (effects (font (size 0.7 0.7) (thickness 0.15)) (justify left bottom))
    )
    (pad "1" smd circle (at 0 0 180) (size 1 1) (layers "F.Cu" "F.Mask")
      (net 15 "/V_VSYNC") (pinfunction "1") (pintype "passive"))
  )

  (footprint "sdi-mipi-bridge-footprints:C_0402_1005Metric" (layer "F.Cu")
    (at 116.5 106.4 90)
    (descr "Capacitor SMD 0402")
    (tags "capacitor SMD 0402")
    (property "Author" "Antmicro")
    (property "Dielectric" "")
    (property "License" "Apache-2.0")
    (property "MPN" "C1005X6S1A105K050BC")
    (property "Manufacturer" "TDK")
    (property "Sheetfile" "sdi-mipi-bridge.kicad_sch")
    (property "Sheetname" "")
    (property "Val" "1u")
    (property "Voltage" "")
    (property "ki_description" " ")
    (attr smd)
    (fp_text reference "C62" (at -2.9 0.4 90) (layer "F.SilkS")
        (effects (font (size 0.65 0.65) (thickness 0.15)) (justify left bottom))
    )
    (fp_text value "C_1u_0402" (at 0 1.4 90) (layer "F.Fab") hide
        (effects (font (size 0.7 0.7) (thickness 0.15)) (justify left bottom))
    )
    (fp_text user "License: Apache-2.0" (at -0.932 5.17 90) (layer "F.Fab") hide
        (effects (font (size 0.7 0.7) (thickness 0.15)) (justify left bottom))
    )
    (fp_text user "Author: Antmicro" (at -0.932 4.17 90) (layer "F.Fab") hide
        (effects (font (size 0.7 0.7) (thickness 0.15)) (justify left bottom))
    )
    (fp_text user "${REFERENCE}" (at -0.932 3.168 90) (layer "F.Fab") hide
        (effects (font (size 0.7 0.7) (thickness 0.15)) (justify left bottom))
    )
    (fp_rect (start -0.94 -0.47) (end 0.94 0.47)
      (stroke (width 0.05) (type solid)) (fill none) (layer "F.CrtYd"))
    (fp_rect (start -0.499 -0.249) (end 0.499 0.249)
      (stroke (width 0.15) (type solid)) (fill none) (layer "F.Fab"))
    (pad "1" smd roundrect (at -0.484 0 90) (size 0.59 0.64) (layers "F.Cu" "F.Paste" "F.Mask") (roundrect_rratio 0.25)
      (net 11 "/VBG") (pintype "passive"))
    (pad "2" smd roundrect (at 0.484 0 90) (size 0.59 0.64) (layers "F.Cu" "F.Paste" "F.Mask") (roundrect_rratio 0.25)
      (net 3 "GNDA") (pintype "passive"))
  )

  (footprint "sdi-mipi-bridge-footprints:R_0402_1005Metric" (layer "F.Cu")
    (at 119.5 106.4 -90)
    (descr "Resistor SMD 0402")
    (tags "resistor SMD 0402")
    (property "Author" "Antmicro")
    (property "Current" "1A")
    (property "DNP" "DNP")
    (property "License" "Apache-2.0")
    (property "MPN" "ERJ2GE0R00X")
    (property "Manufacturer" "Panasonic")
    (property "Sheetfile" "sdi-mipi-bridge.kicad_sch")
    (property "Sheetname" "")
    (property "Tolerance" "")
    (property "Val" "0R")
    (property "ki_description" "0R resistor in 0402 package with unspecified tolerance")
    (attr exclude_from_pos_files)
    (fp_text reference "R32" (at 2.9 -0.4 -90) (layer "F.SilkS")
        (effects (font (size 0.65 0.65) (thickness 0.15)) (justify left bottom))
    )
    (fp_text value "R_0R_0402" (at 0 1.4 -90) (layer "F.Fab") hide
        (effects (font (size 0.7 0.7) (thickness 0.15)) (justify left bottom))
    )
    (fp_text user "${REFERENCE}" (at -0.95 3.168 -90) (layer "F.Fab") hide
        (effects (font (size 0.7 0.7) (thickness 0.15)) (justify left bottom))
    )
    (fp_text user "License: Apache-2.0" (at -0.95 5.169 -90) (layer "F.Fab") hide
        (effects (font (size 0.7 0.7) (thickness 0.15)) (justify left bottom))
    )
    (fp_text user "Author: Antmicro" (at -0.95 4.169 -90) (layer "F.Fab") hide
        (effects (font (size 0.7 0.7) (thickness 0.15)) (justify left bottom))
    )
    (fp_rect (start -0.93 -0.47) (end 0.93 0.47)
      (stroke (width 0.05) (type solid)) (fill none) (layer "F.CrtYd"))
    (fp_rect (start -0.5 -0.25) (end 0.5 0.25)
      (stroke (width 0.15) (type solid)) (fill none) (layer "F.Fab"))
    (pad "1" smd roundrect (at -0.485 0 270) (size 0.59 0.64) (layers "F.Cu" "F.Paste" "F.Mask") (roundrect_rratio 0.25)
      (net 3 "GNDA") (pintype "passive"))
    (pad "2" smd roundrect (at 0.485 0 270) (size 0.59 0.64) (layers "F.Cu" "F.Paste" "F.Mask") (roundrect_rratio 0.25)
      (net 40 "/LB_CONT") (pintype "passive"))
  )

  (footprint "sdi-mipi-bridge-footprints:R_0402_1005Metric" (layer "F.Cu")
    (at 118.5 106.4 -90)
    (descr "Resistor SMD 0402")
    (tags "resistor SMD 0402")
    (property "Author" "Antmicro")
    (property "Current" "1A")
    (property "DNP" "DNP")
    (property "License" "Apache-2.0")
    (property "MPN" "ERJ2GE0R00X")
    (property "Manufacturer" "Panasonic")
    (property "Sheetfile" "sdi-mipi-bridge.kicad_sch")
    (property "Sheetname" "")
    (property "Tolerance" "")
    (property "Val" "0R")
    (property "ki_description" "0R resistor in 0402 package with unspecified tolerance")
    (attr exclude_from_pos_files)
    (fp_text reference "R34" (at 2.9 -0.4 -90) (layer "F.SilkS")
        (effects (font (size 0.65 0.65) (thickness 0.15)) (justify left bottom))
    )
    (fp_text value "R_0R_0402" (at 0 1.4 -90) (layer "F.Fab") hide
        (effects (font (size 0.7 0.7) (thickness 0.15)) (justify left bottom))
    )
    (fp_text user "${REFERENCE}" (at -0.95 3.168 -90) (layer "F.Fab") hide
        (effects (font (size 0.7 0.7) (thickness 0.15)) (justify left bottom))
    )
    (fp_text user "License: Apache-2.0" (at -0.95 5.169 -90) (layer "F.Fab") hide
        (effects (font (size 0.7 0.7) (thickness 0.15)) (justify left bottom))
    )
    (fp_text user "Author: Antmicro" (at -0.95 4.169 -90) (layer "F.Fab") hide
        (effects (font (size 0.7 0.7) (thickness 0.15)) (justify left bottom))
    )
    (fp_rect (start -0.93 -0.47) (end 0.93 0.47)
      (stroke (width 0.05) (type solid)) (fill none) (layer "F.CrtYd"))
    (fp_rect (start -0.5 -0.25) (end 0.5 0.25)
      (stroke (width 0.15) (type solid)) (fill none) (layer "F.Fab"))
    (pad "1" smd roundrect (at -0.485 0 270) (size 0.59 0.64) (layers "F.Cu" "F.Paste" "F.Mask") (roundrect_rratio 0.25)
      (net 5 "+3.3VA") (pintype "passive"))
    (pad "2" smd roundrect (at 0.485 0 270) (size 0.59 0.64) (layers "F.Cu" "F.Paste" "F.Mask") (roundrect_rratio 0.25)
      (net 40 "/LB_CONT") (pintype "passive"))
  )

  (footprint "sdi-mipi-bridge-footprints:Testpoint_smd_1mm" (layer "F.Cu")
    (at 122.5 105.8492 180)
    (property "Author" "Antmicro")
    (property "License" "Apache-2.0")
    (property "MPN" "")
    (property "Manufacturer" "")
    (property "Sheetfile" "sdi-mipi-bridge.kicad_sch")
    (property "Sheetname" "")
    (property "ki_description" "Test Point 1mm")
    (attr smd)
    (fp_text reference "TP1" (at -1.1 -0.3508 180) (layer "F.SilkS")
        (effects (font (size 0.65 0.65) (thickness 0.15)) (justify left bottom))
    )
    (fp_text value "TP_1mm_SMD" (at 0 1.4 180) (layer "F.Fab") hide
        (effects (font (size 0.7 0.7) (thickness 0.15)) (justify left bottom))
    )
    (fp_text user "Author: Antmicro" (at -0.5 4 180) (layer "F.Fab") hide
        (effects (font (size 0.7 0.7) (thickness 0.15)) (justify left bottom))
    )
    (fp_text user "License: Apache-2.0" (at -0.5 5.2 180) (layer "F.Fab") hide
        (effects (font (size 0.7 0.7) (thickness 0.15)) (justify left bottom))
    )
    (fp_text user "${REFERENCE}" (at -0.5 2.8 180) (layer "F.Fab") hide
        (effects (font (size 0.7 0.7) (thickness 0.15)) (justify left bottom))
    )
    (pad "1" smd circle (at 0 0 180) (size 1 1) (layers "F.Cu" "F.Mask")
      (net 14 "/H_HSYNC") (pinfunction "1") (pintype "passive"))
  )

  (footprint "sdi-mipi-bridge-footprints:antmicro-logo_scaled_20mm" (layer "F.Cu")
    (at 144.18 99.67)
    (property "Author" "Antmicro")
    (property "License" "Apache-2.0")
    (property "MPN" "")
    (property "Manufacturer" "")
    (property "Sheetfile" "sdi-mipi-bridge.kicad_sch")
    (property "Sheetname" "")
    (fp_text reference "N1" (at 0.05 -5.5) (layer "F.SilkS") hide
        (effects (font (size 0.65 0.65) (thickness 0.15)) (justify left bottom))
    )
    (fp_text value "antmicro_logo" (at -0.101 5.099) (layer "F.SilkS") hide
        (effects (font (size 0.7 0.7) (thickness 0.15)) (justify left bottom))
    )
    (fp_text user "License: Apache-2.0" (at -9.998 9.499) (layer "F.Fab") hide
        (effects (font (size 0.7 0.7) (thickness 0.15)) (justify left bottom))
    )
    (fp_text user "${REFERENCE}" (at -9.998 7.099) (layer "F.Fab") hide
        (effects (font (size 0.7 0.7) (thickness 0.15)) (justify left bottom))
    )
    (fp_text user "Author: Antmicro" (at -9.998 8.299) (layer "F.Fab") hide
        (effects (font (size 0.7 0.7) (thickness 0.15)) (justify left bottom))
    )
    (fp_poly
      (pts
        (xy 5.212 0.944)
        (xy 4.834 0.944)
        (xy 4.834 -1.292)
        (xy 5.212 -1.292)
        (xy 5.212 0.944)
      )

      (stroke (width 0.00186) (type solid)) (fill solid) (layer "F.Cu"))
    (fp_poly
      (pts
        (xy 8.164 -1.321)
        (xy 8.193 -1.317)
        (xy 8.204 -1.31)
        (xy 8.204 -1.308)
        (xy 8.2 -1.285)
        (xy 8.188 -1.24)
        (xy 8.171 -1.181)
        (xy 8.163 -1.156)
        (xy 8.142 -1.092)
        (xy 8.126 -1.053)
        (xy 8.112 -1.034)
        (xy 8.097 -1.031)
        (xy 8.094 -1.032)
        (xy 7.996 -1.053)
        (xy 7.886 -1.06)
        (xy 7.778 -1.053)
        (xy 7.683 -1.032)
        (xy 7.665 -1.026)
        (xy 7.622 -1.009)
        (xy 7.622 0.944)
        (xy 7.244 0.944)
        (xy 7.244 -1.178)
        (xy 7.358 -1.219)
        (xy 7.457 -1.253)
        (xy 7.548 -1.277)
        (xy 7.639 -1.295)
        (xy 7.738 -1.307)
        (xy 7.856 -1.315)
        (xy 7.94 -1.319)
        (xy 8.042 -1.322)
        (xy 8.115 -1.322)
        (xy 8.164 -1.321)
      )

      (stroke (width 0.00186) (type solid)) (fill solid) (layer "F.Cu"))
    (fp_poly
      (pts
        (xy 0.795 -1.891)
        (xy 0.798 -1.849)
        (xy 0.8 -1.786)
        (xy 0.802 -1.705)
        (xy 0.803 -1.612)
        (xy 0.803 -1.599)
        (xy 0.803 -1.292)
        (xy 1.181 -1.292)
        (xy 1.181 -1.04)
        (xy 0.803 -1.04)
        (xy 0.803 0.498)
        (xy 0.838 0.566)
        (xy 0.885 0.631)
        (xy 0.944 0.671)
        (xy 1.021 0.688)
        (xy 1.082 0.689)
        (xy 1.181 0.685)
        (xy 1.181 0.806)
        (xy 1.178 0.88)
        (xy 1.17 0.926)
        (xy 1.161 0.939)
        (xy 1.138 0.945)
        (xy 1.09 0.95)
        (xy 1.028 0.954)
        (xy 0.984 0.956)
        (xy 0.897 0.957)
        (xy 0.832 0.953)
        (xy 0.778 0.942)
        (xy 0.743 0.931)
        (xy 0.647 0.886)
        (xy 0.571 0.823)
        (xy 0.508 0.737)
        (xy 0.488 0.701)
        (xy 0.433 0.593)
        (xy 0.428 -0.223)
        (xy 0.424 -1.04)
        (xy 0.173 -1.04)
        (xy 0.173 -1.292)
        (xy 0.425 -1.292)
        (xy 0.425 -1.795)
        (xy 0.603 -1.85)
        (xy 0.673 -1.872)
        (xy 0.733 -1.89)
        (xy 0.774 -1.902)
        (xy 0.792 -1.906)
        (xy 0.795 -1.891)
      )

      (stroke (width 0.00186) (type solid)) (fill solid) (layer "F.Cu"))
    (fp_poly
      (pts
        (xy -0.82 -1.315)
        (xy -0.737 -1.312)
        (xy -0.672 -1.308)
        (xy -0.621 -1.301)
        (xy -0.577 -1.291)
        (xy -0.56 -1.286)
        (xy -0.417 -1.232)
        (xy -0.302 -1.164)
        (xy -0.212 -1.082)
        (xy -0.154 -0.996)
        (xy -0.135 -0.961)
        (xy -0.119 -0.927)
        (xy -0.105 -0.893)
        (xy -0.094 -0.855)
        (xy -0.085 -0.811)
        (xy -0.078 -0.758)
        (xy -0.073 -0.693)
        (xy -0.069 -0.612)
        (xy -0.067 -0.515)
        (xy -0.065 -0.397)
        (xy -0.064 -0.256)
        (xy -0.064 -0.088)
        (xy -0.063 0.105)
        (xy -0.063 0.944)
        (xy -0.441 0.944)
        (xy -0.441 0.113)
        (xy -0.442 -0.083)
        (xy -0.442 -0.25)
        (xy -0.443 -0.391)
        (xy -0.445 -0.508)
        (xy -0.448 -0.604)
        (xy -0.452 -0.682)
        (xy -0.457 -0.744)
        (xy -0.465 -0.794)
        (xy -0.474 -0.833)
        (xy -0.486 -0.864)
        (xy -0.501 -0.89)
        (xy -0.518 -0.913)
        (xy -0.538 -0.937)
        (xy -0.539 -0.939)
        (xy -0.604 -0.997)
        (xy -0.684 -1.039)
        (xy -0.784 -1.066)
        (xy -0.822 -1.072)
        (xy -0.927 -1.078)
        (xy -1.044 -1.073)
        (xy -1.158 -1.056)
        (xy -1.24 -1.034)
        (xy -1.3 -1.013)
        (xy -1.304 -0.034)
        (xy -1.308 0.944)
        (xy -1.686 0.944)
        (xy -1.686 -1.178)
        (xy -1.54 -1.225)
        (xy -1.44 -1.257)
        (xy -1.354 -1.28)
        (xy -1.276 -1.297)
        (xy -1.195 -1.307)
        (xy -1.105 -1.313)
        (xy -0.995 -1.315)
        (xy -0.93 -1.315)
        (xy -0.82 -1.315)
      )

      (stroke (width 0.00186) (type solid)) (fill solid) (layer "F.Cu"))
    (fp_poly
      (pts
        (xy 3.757 -1.312)
        (xy 3.91 -1.278)
        (xy 4.043 -1.223)
        (xy 4.153 -1.146)
        (xy 4.24 -1.047)
        (xy 4.282 -0.977)
        (xy 4.299 -0.943)
        (xy 4.313 -0.91)
        (xy 4.325 -0.876)
        (xy 4.335 -0.837)
        (xy 4.343 -0.791)
        (xy 4.349 -0.734)
        (xy 4.353 -0.665)
        (xy 4.357 -0.581)
        (xy 4.359 -0.478)
        (xy 4.361 -0.354)
        (xy 4.361 -0.206)
        (xy 4.362 -0.031)
        (xy 4.362 0.111)
        (xy 4.362 0.944)
        (xy 3.985 0.944)
        (xy 3.98 0.074)
        (xy 3.976 -0.796)
        (xy 3.93 -0.879)
        (xy 3.867 -0.961)
        (xy 3.786 -1.022)
        (xy 3.691 -1.062)
        (xy 3.586 -1.079)
        (xy 3.476 -1.074)
        (xy 3.366 -1.045)
        (xy 3.26 -0.994)
        (xy 3.185 -0.938)
        (xy 3.118 -0.88)
        (xy 3.118 0.944)
        (xy 2.74 0.944)
        (xy 2.74 0.092)
        (xy 2.739 -0.122)
        (xy 2.739 -0.305)
        (xy 2.737 -0.459)
        (xy 2.735 -0.585)
        (xy 2.732 -0.683)
        (xy 2.729 -0.755)
        (xy 2.725 -0.802)
        (xy 2.722 -0.821)
        (xy 2.679 -0.91)
        (xy 2.613 -0.981)
        (xy 2.523 -1.034)
        (xy 2.413 -1.067)
        (xy 2.284 -1.079)
        (xy 2.154 -1.073)
        (xy 2.082 -1.064)
        (xy 2.031 -1.056)
        (xy 1.989 -1.046)
        (xy 1.944 -1.031)
        (xy 1.917 -1.021)
        (xy 1.874 -1.005)
        (xy 1.874 0.944)
        (xy 1.511 0.944)
        (xy 1.511 -1.18)
        (xy 1.661 -1.228)
        (xy 1.83 -1.276)
        (xy 1.988 -1.306)
        (xy 2.148 -1.319)
        (xy 2.314 -1.319)
        (xy 2.448 -1.311)
        (xy 2.557 -1.297)
        (xy 2.649 -1.272)
        (xy 2.732 -1.237)
        (xy 2.811 -1.189)
        (xy 2.843 -1.165)
        (xy 2.947 -1.087)
        (xy 3.012 -1.14)
        (xy 3.14 -1.224)
        (xy 3.283 -1.283)
        (xy 3.443 -1.315)
        (xy 3.582 -1.323)
        (xy 3.757 -1.312)
      )

      (stroke (width 0.00186) (type solid)) (fill solid) (layer "F.Cu"))
    (fp_poly
      (pts
        (xy 9.278 -1.313)
        (xy 9.419 -1.281)
        (xy 9.543 -1.225)
        (xy 9.656 -1.146)
        (xy 9.708 -1.097)
        (xy 9.808 -0.975)
        (xy 9.887 -0.831)
        (xy 9.945 -0.666)
        (xy 9.984 -0.476)
        (xy 9.998 -0.354)
        (xy 10.005 -0.134)
        (xy 9.992 0.072)
        (xy 9.96 0.262)
        (xy 9.908 0.434)
        (xy 9.837 0.585)
        (xy 9.749 0.714)
        (xy 9.643 0.819)
        (xy 9.578 0.867)
        (xy 9.475 0.918)
        (xy 9.352 0.956)
        (xy 9.219 0.98)
        (xy 9.087 0.986)
        (xy 8.966 0.975)
        (xy 8.81 0.933)
        (xy 8.673 0.864)
        (xy 8.553 0.771)
        (xy 8.452 0.653)
        (xy 8.371 0.511)
        (xy 8.31 0.346)
        (xy 8.277 0.202)
        (xy 8.249 -0.011)
        (xy 8.243 -0.182)
        (xy 8.619 -0.182)
        (xy 8.626 -0.007)
        (xy 8.647 0.163)
        (xy 8.682 0.318)
        (xy 8.73 0.449)
        (xy 8.792 0.552)
        (xy 8.87 0.633)
        (xy 8.961 0.69)
        (xy 9.06 0.721)
        (xy 9.164 0.724)
        (xy 9.268 0.699)
        (xy 9.303 0.683)
        (xy 9.391 0.625)
        (xy 9.465 0.546)
        (xy 9.524 0.443)
        (xy 9.569 0.315)
        (xy 9.601 0.162)
        (xy 9.62 0)
        (xy 9.628 -0.198)
        (xy 9.62 -0.382)
        (xy 9.597 -0.55)
        (xy 9.558 -0.698)
        (xy 9.505 -0.825)
        (xy 9.439 -0.927)
        (xy 9.397 -0.971)
        (xy 9.307 -1.035)
        (xy 9.21 -1.071)
        (xy 9.109 -1.079)
        (xy 9.009 -1.062)
        (xy 8.915 -1.019)
        (xy 8.831 -0.953)
        (xy 8.76 -0.863)
        (xy 8.733 -0.813)
        (xy 8.684 -0.68)
        (xy 8.648 -0.526)
        (xy 8.627 -0.358)
        (xy 8.619 -0.182)
        (xy 8.243 -0.182)
        (xy 8.242 -0.218)
        (xy 8.255 -0.417)
        (xy 8.288 -0.602)
        (xy 8.339 -0.772)
        (xy 8.41 -0.923)
        (xy 8.498 -1.051)
        (xy 8.524 -1.081)
        (xy 8.637 -1.182)
        (xy 8.765 -1.255)
        (xy 8.908 -1.302)
        (xy 9.068 -1.322)
        (xy 9.117 -1.323)
        (xy 9.278 -1.313)
      )

      (stroke (width 0.00186) (type solid)) (fill solid) (layer "F.Cu"))
    (fp_poly
      (pts
        (xy 6.48 -1.32)
        (xy 6.584 -1.31)
        (xy 6.642 -1.3)
        (xy 6.701 -1.282)
        (xy 6.765 -1.259)
        (xy 6.825 -1.233)
        (xy 6.873 -1.209)
        (xy 6.9 -1.189)
        (xy 6.902 -1.186)
        (xy 6.901 -1.166)
        (xy 6.889 -1.128)
        (xy 6.872 -1.079)
        (xy 6.852 -1.03)
        (xy 6.833 -0.989)
        (xy 6.818 -0.966)
        (xy 6.815 -0.963)
        (xy 6.795 -0.969)
        (xy 6.757 -0.985)
        (xy 6.717 -1.002)
        (xy 6.597 -1.044)
        (xy 6.478 -1.06)
        (xy 6.365 -1.05)
        (xy 6.267 -1.016)
        (xy 6.184 -0.957)
        (xy 6.109 -0.87)
        (xy 6.042 -0.76)
        (xy 5.988 -0.629)
        (xy 5.964 -0.554)
        (xy 5.946 -0.461)
        (xy 5.934 -0.347)
        (xy 5.929 -0.22)
        (xy 5.931 -0.091)
        (xy 5.938 0.032)
        (xy 5.953 0.138)
        (xy 5.965 0.191)
        (xy 6.018 0.347)
        (xy 6.085 0.476)
        (xy 6.166 0.576)
        (xy 6.262 0.649)
        (xy 6.269 0.653)
        (xy 6.318 0.678)
        (xy 6.36 0.692)
        (xy 6.409 0.698)
        (xy 6.476 0.7)
        (xy 6.48 0.7)
        (xy 6.551 0.697)
        (xy 6.613 0.686)
        (xy 6.676 0.665)
        (xy 6.75 0.631)
        (xy 6.805 0.602)
        (xy 6.811 0.606)
        (xy 6.823 0.627)
        (xy 6.842 0.667)
        (xy 6.868 0.73)
        (xy 6.904 0.819)
        (xy 6.907 0.827)
        (xy 6.898 0.844)
        (xy 6.866 0.868)
        (xy 6.818 0.895)
        (xy 6.759 0.922)
        (xy 6.697 0.945)
        (xy 6.68 0.95)
        (xy 6.596 0.968)
        (xy 6.494 0.98)
        (xy 6.388 0.984)
        (xy 6.292 0.98)
        (xy 6.251 0.975)
        (xy 6.192 0.96)
        (xy 6.121 0.935)
        (xy 6.055 0.906)
        (xy 5.924 0.825)
        (xy 5.811 0.718)
        (xy 5.717 0.586)
        (xy 5.641 0.431)
        (xy 5.585 0.252)
        (xy 5.566 0.164)
        (xy 5.552 0.061)
        (xy 5.545 -0.061)
        (xy 5.544 -0.193)
        (xy 5.549 -0.327)
        (xy 5.56 -0.453)
        (xy 5.576 -0.563)
        (xy 5.589 -0.623)
        (xy 5.65 -0.797)
        (xy 5.731 -0.949)
        (xy 5.831 -1.077)
        (xy 5.948 -1.181)
        (xy 6.081 -1.259)
        (xy 6.187 -1.298)
        (xy 6.27 -1.314)
        (xy 6.372 -1.322)
        (xy 6.48 -1.32)
      )

      (stroke (width 0.00186) (type solid)) (fill solid) (layer "F.Cu"))
    (fp_poly
      (pts
        (xy -2.763 -1.313)
        (xy -2.663 -1.294)
        (xy -2.55 -1.259)
        (xy -2.459 -1.216)
        (xy -2.38 -1.16)
        (xy -2.341 -1.124)
        (xy -2.284 -1.053)
        (xy -2.232 -0.961)
        (xy -2.192 -0.861)
        (xy -2.174 -0.79)
        (xy -2.17 -0.754)
        (xy -2.167 -0.69)
        (xy -2.164 -0.599)
        (xy -2.162 -0.485)
        (xy -2.16 -0.35)
        (xy -2.159 -0.196)
        (xy -2.158 -0.027)
        (xy -2.158 0.064)
        (xy -2.158 0.833)
        (xy -2.232 0.865)
        (xy -2.364 0.913)
        (xy -2.517 0.949)
        (xy -2.682 0.974)
        (xy -2.85 0.986)
        (xy -3.011 0.983)
        (xy -3.097 0.975)
        (xy -3.264 0.942)
        (xy -3.407 0.889)
        (xy -3.525 0.817)
        (xy -3.618 0.725)
        (xy -3.686 0.616)
        (xy -3.729 0.487)
        (xy -3.746 0.341)
        (xy -3.746 0.268)
        (xy -3.744 0.254)
        (xy -3.383 0.254)
        (xy -3.38 0.384)
        (xy -3.352 0.497)
        (xy -3.298 0.591)
        (xy -3.221 0.665)
        (xy -3.12 0.719)
        (xy -3.072 0.735)
        (xy -3.011 0.745)
        (xy -2.928 0.75)
        (xy -2.835 0.75)
        (xy -2.74 0.744)
        (xy -2.655 0.734)
        (xy -2.589 0.72)
        (xy -2.579 0.716)
        (xy -2.504 0.689)
        (xy -2.504 -0.302)
        (xy -2.595 -0.291)
        (xy -2.653 -0.282)
        (xy -2.728 -0.267)
        (xy -2.806 -0.25)
        (xy -2.831 -0.244)
        (xy -2.992 -0.194)
        (xy -3.125 -0.133)
        (xy -3.229 -0.06)
        (xy -3.306 0.026)
        (xy -3.357 0.125)
        (xy -3.381 0.238)
        (xy -3.383 0.254)
        (xy -3.744 0.254)
        (xy -3.725 0.126)
        (xy -3.678 0)
        (xy -3.602 -0.112)
        (xy -3.559 -0.158)
        (xy -3.465 -0.233)
        (xy -3.343 -0.303)
        (xy -3.198 -0.365)
        (xy -3.034 -0.417)
        (xy -2.856 -0.46)
        (xy -2.666 -0.49)
        (xy -2.663 -0.49)
        (xy -2.5 -0.51)
        (xy -2.51 -0.644)
        (xy -2.528 -0.77)
        (xy -2.564 -0.871)
        (xy -2.62 -0.949)
        (xy -2.697 -1.007)
        (xy -2.797 -1.045)
        (xy -2.845 -1.056)
        (xy -2.975 -1.067)
        (xy -3.12 -1.056)
        (xy -3.272 -1.024)
        (xy -3.426 -0.972)
        (xy -3.439 -0.967)
        (xy -3.488 -0.947)
        (xy -3.523 -0.936)
        (xy -3.537 -0.934)
        (xy -3.545 -0.95)
        (xy -3.56 -0.987)
        (xy -3.579 -1.035)
        (xy -3.598 -1.086)
        (xy -3.613 -1.129)
        (xy -3.622 -1.155)
        (xy -3.623 -1.159)
        (xy -3.609 -1.169)
        (xy -3.575 -1.188)
        (xy -3.537 -1.206)
        (xy -3.395 -1.257)
        (xy -3.239 -1.294)
        (xy -3.075 -1.316)
        (xy -2.914 -1.323)
        (xy -2.763 -1.313)
      )

      (stroke (width 0.00186) (type solid)) (fill solid) (layer "F.Cu"))
    (fp_poly
      (pts
        (xy -7.153 -3.366)
        (xy -7.087 -3.351)
        (xy -7.086 -3.351)
        (xy -7.066 -3.34)
        (xy -7.021 -3.315)
        (xy -6.953 -3.277)
        (xy -6.865 -3.227)
        (xy -6.759 -3.167)
        (xy -6.639 -3.099)
        (xy -6.505 -3.022)
        (xy -6.361 -2.94)
        (xy -6.209 -2.853)
        (xy -6.052 -2.762)
        (xy -5.891 -2.67)
        (xy -5.729 -2.577)
        (xy -5.569 -2.485)
        (xy -5.413 -2.395)
        (xy -5.264 -2.309)
        (xy -5.123 -2.227)
        (xy -4.994 -2.152)
        (xy -4.878 -2.085)
        (xy -4.778 -2.027)
        (xy -4.697 -1.979)
        (xy -4.636 -1.943)
        (xy -4.599 -1.921)
        (xy -4.595 -1.918)
        (xy -4.528 -1.863)
        (xy -4.476 -1.798)
        (xy -4.434 -1.725)
        (xy -4.429 -0.224)
        (xy -4.429 0.063)
        (xy -4.428 0.323)
        (xy -4.429 0.553)
        (xy -4.429 0.755)
        (xy -4.43 0.928)
        (xy -4.432 1.071)
        (xy -4.434 1.184)
        (xy -4.436 1.266)
        (xy -4.439 1.318)
        (xy -4.441 1.337)
        (xy -4.448 1.36)
        (xy -4.454 1.382)
        (xy -4.463 1.403)
        (xy -4.476 1.423)
        (xy -4.494 1.445)
        (xy -4.519 1.47)
        (xy -4.552 1.497)
        (xy -4.596 1.529)
        (xy -4.652 1.567)
        (xy -4.721 1.611)
        (xy -4.805 1.663)
        (xy -4.906 1.723)
        (xy -5.025 1.794)
        (xy -5.165 1.875)
        (xy -5.326 1.969)
        (xy -5.511 2.076)
        (xy -5.72 2.197)
        (xy -5.813 2.251)
        (xy -7.079 2.982)
        (xy -7.197 2.988)
        (xy -7.315 2.994)
        (xy -7.78 2.727)
        (xy -8.064 2.563)
        (xy -8.323 2.415)
        (xy -8.557 2.28)
        (xy -8.767 2.159)
        (xy -8.955 2.051)
        (xy -9.122 1.954)
        (xy -9.27 1.868)
        (xy -9.399 1.792)
        (xy -9.51 1.726)
        (xy -9.606 1.669)
        (xy -9.688 1.619)
        (xy -9.756 1.576)
        (xy -9.812 1.539)
        (xy -9.857 1.507)
        (xy -9.893 1.481)
        (xy -9.92 1.458)
        (xy -9.94 1.437)
        (xy -9.955 1.42)
        (xy -9.965 1.403)
        (xy -9.972 1.387)
        (xy -9.977 1.371)
        (xy -9.981 1.354)
        (xy -9.985 1.337)
        (xy -9.988 1.309)
        (xy -9.991 1.25)
        (xy -9.993 1.161)
        (xy -9.995 1.041)
        (xy -9.996 0.891)
        (xy -9.997 0.712)
        (xy -9.998 0.503)
        (xy -9.998 0.266)
        (xy -9.997 0)
        (xy -9.997 -0.189)
        (xy -9.024 -0.189)
        (xy -9.024 0.015)
        (xy -9.024 0.191)
        (xy -9.023 0.34)
        (xy -9.022 0.464)
        (xy -9.021 0.567)
        (xy -9.018 0.65)
        (xy -9.014 0.717)
        (xy -9.01 0.768)
        (xy -9.003 0.808)
        (xy -8.995 0.837)
        (xy -8.986 0.859)
        (xy -8.974 0.876)
        (xy -8.961 0.891)
        (xy -8.945 0.905)
        (xy -8.943 0.906)
        (xy -8.922 0.921)
        (xy -8.877 0.949)
        (xy -8.81 0.989)
        (xy -8.725 1.039)
        (xy -8.625 1.098)
        (xy -8.512 1.164)
        (xy -8.389 1.235)
        (xy -8.26 1.31)
        (xy -8.128 1.386)
        (xy -7.995 1.463)
        (xy -7.864 1.538)
        (xy -7.739 1.609)
        (xy -7.622 1.676)
        (xy -7.517 1.735)
        (xy -7.425 1.787)
        (xy -7.351 1.828)
        (xy -7.297 1.857)
        (xy -7.266 1.872)
        (xy -7.261 1.874)
        (xy -7.222 1.885)
        (xy -7.195 1.886)
        (xy -7.163 1.875)
        (xy -7.144 1.867)
        (xy -7.117 1.854)
        (xy -7.067 1.827)
        (xy -6.997 1.788)
        (xy -6.909 1.738)
        (xy -6.805 1.679)
        (xy -6.691 1.614)
        (xy -6.567 1.543)
        (xy -6.438 1.469)
        (xy -6.306 1.392)
        (xy -6.174 1.316)
        (xy -6.045 1.241)
        (xy -5.922 1.17)
        (xy -5.809 1.103)
        (xy -5.708 1.044)
        (xy -5.622 0.992)
        (xy -5.553 0.952)
        (xy -5.507 0.923)
        (xy -5.484 0.907)
        (xy -5.483 0.907)
        (xy -5.467 0.892)
        (xy -5.453 0.878)
        (xy -5.441 0.861)
        (xy -5.431 0.839)
        (xy -5.423 0.81)
        (xy -5.417 0.772)
        (xy -5.412 0.721)
        (xy -5.408 0.656)
        (xy -5.406 0.574)
        (xy -5.404 0.473)
        (xy -5.403 0.35)
        (xy -5.402 0.203)
        (xy -5.402 0.03)
        (xy -5.402 -0.172)
        (xy -5.402 -0.189)
        (xy -5.402 -0.395)
        (xy -5.402 -0.572)
        (xy -5.403 -0.721)
        (xy -5.404 -0.847)
        (xy -5.406 -0.95)
        (xy -5.408 -1.034)
        (xy -5.412 -1.101)
        (xy -5.418 -1.153)
        (xy -5.425 -1.193)
        (xy -5.434 -1.223)
        (xy -5.445 -1.245)
        (xy -5.458 -1.262)
        (xy -5.473 -1.276)
        (xy -5.491 -1.29)
        (xy -5.499 -1.295)
        (xy -5.522 -1.31)
        (xy -5.57 -1.339)
        (xy -5.64 -1.381)
        (xy -5.729 -1.433)
        (xy -5.835 -1.496)
        (xy -5.956 -1.566)
        (xy -6.088 -1.643)
        (xy -6.229 -1.725)
        (xy -6.348 -1.793)
        (xy -6.519 -1.891)
        (xy -6.664 -1.974)
        (xy -6.786 -2.044)
        (xy -6.888 -2.101)
        (xy -6.971 -2.147)
        (xy -7.038 -2.183)
        (xy -7.091 -2.21)
        (xy -7.132 -2.229)
        (xy -7.163 -2.242)
        (xy -7.187 -2.249)
        (xy -7.205 -2.252)
        (xy -7.211 -2.252)
        (xy -7.228 -2.251)
        (xy -7.249 -2.246)
        (xy -7.276 -2.236)
        (xy -7.312 -2.219)
        (xy -7.359 -2.196)
        (xy -7.419 -2.165)
        (xy -7.495 -2.123)
        (xy -7.587 -2.072)
        (xy -7.699 -2.008)
        (xy -7.832 -1.932)
        (xy -7.99 -1.842)
        (xy -8.1 -1.778)
        (xy -8.248 -1.693)
        (xy -8.388 -1.611)
        (xy -8.519 -1.535)
        (xy -8.637 -1.466)
        (xy -8.739 -1.406)
        (xy -8.825 -1.355)
        (xy -8.89 -1.316)
        (xy -8.933 -1.29)
        (xy -8.951 -1.278)
        (xy -8.966 -1.265)
        (xy -8.978 -1.251)
        (xy -8.989 -1.234)
        (xy -8.998 -1.212)
        (xy -9.005 -1.182)
        (xy -9.011 -1.141)
        (xy -9.015 -1.087)
        (xy -9.018 -1.019)
        (xy -9.021 -0.933)
        (xy -9.022 -0.827)
        (xy -9.023 -0.699)
        (xy -9.024 -0.546)
        (xy -9.024 -0.366)
        (xy -9.024 -0.189)
        (xy -9.997 -0.189)
        (xy -9.997 -0.224)
        (xy -9.996 -0.479)
        (xy -9.996 -0.705)
        (xy -9.995 -0.903)
        (xy -9.994 -1.075)
        (xy -9.993 -1.223)
        (xy -9.992 -1.35)
        (xy -9.99 -1.456)
        (xy -9.987 -1.545)
        (xy -9.984 -1.617)
        (xy -9.98 -1.675)
        (xy -9.974 -1.721)
        (xy -9.968 -1.757)
        (xy -9.961 -1.784)
        (xy -9.952 -1.805)
        (xy -9.941 -1.821)
        (xy -9.929 -1.834)
        (xy -9.915 -1.847)
        (xy -9.9 -1.86)
        (xy -9.893 -1.866)
        (xy -9.873 -1.88)
        (xy -9.828 -1.909)
        (xy -9.759 -1.951)
        (xy -9.669 -2.005)
        (xy -9.56 -2.07)
        (xy -9.433 -2.145)
        (xy -9.291 -2.228)
        (xy -9.136 -2.319)
        (xy -8.969 -2.416)
        (xy -8.793 -2.518)
        (xy -8.61 -2.624)
        (xy -8.59 -2.635)
        (xy -8.377 -2.759)
        (xy -8.189 -2.867)
        (xy -8.024 -2.962)
        (xy -7.882 -3.044)
        (xy -7.759 -3.114)
        (xy -7.656 -3.173)
        (xy -7.568 -3.221)
        (xy -7.496 -3.261)
        (xy -7.437 -3.293)
        (xy -7.389 -3.317)
        (xy -7.351 -3.336)
        (xy -7.321 -3.349)
        (xy -7.296 -3.357)
        (xy -7.276 -3.363)
        (xy -7.259 -3.366)
        (xy -7.242 -3.367)
        (xy -7.237 -3.368)
        (xy -7.153 -3.366)
      )

      (stroke (width 0.00186) (type solid)) (fill solid) (layer "F.Cu"))
    (fp_poly
      (pts
        (xy -7.128 -1.48)
        (xy -7.114 -1.475)
        (xy -7.042 -1.428)
        (xy -6.989 -1.361)
        (xy -6.96 -1.281)
        (xy -6.957 -1.196)
        (xy -6.961 -1.175)
        (xy -6.992 -1.094)
        (xy -7.046 -1.034)
        (xy -7.101 -1.001)
        (xy -7.166 -0.969)
        (xy -7.166 -0.599)
        (xy -6.891 -0.599)
        (xy -6.778 -0.711)
        (xy -6.665 -0.824)
        (xy -6.673 -0.905)
        (xy -6.673 -0.906)
        (xy -6.566 -0.906)
        (xy -6.549 -0.87)
        (xy -6.512 -0.853)
        (xy -6.467 -0.856)
        (xy -6.435 -0.876)
        (xy -6.412 -0.913)
        (xy -6.42 -0.95)
        (xy -6.441 -0.977)
        (xy -6.471 -1.002)
        (xy -6.496 -1.005)
        (xy -6.53 -0.986)
        (xy -6.532 -0.984)
        (xy -6.56 -0.949)
        (xy -6.566 -0.906)
        (xy -6.673 -0.906)
        (xy -6.676 -0.957)
        (xy -6.669 -0.992)
        (xy -6.648 -1.025)
        (xy -6.639 -1.036)
        (xy -6.582 -1.084)
        (xy -6.519 -1.106)
        (xy -6.456 -1.105)
        (xy -6.397 -1.084)
        (xy -6.349 -1.044)
        (xy -6.316 -0.99)
        (xy -6.304 -0.925)
        (xy -6.315 -0.859)
        (xy -6.351 -0.797)
        (xy -6.408 -0.757)
        (xy -6.484 -0.741)
        (xy -6.497 -0.741)
        (xy -6.529 -0.74)
        (xy -6.557 -0.734)
        (xy -6.585 -0.719)
        (xy -6.619 -0.693)
        (xy -6.667 -0.651)
        (xy -6.705 -0.615)
        (xy -6.84 -0.489)
        (xy -7.166 -0.489)
        (xy -7.166 -0.237)
        (xy -6.568 -0.237)
        (xy -6.545 -0.282)
        (xy -6.502 -0.333)
        (xy -6.443 -0.364)
        (xy -6.377 -0.373)
        (xy -6.311 -0.36)
        (xy -6.255 -0.322)
        (xy -6.249 -0.317)
        (xy -6.209 -0.253)
        (xy -6.195 -0.188)
        (xy -6.205 -0.126)
        (xy -6.234 -0.072)
        (xy -6.28 -0.03)
        (xy -6.337 -0.006)
        (xy -6.402 -0.002)
        (xy -6.472 -0.025)
        (xy -6.486 -0.033)
        (xy -6.523 -0.061)
        (xy -6.545 -0.091)
        (xy -6.547 -0.096)
        (xy -6.552 -0.106)
        (xy -6.561 -0.114)
        (xy -6.58 -0.12)
        (xy -6.613 -0.123)
        (xy -6.664 -0.125)
        (xy -6.737 -0.126)
        (xy -6.836 -0.126)
        (xy -6.861 -0.126)
        (xy -7.166 -0.126)
        (xy -7.166 0.11)
        (xy -6.842 0.11)
        (xy -6.581 0.373)
        (xy -6.507 0.366)
        (xy -6.428 0.372)
        (xy -6.367 0.402)
        (xy -6.325 0.457)
        (xy -6.314 0.486)
        (xy -6.304 0.561)
        (xy -6.322 0.626)
        (xy -6.361 0.678)
        (xy -6.422 0.72)
        (xy -6.487 0.736)
        (xy -6.55 0.727)
        (xy -6.605 0.697)
        (xy -6.648 0.648)
        (xy -6.671 0.583)
        (xy -6.672 0.536)
        (xy -6.564 0.536)
        (xy -6.559 0.575)
        (xy -6.544 0.597)
        (xy -6.508 0.625)
        (xy -6.474 0.623)
        (xy -6.441 0.598)
        (xy -6.414 0.56)
        (xy -6.417 0.525)
        (xy -6.44 0.497)
        (xy -6.48 0.476)
        (xy -6.518 0.48)
        (xy -6.549 0.502)
        (xy -6.564 0.536)
        (xy -6.672 0.536)
        (xy -6.673 0.52)
        (xy -6.664 0.445)
        (xy -6.891 0.22)
        (xy -7.166 0.22)
        (xy -7.166 0.593)
        (xy -7.101 0.622)
        (xy -7.033 0.668)
        (xy -6.986 0.732)
        (xy -6.96 0.805)
        (xy -6.956 0.883)
        (xy -6.973 0.959)
        (xy -7.013 1.026)
        (xy -7.074 1.079)
        (xy -7.088 1.087)
        (xy -7.171 1.112)
        (xy -7.258 1.112)
        (xy -7.34 1.087)
        (xy -7.341 1.086)
        (xy -7.406 1.036)
        (xy -7.448 0.97)
        (xy -7.469 0.895)
        (xy -7.468 0.858)
        (xy -7.361 0.858)
        (xy -7.355 0.905)
        (xy -7.331 0.942)
        (xy -7.31 0.962)
        (xy -7.252 0.999)
        (xy -7.195 1.005)
        (xy -7.137 0.979)
        (xy -7.116 0.962)
        (xy -7.08 0.923)
        (xy -7.066 0.883)
        (xy -7.065 0.858)
        (xy -7.079 0.801)
        (xy -7.116 0.751)
        (xy -7.167 0.718)
        (xy -7.213 0.708)
        (xy -7.27 0.722)
        (xy -7.319 0.76)
        (xy -7.352 0.812)
        (xy -7.361 0.858)
        (xy -7.468 0.858)
        (xy -7.468 0.817)
        (xy -7.445 0.742)
        (xy -7.401 0.677)
        (xy -7.336 0.628)
        (xy -7.325 0.622)
        (xy -7.26 0.593)
        (xy -7.26 0.22)
        (xy -7.535 0.22)
        (xy -7.762 0.445)
        (xy -7.753 0.52)
        (xy -7.757 0.595)
        (xy -7.785 0.658)
        (xy -7.83 0.703)
        (xy -7.887 0.73)
        (xy -7.951 0.735)
        (xy -8.015 0.715)
        (xy -8.065 0.678)
        (xy -8.109 0.617)
        (xy -8.123 0.551)
        (xy -8.12 0.532)
        (xy -8.012 0.532)
        (xy -8.009 0.566)
        (xy -7.985 0.598)
        (xy -7.946 0.625)
        (xy -7.912 0.623)
        (xy -7.883 0.599)
        (xy -7.863 0.558)
        (xy -7.868 0.517)
        (xy -7.896 0.486)
        (xy -7.915 0.478)
        (xy -7.961 0.48)
        (xy -7.985 0.496)
        (xy -8.012 0.532)
        (xy -8.12 0.532)
        (xy -8.112 0.486)
        (xy -8.079 0.422)
        (xy -8.025 0.381)
        (xy -7.953 0.365)
        (xy -7.919 0.366)
        (xy -7.845 0.373)
        (xy -7.584 0.11)
        (xy -7.26 0.11)
        (xy -7.26 -0.126)
        (xy -7.566 -0.126)
        (xy -7.672 -0.126)
        (xy -7.75 -0.126)
        (xy -7.805 -0.124)
        (xy -7.841 -0.121)
        (xy -7.863 -0.116)
        (xy -7.875 -0.108)
        (xy -7.881 -0.098)
        (xy -7.883 -0.094)
        (xy -7.908 -0.058)
        (xy -7.954 -0.026)
        (xy -8.009 -0.005)
        (xy -8.045 -0.001)
        (xy -8.117 -0.014)
        (xy -8.174 -0.049)
        (xy -8.213 -0.102)
        (xy -8.23 -0.164)
        (xy -8.228 -0.186)
        (xy -8.124 -0.186)
        (xy -8.12 -0.163)
        (xy -8.104 -0.143)
        (xy -8.063 -0.115)
        (xy -8.021 -0.117)
        (xy -7.994 -0.135)
        (xy -7.971 -0.176)
        (xy -7.976 -0.202)
        (xy -6.455 -0.202)
        (xy -6.449 -0.158)
        (xy -6.432 -0.135)
        (xy -6.392 -0.113)
        (xy -6.35 -0.121)
        (xy -6.322 -0.143)
        (xy -6.303 -0.169)
        (xy -6.304 -0.193)
        (xy -6.316 -0.218)
        (xy -6.35 -0.254)
        (xy -6.39 -0.265)
        (xy -6.429 -0.247)
        (xy -6.432 -0.244)
        (xy -6.455 -0.202)
        (xy -7.976 -0.202)
        (xy -7.979 -0.218)
        (xy -7.999 -0.244)
        (xy -8.04 -0.265)
        (xy -8.078 -0.255)
        (xy -8.11 -0.218)
        (xy -8.124 -0.186)
        (xy -8.228 -0.186)
        (xy -8.224 -0.232)
        (xy -8.192 -0.297)
        (xy -8.177 -0.317)
        (xy -8.121 -0.358)
        (xy -8.055 -0.374)
        (xy -7.988 -0.365)
        (xy -7.927 -0.333)
        (xy -7.885 -0.284)
        (xy -7.857 -0.237)
        (xy -7.26 -0.237)
        (xy -7.26 -0.489)
        (xy -7.586 -0.489)
        (xy -7.721 -0.615)
        (xy -7.779 -0.669)
        (xy -7.821 -0.704)
        (xy -7.852 -0.726)
        (xy -7.879 -0.737)
        (xy -7.908 -0.74)
        (xy -7.934 -0.741)
        (xy -8.011 -0.752)
        (xy -8.068 -0.787)
        (xy -8.105 -0.846)
        (xy -8.112 -0.866)
        (xy -8.119 -0.923)
        (xy -8.016 -0.923)
        (xy -8.003 -0.887)
        (xy -7.969 -0.862)
        (xy -7.928 -0.852)
        (xy -7.888 -0.861)
        (xy -7.878 -0.87)
        (xy -7.86 -0.907)
        (xy -7.866 -0.949)
        (xy -7.894 -0.984)
        (xy -7.924 -1.002)
        (xy -7.941 -1.008)
        (xy -7.964 -0.997)
        (xy -7.991 -0.969)
        (xy -8.011 -0.939)
        (xy -8.016 -0.923)
        (xy -8.119 -0.923)
        (xy -8.121 -0.94)
        (xy -8.105 -1.004)
        (xy -8.069 -1.055)
        (xy -8.018 -1.091)
        (xy -7.958 -1.108)
        (xy -7.894 -1.104)
        (xy -7.831 -1.076)
        (xy -7.787 -1.036)
        (xy -7.762 -1.001)
        (xy -7.751 -0.968)
        (xy -7.751 -0.923)
        (xy -7.753 -0.905)
        (xy -7.762 -0.824)
        (xy -7.648 -0.711)
        (xy -7.535 -0.599)
        (xy -7.26 -0.599)
        (xy -7.26 -0.971)
        (xy -7.323 -0.998)
        (xy -7.396 -1.046)
        (xy -7.446 -1.114)
        (xy -7.465 -1.166)
        (xy -7.472 -1.24)
        (xy -7.365 -1.24)
        (xy -7.359 -1.204)
        (xy -7.347 -1.177)
        (xy -7.307 -1.123)
        (xy -7.254 -1.093)
        (xy -7.194 -1.09)
        (xy -7.134 -1.116)
        (xy -7.127 -1.121)
        (xy -7.081 -1.171)
        (xy -7.065 -1.225)
        (xy -7.078 -1.283)
        (xy -7.116 -1.342)
        (xy -7.166 -1.375)
        (xy -7.222 -1.384)
        (xy -7.278 -1.368)
        (xy -7.326 -1.326)
        (xy -7.354 -1.278)
        (xy -7.365 -1.24)
        (xy -7.472 -1.24)
        (xy -7.474 -1.25)
        (xy -7.455 -1.328)
        (xy -7.416 -1.396)
        (xy -7.358 -1.449)
        (xy -7.288 -1.484)
        (xy -7.21 -1.495)
        (xy -7.128 -1.48)
      )

      (stroke (width 0.00186) (type solid)) (fill solid) (layer "F.Cu"))
    (fp_poly
      (pts
        (xy 5.212 0.944)
        (xy 4.834 0.944)
        (xy 4.834 -1.292)
        (xy 5.212 -1.292)
        (xy 5.212 0.944)
      )

      (stroke (width 0.00186) (type solid)) (fill solid) (layer "F.Mask"))
    (fp_poly
      (pts
        (xy 8.164 -1.321)
        (xy 8.193 -1.317)
        (xy 8.204 -1.31)
        (xy 8.204 -1.308)
        (xy 8.2 -1.285)
        (xy 8.188 -1.24)
        (xy 8.171 -1.181)
        (xy 8.163 -1.156)
        (xy 8.142 -1.092)
        (xy 8.126 -1.053)
        (xy 8.112 -1.034)
        (xy 8.097 -1.031)
        (xy 8.094 -1.032)
        (xy 7.996 -1.053)
        (xy 7.886 -1.06)
        (xy 7.778 -1.053)
        (xy 7.683 -1.032)
        (xy 7.665 -1.026)
        (xy 7.622 -1.009)
        (xy 7.622 0.944)
        (xy 7.244 0.944)
        (xy 7.244 -1.178)
        (xy 7.358 -1.219)
        (xy 7.457 -1.253)
        (xy 7.548 -1.277)
        (xy 7.639 -1.295)
        (xy 7.738 -1.307)
        (xy 7.856 -1.315)
        (xy 7.94 -1.319)
        (xy 8.042 -1.322)
        (xy 8.115 -1.322)
        (xy 8.164 -1.321)
      )

      (stroke (width 0.00186) (type solid)) (fill solid) (layer "F.Mask"))
    (fp_poly
      (pts
        (xy 0.795 -1.891)
        (xy 0.798 -1.849)
        (xy 0.8 -1.786)
        (xy 0.802 -1.705)
        (xy 0.803 -1.612)
        (xy 0.803 -1.599)
        (xy 0.803 -1.292)
        (xy 1.181 -1.292)
        (xy 1.181 -1.04)
        (xy 0.803 -1.04)
        (xy 0.803 0.498)
        (xy 0.838 0.566)
        (xy 0.885 0.631)
        (xy 0.944 0.671)
        (xy 1.021 0.688)
        (xy 1.082 0.689)
        (xy 1.181 0.685)
        (xy 1.181 0.806)
        (xy 1.178 0.88)
        (xy 1.17 0.926)
        (xy 1.161 0.939)
        (xy 1.138 0.945)
        (xy 1.09 0.95)
        (xy 1.028 0.954)
        (xy 0.984 0.956)
        (xy 0.897 0.957)
        (xy 0.832 0.953)
        (xy 0.778 0.942)
        (xy 0.743 0.931)
        (xy 0.647 0.886)
        (xy 0.571 0.823)
        (xy 0.508 0.737)
        (xy 0.488 0.701)
        (xy 0.433 0.593)
        (xy 0.428 -0.223)
        (xy 0.424 -1.04)
        (xy 0.173 -1.04)
        (xy 0.173 -1.292)
        (xy 0.425 -1.292)
        (xy 0.425 -1.795)
        (xy 0.603 -1.85)
        (xy 0.673 -1.872)
        (xy 0.733 -1.89)
        (xy 0.774 -1.902)
        (xy 0.792 -1.906)
        (xy 0.795 -1.891)
      )

      (stroke (width 0.00186) (type solid)) (fill solid) (layer "F.Mask"))
    (fp_poly
      (pts
        (xy -0.82 -1.315)
        (xy -0.737 -1.312)
        (xy -0.672 -1.308)
        (xy -0.621 -1.301)
        (xy -0.577 -1.291)
        (xy -0.56 -1.286)
        (xy -0.417 -1.232)
        (xy -0.302 -1.164)
        (xy -0.212 -1.082)
        (xy -0.154 -0.996)
        (xy -0.135 -0.961)
        (xy -0.119 -0.927)
        (xy -0.105 -0.893)
        (xy -0.094 -0.855)
        (xy -0.085 -0.811)
        (xy -0.078 -0.758)
        (xy -0.073 -0.693)
        (xy -0.069 -0.612)
        (xy -0.067 -0.515)
        (xy -0.065 -0.397)
        (xy -0.064 -0.256)
        (xy -0.064 -0.088)
        (xy -0.063 0.105)
        (xy -0.063 0.944)
        (xy -0.441 0.944)
        (xy -0.441 0.113)
        (xy -0.442 -0.083)
        (xy -0.442 -0.25)
        (xy -0.443 -0.391)
        (xy -0.445 -0.508)
        (xy -0.448 -0.604)
        (xy -0.452 -0.682)
        (xy -0.457 -0.744)
        (xy -0.465 -0.794)
        (xy -0.474 -0.833)
        (xy -0.486 -0.864)
        (xy -0.501 -0.89)
        (xy -0.518 -0.913)
        (xy -0.538 -0.937)
        (xy -0.539 -0.939)
        (xy -0.604 -0.997)
        (xy -0.684 -1.039)
        (xy -0.784 -1.066)
        (xy -0.822 -1.072)
        (xy -0.927 -1.078)
        (xy -1.044 -1.073)
        (xy -1.158 -1.056)
        (xy -1.24 -1.034)
        (xy -1.3 -1.013)
        (xy -1.304 -0.034)
        (xy -1.308 0.944)
        (xy -1.686 0.944)
        (xy -1.686 -1.178)
        (xy -1.54 -1.225)
        (xy -1.44 -1.257)
        (xy -1.354 -1.28)
        (xy -1.276 -1.297)
        (xy -1.195 -1.307)
        (xy -1.105 -1.313)
        (xy -0.995 -1.315)
        (xy -0.93 -1.315)
        (xy -0.82 -1.315)
      )

      (stroke (width 0.00186) (type solid)) (fill solid) (layer "F.Mask"))
    (fp_poly
      (pts
        (xy 3.757 -1.312)
        (xy 3.91 -1.278)
        (xy 4.043 -1.223)
        (xy 4.153 -1.146)
        (xy 4.24 -1.047)
        (xy 4.282 -0.977)
        (xy 4.299 -0.943)
        (xy 4.313 -0.91)
        (xy 4.325 -0.876)
        (xy 4.335 -0.837)
        (xy 4.343 -0.791)
        (xy 4.349 -0.734)
        (xy 4.353 -0.665)
        (xy 4.357 -0.581)
        (xy 4.359 -0.478)
        (xy 4.361 -0.354)
        (xy 4.361 -0.206)
        (xy 4.362 -0.031)
        (xy 4.362 0.111)
        (xy 4.362 0.944)
        (xy 3.985 0.944)
        (xy 3.98 0.074)
        (xy 3.976 -0.796)
        (xy 3.93 -0.879)
        (xy 3.867 -0.961)
        (xy 3.786 -1.022)
        (xy 3.691 -1.062)
        (xy 3.586 -1.079)
        (xy 3.476 -1.074)
        (xy 3.366 -1.045)
        (xy 3.26 -0.994)
        (xy 3.185 -0.938)
        (xy 3.118 -0.88)
        (xy 3.118 0.944)
        (xy 2.74 0.944)
        (xy 2.74 0.092)
        (xy 2.739 -0.122)
        (xy 2.739 -0.305)
        (xy 2.737 -0.459)
        (xy 2.735 -0.585)
        (xy 2.732 -0.683)
        (xy 2.729 -0.755)
        (xy 2.725 -0.802)
        (xy 2.722 -0.821)
        (xy 2.679 -0.91)
        (xy 2.613 -0.981)
        (xy 2.523 -1.034)
        (xy 2.413 -1.067)
        (xy 2.284 -1.079)
        (xy 2.154 -1.073)
        (xy 2.082 -1.064)
        (xy 2.031 -1.056)
        (xy 1.989 -1.046)
        (xy 1.944 -1.031)
        (xy 1.917 -1.021)
        (xy 1.874 -1.005)
        (xy 1.874 0.944)
        (xy 1.511 0.944)
        (xy 1.511 -1.18)
        (xy 1.661 -1.228)
        (xy 1.83 -1.276)
        (xy 1.988 -1.306)
        (xy 2.148 -1.319)
        (xy 2.314 -1.319)
        (xy 2.448 -1.311)
        (xy 2.557 -1.297)
        (xy 2.649 -1.272)
        (xy 2.732 -1.237)
        (xy 2.811 -1.189)
        (xy 2.843 -1.165)
        (xy 2.947 -1.087)
        (xy 3.012 -1.14)
        (xy 3.14 -1.224)
        (xy 3.283 -1.283)
        (xy 3.443 -1.315)
        (xy 3.582 -1.323)
        (xy 3.757 -1.312)
      )

      (stroke (width 0.00186) (type solid)) (fill solid) (layer "F.Mask"))
    (fp_poly
      (pts
        (xy 9.278 -1.313)
        (xy 9.419 -1.281)
        (xy 9.543 -1.225)
        (xy 9.656 -1.146)
        (xy 9.708 -1.097)
        (xy 9.808 -0.975)
        (xy 9.887 -0.831)
        (xy 9.945 -0.666)
        (xy 9.984 -0.476)
        (xy 9.998 -0.354)
        (xy 10.005 -0.134)
        (xy 9.992 0.072)
        (xy 9.96 0.262)
        (xy 9.908 0.434)
        (xy 9.837 0.585)
        (xy 9.749 0.714)
        (xy 9.643 0.819)
        (xy 9.578 0.867)
        (xy 9.475 0.918)
        (xy 9.352 0.956)
        (xy 9.219 0.98)
        (xy 9.087 0.986)
        (xy 8.966 0.975)
        (xy 8.81 0.933)
        (xy 8.673 0.864)
        (xy 8.553 0.771)
        (xy 8.452 0.653)
        (xy 8.371 0.511)
        (xy 8.31 0.346)
        (xy 8.277 0.202)
        (xy 8.249 -0.011)
        (xy 8.243 -0.182)
        (xy 8.619 -0.182)
        (xy 8.626 -0.007)
        (xy 8.647 0.163)
        (xy 8.682 0.318)
        (xy 8.73 0.449)
        (xy 8.792 0.552)
        (xy 8.87 0.633)
        (xy 8.961 0.69)
        (xy 9.06 0.721)
        (xy 9.164 0.724)
        (xy 9.268 0.699)
        (xy 9.303 0.683)
        (xy 9.391 0.625)
        (xy 9.465 0.546)
        (xy 9.524 0.443)
        (xy 9.569 0.315)
        (xy 9.601 0.162)
        (xy 9.62 0)
        (xy 9.628 -0.198)
        (xy 9.62 -0.382)
        (xy 9.597 -0.55)
        (xy 9.558 -0.698)
        (xy 9.505 -0.825)
        (xy 9.439 -0.927)
        (xy 9.397 -0.971)
        (xy 9.307 -1.035)
        (xy 9.21 -1.071)
        (xy 9.109 -1.079)
        (xy 9.009 -1.062)
        (xy 8.915 -1.019)
        (xy 8.831 -0.953)
        (xy 8.76 -0.863)
        (xy 8.733 -0.813)
        (xy 8.684 -0.68)
        (xy 8.648 -0.526)
        (xy 8.627 -0.358)
        (xy 8.619 -0.182)
        (xy 8.243 -0.182)
        (xy 8.242 -0.218)
        (xy 8.255 -0.417)
        (xy 8.288 -0.602)
        (xy 8.339 -0.772)
        (xy 8.41 -0.923)
        (xy 8.498 -1.051)
        (xy 8.524 -1.081)
        (xy 8.637 -1.182)
        (xy 8.765 -1.255)
        (xy 8.908 -1.302)
        (xy 9.068 -1.322)
        (xy 9.117 -1.323)
        (xy 9.278 -1.313)
      )

      (stroke (width 0.00186) (type solid)) (fill solid) (layer "F.Mask"))
    (fp_poly
      (pts
        (xy 6.48 -1.32)
        (xy 6.584 -1.31)
        (xy 6.642 -1.3)
        (xy 6.701 -1.282)
        (xy 6.765 -1.259)
        (xy 6.825 -1.233)
        (xy 6.873 -1.209)
        (xy 6.9 -1.189)
        (xy 6.902 -1.186)
        (xy 6.901 -1.166)
        (xy 6.889 -1.128)
        (xy 6.872 -1.079)
        (xy 6.852 -1.03)
        (xy 6.833 -0.989)
        (xy 6.818 -0.966)
        (xy 6.815 -0.963)
        (xy 6.795 -0.969)
        (xy 6.757 -0.985)
        (xy 6.717 -1.002)
        (xy 6.597 -1.044)
        (xy 6.478 -1.06)
        (xy 6.365 -1.05)
        (xy 6.267 -1.016)
        (xy 6.184 -0.957)
        (xy 6.109 -0.87)
        (xy 6.042 -0.76)
        (xy 5.988 -0.629)
        (xy 5.964 -0.554)
        (xy 5.946 -0.461)
        (xy 5.934 -0.347)
        (xy 5.929 -0.22)
        (xy 5.931 -0.091)
        (xy 5.938 0.032)
        (xy 5.953 0.138)
        (xy 5.965 0.191)
        (xy 6.018 0.347)
        (xy 6.085 0.476)
        (xy 6.166 0.576)
        (xy 6.262 0.649)
        (xy 6.269 0.653)
        (xy 6.318 0.678)
        (xy 6.36 0.692)
        (xy 6.409 0.698)
        (xy 6.476 0.7)
        (xy 6.48 0.7)
        (xy 6.551 0.697)
        (xy 6.613 0.686)
        (xy 6.676 0.665)
        (xy 6.75 0.631)
        (xy 6.805 0.602)
        (xy 6.811 0.606)
        (xy 6.823 0.627)
        (xy 6.842 0.667)
        (xy 6.868 0.73)
        (xy 6.904 0.819)
        (xy 6.907 0.827)
        (xy 6.898 0.844)
        (xy 6.866 0.868)
        (xy 6.818 0.895)
        (xy 6.759 0.922)
        (xy 6.697 0.945)
        (xy 6.68 0.95)
        (xy 6.596 0.968)
        (xy 6.494 0.98)
        (xy 6.388 0.984)
        (xy 6.292 0.98)
        (xy 6.251 0.975)
        (xy 6.192 0.96)
        (xy 6.121 0.935)
        (xy 6.055 0.906)
        (xy 5.924 0.825)
        (xy 5.811 0.718)
        (xy 5.717 0.586)
        (xy 5.641 0.431)
        (xy 5.585 0.252)
        (xy 5.566 0.164)
        (xy 5.552 0.061)
        (xy 5.545 -0.061)
        (xy 5.544 -0.193)
        (xy 5.549 -0.327)
        (xy 5.56 -0.453)
        (xy 5.576 -0.563)
        (xy 5.589 -0.623)
        (xy 5.65 -0.797)
        (xy 5.731 -0.949)
        (xy 5.831 -1.077)
        (xy 5.948 -1.181)
        (xy 6.081 -1.259)
        (xy 6.187 -1.298)
        (xy 6.27 -1.314)
        (xy 6.372 -1.322)
        (xy 6.48 -1.32)
      )

      (stroke (width 0.00186) (type solid)) (fill solid) (layer "F.Mask"))
    (fp_poly
      (pts
        (xy -2.763 -1.313)
        (xy -2.663 -1.294)
        (xy -2.55 -1.259)
        (xy -2.459 -1.216)
        (xy -2.38 -1.16)
        (xy -2.341 -1.124)
        (xy -2.284 -1.053)
        (xy -2.232 -0.961)
        (xy -2.192 -0.861)
        (xy -2.174 -0.79)
        (xy -2.17 -0.754)
        (xy -2.167 -0.69)
        (xy -2.164 -0.599)
        (xy -2.162 -0.485)
        (xy -2.16 -0.35)
        (xy -2.159 -0.196)
        (xy -2.158 -0.027)
        (xy -2.158 0.064)
        (xy -2.158 0.833)
        (xy -2.232 0.865)
        (xy -2.364 0.913)
        (xy -2.517 0.949)
        (xy -2.682 0.974)
        (xy -2.85 0.986)
        (xy -3.011 0.983)
        (xy -3.097 0.975)
        (xy -3.264 0.942)
        (xy -3.407 0.889)
        (xy -3.525 0.817)
        (xy -3.618 0.725)
        (xy -3.686 0.616)
        (xy -3.729 0.487)
        (xy -3.746 0.341)
        (xy -3.746 0.268)
        (xy -3.744 0.254)
        (xy -3.383 0.254)
        (xy -3.38 0.384)
        (xy -3.352 0.497)
        (xy -3.298 0.591)
        (xy -3.221 0.665)
        (xy -3.12 0.719)
        (xy -3.072 0.735)
        (xy -3.011 0.745)
        (xy -2.928 0.75)
        (xy -2.835 0.75)
        (xy -2.74 0.744)
        (xy -2.655 0.734)
        (xy -2.589 0.72)
        (xy -2.579 0.716)
        (xy -2.504 0.689)
        (xy -2.504 -0.302)
        (xy -2.595 -0.291)
        (xy -2.653 -0.282)
        (xy -2.728 -0.267)
        (xy -2.806 -0.25)
        (xy -2.831 -0.244)
        (xy -2.992 -0.194)
        (xy -3.125 -0.133)
        (xy -3.229 -0.06)
        (xy -3.306 0.026)
        (xy -3.357 0.125)
        (xy -3.381 0.238)
        (xy -3.383 0.254)
        (xy -3.744 0.254)
        (xy -3.725 0.126)
        (xy -3.678 0)
        (xy -3.602 -0.112)
        (xy -3.559 -0.158)
        (xy -3.465 -0.233)
        (xy -3.343 -0.303)
        (xy -3.198 -0.365)
        (xy -3.034 -0.417)
        (xy -2.856 -0.46)
        (xy -2.666 -0.49)
        (xy -2.663 -0.49)
        (xy -2.5 -0.51)
        (xy -2.51 -0.644)
        (xy -2.528 -0.77)
        (xy -2.564 -0.871)
        (xy -2.62 -0.949)
        (xy -2.697 -1.007)
        (xy -2.797 -1.045)
        (xy -2.845 -1.056)
        (xy -2.975 -1.067)
        (xy -3.12 -1.056)
        (xy -3.272 -1.024)
        (xy -3.426 -0.972)
        (xy -3.439 -0.967)
        (xy -3.488 -0.947)
        (xy -3.523 -0.936)
        (xy -3.537 -0.934)
        (xy -3.545 -0.95)
        (xy -3.56 -0.987)
        (xy -3.579 -1.035)
        (xy -3.598 -1.086)
        (xy -3.613 -1.129)
        (xy -3.622 -1.155)
        (xy -3.623 -1.159)
        (xy -3.609 -1.169)
        (xy -3.575 -1.188)
        (xy -3.537 -1.206)
        (xy -3.395 -1.257)
        (xy -3.239 -1.294)
        (xy -3.075 -1.316)
        (xy -2.914 -1.323)
        (xy -2.763 -1.313)
      )

      (stroke (width 0.00186) (type solid)) (fill solid) (layer "F.Mask"))
    (fp_poly
      (pts
        (xy -7.153 -3.366)
        (xy -7.087 -3.351)
        (xy -7.086 -3.351)
        (xy -7.066 -3.34)
        (xy -7.021 -3.315)
        (xy -6.953 -3.277)
        (xy -6.865 -3.227)
        (xy -6.759 -3.167)
        (xy -6.639 -3.099)
        (xy -6.505 -3.022)
        (xy -6.361 -2.94)
        (xy -6.209 -2.853)
        (xy -6.052 -2.762)
        (xy -5.891 -2.67)
        (xy -5.729 -2.577)
        (xy -5.569 -2.485)
        (xy -5.413 -2.395)
        (xy -5.264 -2.309)
        (xy -5.123 -2.227)
        (xy -4.994 -2.152)
        (xy -4.878 -2.085)
        (xy -4.778 -2.027)
        (xy -4.697 -1.979)
        (xy -4.636 -1.943)
        (xy -4.599 -1.921)
        (xy -4.595 -1.918)
        (xy -4.528 -1.863)
        (xy -4.476 -1.798)
        (xy -4.434 -1.725)
        (xy -4.429 -0.224)
        (xy -4.429 0.063)
        (xy -4.428 0.323)
        (xy -4.429 0.553)
        (xy -4.429 0.755)
        (xy -4.43 0.928)
        (xy -4.432 1.071)
        (xy -4.434 1.184)
        (xy -4.436 1.266)
        (xy -4.439 1.318)
        (xy -4.441 1.337)
        (xy -4.448 1.36)
        (xy -4.454 1.382)
        (xy -4.463 1.403)
        (xy -4.476 1.423)
        (xy -4.494 1.445)
        (xy -4.519 1.47)
        (xy -4.552 1.497)
        (xy -4.596 1.529)
        (xy -4.652 1.567)
        (xy -4.721 1.611)
        (xy -4.805 1.663)
        (xy -4.906 1.723)
        (xy -5.025 1.794)
        (xy -5.165 1.875)
        (xy -5.326 1.969)
        (xy -5.511 2.076)
        (xy -5.72 2.197)
        (xy -5.813 2.251)
        (xy -7.079 2.982)
        (xy -7.197 2.988)
        (xy -7.315 2.994)
        (xy -7.78 2.727)
        (xy -8.064 2.563)
        (xy -8.323 2.415)
        (xy -8.557 2.28)
        (xy -8.767 2.159)
        (xy -8.955 2.051)
        (xy -9.122 1.954)
        (xy -9.27 1.868)
        (xy -9.399 1.792)
        (xy -9.51 1.726)
        (xy -9.606 1.669)
        (xy -9.688 1.619)
        (xy -9.756 1.576)
        (xy -9.812 1.539)
        (xy -9.857 1.507)
        (xy -9.893 1.481)
        (xy -9.92 1.458)
        (xy -9.94 1.437)
        (xy -9.955 1.42)
        (xy -9.965 1.403)
        (xy -9.972 1.387)
        (xy -9.977 1.371)
        (xy -9.981 1.354)
        (xy -9.985 1.337)
        (xy -9.988 1.309)
        (xy -9.991 1.25)
        (xy -9.993 1.161)
        (xy -9.995 1.041)
        (xy -9.996 0.891)
        (xy -9.997 0.712)
        (xy -9.998 0.503)
        (xy -9.998 0.266)
        (xy -9.997 0)
        (xy -9.997 -0.189)
        (xy -9.024 -0.189)
        (xy -9.024 0.015)
        (xy -9.024 0.191)
        (xy -9.023 0.34)
        (xy -9.022 0.464)
        (xy -9.021 0.567)
        (xy -9.018 0.65)
        (xy -9.014 0.717)
        (xy -9.01 0.768)
        (xy -9.003 0.808)
        (xy -8.995 0.837)
        (xy -8.986 0.859)
        (xy -8.974 0.876)
        (xy -8.961 0.891)
        (xy -8.945 0.905)
        (xy -8.943 0.906)
        (xy -8.922 0.921)
        (xy -8.877 0.949)
        (xy -8.81 0.989)
        (xy -8.725 1.039)
        (xy -8.625 1.098)
        (xy -8.512 1.164)
        (xy -8.389 1.235)
        (xy -8.26 1.31)
        (xy -8.128 1.386)
        (xy -7.995 1.463)
        (xy -7.864 1.538)
        (xy -7.739 1.609)
        (xy -7.622 1.676)
        (xy -7.517 1.735)
        (xy -7.425 1.787)
        (xy -7.351 1.828)
        (xy -7.297 1.857)
        (xy -7.266 1.872)
        (xy -7.261 1.874)
        (xy -7.222 1.885)
        (xy -7.195 1.886)
        (xy -7.163 1.875)
        (xy -7.144 1.867)
        (xy -7.117 1.854)
        (xy -7.067 1.827)
        (xy -6.997 1.788)
        (xy -6.909 1.738)
        (xy -6.805 1.679)
        (xy -6.691 1.614)
        (xy -6.567 1.543)
        (xy -6.438 1.469)
        (xy -6.306 1.392)
        (xy -6.174 1.316)
        (xy -6.045 1.241)
        (xy -5.922 1.17)
        (xy -5.809 1.103)
        (xy -5.708 1.044)
        (xy -5.622 0.992)
        (xy -5.553 0.952)
        (xy -5.507 0.923)
        (xy -5.484 0.907)
        (xy -5.483 0.907)
        (xy -5.467 0.892)
        (xy -5.453 0.878)
        (xy -5.441 0.861)
        (xy -5.431 0.839)
        (xy -5.423 0.81)
        (xy -5.417 0.772)
        (xy -5.412 0.721)
        (xy -5.408 0.656)
        (xy -5.406 0.574)
        (xy -5.404 0.473)
        (xy -5.403 0.35)
        (xy -5.402 0.203)
        (xy -5.402 0.03)
        (xy -5.402 -0.172)
        (xy -5.402 -0.189)
        (xy -5.402 -0.395)
        (xy -5.402 -0.572)
        (xy -5.403 -0.721)
        (xy -5.404 -0.847)
        (xy -5.406 -0.95)
        (xy -5.408 -1.034)
        (xy -5.412 -1.101)
        (xy -5.418 -1.153)
        (xy -5.425 -1.193)
        (xy -5.434 -1.223)
        (xy -5.445 -1.245)
        (xy -5.458 -1.262)
        (xy -5.473 -1.276)
        (xy -5.491 -1.29)
        (xy -5.499 -1.295)
        (xy -5.522 -1.31)
        (xy -5.57 -1.339)
        (xy -5.64 -1.381)
        (xy -5.729 -1.433)
        (xy -5.835 -1.496)
        (xy -5.956 -1.566)
        (xy -6.088 -1.643)
        (xy -6.229 -1.725)
        (xy -6.348 -1.793)
        (xy -6.519 -1.891)
        (xy -6.664 -1.974)
        (xy -6.786 -2.044)
        (xy -6.888 -2.101)
        (xy -6.971 -2.147)
        (xy -7.038 -2.183)
        (xy -7.091 -2.21)
        (xy -7.132 -2.229)
        (xy -7.163 -2.242)
        (xy -7.187 -2.249)
        (xy -7.205 -2.252)
        (xy -7.211 -2.252)
        (xy -7.228 -2.251)
        (xy -7.249 -2.246)
        (xy -7.276 -2.236)
        (xy -7.312 -2.219)
        (xy -7.359 -2.196)
        (xy -7.419 -2.165)
        (xy -7.495 -2.123)
        (xy -7.587 -2.072)
        (xy -7.699 -2.008)
        (xy -7.832 -1.932)
        (xy -7.99 -1.842)
        (xy -8.1 -1.778)
        (xy -8.248 -1.693)
        (xy -8.388 -1.611)
        (xy -8.519 -1.535)
        (xy -8.637 -1.466)
        (xy -8.739 -1.406)
        (xy -8.825 -1.355)
        (xy -8.89 -1.316)
        (xy -8.933 -1.29)
        (xy -8.951 -1.278)
        (xy -8.966 -1.265)
        (xy -8.978 -1.251)
        (xy -8.989 -1.234)
        (xy -8.998 -1.212)
        (xy -9.005 -1.182)
        (xy -9.011 -1.141)
        (xy -9.015 -1.087)
        (xy -9.018 -1.019)
        (xy -9.021 -0.933)
        (xy -9.022 -0.827)
        (xy -9.023 -0.699)
        (xy -9.024 -0.546)
        (xy -9.024 -0.366)
        (xy -9.024 -0.189)
        (xy -9.997 -0.189)
        (xy -9.997 -0.224)
        (xy -9.996 -0.479)
        (xy -9.996 -0.705)
        (xy -9.995 -0.903)
        (xy -9.994 -1.075)
        (xy -9.993 -1.223)
        (xy -9.992 -1.35)
        (xy -9.99 -1.456)
        (xy -9.987 -1.545)
        (xy -9.984 -1.617)
        (xy -9.98 -1.675)
        (xy -9.974 -1.721)
        (xy -9.968 -1.757)
        (xy -9.961 -1.784)
        (xy -9.952 -1.805)
        (xy -9.941 -1.821)
        (xy -9.929 -1.834)
        (xy -9.915 -1.847)
        (xy -9.9 -1.86)
        (xy -9.893 -1.866)
        (xy -9.873 -1.88)
        (xy -9.828 -1.909)
        (xy -9.759 -1.951)
        (xy -9.669 -2.005)
        (xy -9.56 -2.07)
        (xy -9.433 -2.145)
        (xy -9.291 -2.228)
        (xy -9.136 -2.319)
        (xy -8.969 -2.416)
        (xy -8.793 -2.518)
        (xy -8.61 -2.624)
        (xy -8.59 -2.635)
        (xy -8.377 -2.759)
        (xy -8.189 -2.867)
        (xy -8.024 -2.962)
        (xy -7.882 -3.044)
        (xy -7.759 -3.114)
        (xy -7.656 -3.173)
        (xy -7.568 -3.221)
        (xy -7.496 -3.261)
        (xy -7.437 -3.293)
        (xy -7.389 -3.317)
        (xy -7.351 -3.336)
        (xy -7.321 -3.349)
        (xy -7.296 -3.357)
        (xy -7.276 -3.363)
        (xy -7.259 -3.366)
        (xy -7.242 -3.367)
        (xy -7.237 -3.368)
        (xy -7.153 -3.366)
      )

      (stroke (width 0.00186) (type solid)) (fill solid) (layer "F.Mask"))
    (fp_poly
      (pts
        (xy -7.128 -1.48)
        (xy -7.114 -1.475)
        (xy -7.042 -1.428)
        (xy -6.989 -1.361)
        (xy -6.96 -1.281)
        (xy -6.957 -1.196)
        (xy -6.961 -1.175)
        (xy -6.992 -1.094)
        (xy -7.046 -1.034)
        (xy -7.101 -1.001)
        (xy -7.166 -0.969)
        (xy -7.166 -0.599)
        (xy -6.891 -0.599)
        (xy -6.778 -0.711)
        (xy -6.665 -0.824)
        (xy -6.673 -0.905)
        (xy -6.673 -0.906)
        (xy -6.566 -0.906)
        (xy -6.549 -0.87)
        (xy -6.512 -0.853)
        (xy -6.467 -0.856)
        (xy -6.435 -0.876)
        (xy -6.412 -0.913)
        (xy -6.42 -0.95)
        (xy -6.441 -0.977)
        (xy -6.471 -1.002)
        (xy -6.496 -1.005)
        (xy -6.53 -0.986)
        (xy -6.532 -0.984)
        (xy -6.56 -0.949)
        (xy -6.566 -0.906)
        (xy -6.673 -0.906)
        (xy -6.676 -0.957)
        (xy -6.669 -0.992)
        (xy -6.648 -1.025)
        (xy -6.639 -1.036)
        (xy -6.582 -1.084)
        (xy -6.519 -1.106)
        (xy -6.456 -1.105)
        (xy -6.397 -1.084)
        (xy -6.349 -1.044)
        (xy -6.316 -0.99)
        (xy -6.304 -0.925)
        (xy -6.315 -0.859)
        (xy -6.351 -0.797)
        (xy -6.408 -0.757)
        (xy -6.484 -0.741)
        (xy -6.497 -0.741)
        (xy -6.529 -0.74)
        (xy -6.557 -0.734)
        (xy -6.585 -0.719)
        (xy -6.619 -0.693)
        (xy -6.667 -0.651)
        (xy -6.705 -0.615)
        (xy -6.84 -0.489)
        (xy -7.166 -0.489)
        (xy -7.166 -0.237)
        (xy -6.568 -0.237)
        (xy -6.545 -0.282)
        (xy -6.502 -0.333)
        (xy -6.443 -0.364)
        (xy -6.377 -0.373)
        (xy -6.311 -0.36)
        (xy -6.255 -0.322)
        (xy -6.249 -0.317)
        (xy -6.209 -0.253)
        (xy -6.195 -0.188)
        (xy -6.205 -0.126)
        (xy -6.234 -0.072)
        (xy -6.28 -0.03)
        (xy -6.337 -0.006)
        (xy -6.402 -0.002)
        (xy -6.472 -0.025)
        (xy -6.486 -0.033)
        (xy -6.523 -0.061)
        (xy -6.545 -0.091)
        (xy -6.547 -0.096)
        (xy -6.552 -0.106)
        (xy -6.561 -0.114)
        (xy -6.58 -0.12)
        (xy -6.613 -0.123)
        (xy -6.664 -0.125)
        (xy -6.737 -0.126)
        (xy -6.836 -0.126)
        (xy -6.861 -0.126)
        (xy -7.166 -0.126)
        (xy -7.166 0.11)
        (xy -6.842 0.11)
        (xy -6.581 0.373)
        (xy -6.507 0.366)
        (xy -6.428 0.372)
        (xy -6.367 0.402)
        (xy -6.325 0.457)
        (xy -6.314 0.486)
        (xy -6.304 0.561)
        (xy -6.322 0.626)
        (xy -6.361 0.678)
        (xy -6.422 0.72)
        (xy -6.487 0.736)
        (xy -6.55 0.727)
        (xy -6.605 0.697)
        (xy -6.648 0.648)
        (xy -6.671 0.583)
        (xy -6.672 0.536)
        (xy -6.564 0.536)
        (xy -6.559 0.575)
        (xy -6.544 0.597)
        (xy -6.508 0.625)
        (xy -6.474 0.623)
        (xy -6.441 0.598)
        (xy -6.414 0.56)
        (xy -6.417 0.525)
        (xy -6.44 0.497)
        (xy -6.48 0.476)
        (xy -6.518 0.48)
        (xy -6.549 0.502)
        (xy -6.564 0.536)
        (xy -6.672 0.536)
        (xy -6.673 0.52)
        (xy -6.664 0.445)
        (xy -6.891 0.22)
        (xy -7.166 0.22)
        (xy -7.166 0.593)
        (xy -7.101 0.622)
        (xy -7.033 0.668)
        (xy -6.986 0.732)
        (xy -6.96 0.805)
        (xy -6.956 0.883)
        (xy -6.973 0.959)
        (xy -7.013 1.026)
        (xy -7.074 1.079)
        (xy -7.088 1.087)
        (xy -7.171 1.112)
        (xy -7.258 1.112)
        (xy -7.34 1.087)
        (xy -7.341 1.086)
        (xy -7.406 1.036)
        (xy -7.448 0.97)
        (xy -7.469 0.895)
        (xy -7.468 0.858)
        (xy -7.361 0.858)
        (xy -7.355 0.905)
        (xy -7.331 0.942)
        (xy -7.31 0.962)
        (xy -7.252 0.999)
        (xy -7.195 1.005)
        (xy -7.137 0.979)
        (xy -7.116 0.962)
        (xy -7.08 0.923)
        (xy -7.066 0.883)
        (xy -7.065 0.858)
        (xy -7.079 0.801)
        (xy -7.116 0.751)
        (xy -7.167 0.718)
        (xy -7.213 0.708)
        (xy -7.27 0.722)
        (xy -7.319 0.76)
        (xy -7.352 0.812)
        (xy -7.361 0.858)
        (xy -7.468 0.858)
        (xy -7.468 0.817)
        (xy -7.445 0.742)
        (xy -7.401 0.677)
        (xy -7.336 0.628)
        (xy -7.325 0.622)
        (xy -7.26 0.593)
        (xy -7.26 0.22)
        (xy -7.535 0.22)
        (xy -7.762 0.445)
        (xy -7.753 0.52)
        (xy -7.757 0.595)
        (xy -7.785 0.658)
        (xy -7.83 0.703)
        (xy -7.887 0.73)
        (xy -7.951 0.735)
        (xy -8.015 0.715)
        (xy -8.065 0.678)
        (xy -8.109 0.617)
        (xy -8.123 0.551)
        (xy -8.12 0.532)
        (xy -8.012 0.532)
        (xy -8.009 0.566)
        (xy -7.985 0.598)
        (xy -7.946 0.625)
        (xy -7.912 0.623)
        (xy -7.883 0.599)
        (xy -7.863 0.558)
        (xy -7.868 0.517)
        (xy -7.896 0.486)
        (xy -7.915 0.478)
        (xy -7.961 0.48)
        (xy -7.985 0.496)
        (xy -8.012 0.532)
        (xy -8.12 0.532)
        (xy -8.112 0.486)
        (xy -8.079 0.422)
        (xy -8.025 0.381)
        (xy -7.953 0.365)
        (xy -7.919 0.366)
        (xy -7.845 0.373)
        (xy -7.584 0.11)
        (xy -7.26 0.11)
        (xy -7.26 -0.126)
        (xy -7.566 -0.126)
        (xy -7.672 -0.126)
        (xy -7.75 -0.126)
        (xy -7.805 -0.124)
        (xy -7.841 -0.121)
        (xy -7.863 -0.116)
        (xy -7.875 -0.108)
        (xy -7.881 -0.098)
        (xy -7.883 -0.094)
        (xy -7.908 -0.058)
        (xy -7.954 -0.026)
        (xy -8.009 -0.005)
        (xy -8.045 -0.001)
        (xy -8.117 -0.014)
        (xy -8.174 -0.049)
        (xy -8.213 -0.102)
        (xy -8.23 -0.164)
        (xy -8.228 -0.186)
        (xy -8.124 -0.186)
        (xy -8.12 -0.163)
        (xy -8.104 -0.143)
        (xy -8.063 -0.115)
        (xy -8.021 -0.117)
        (xy -7.994 -0.135)
        (xy -7.971 -0.176)
        (xy -7.976 -0.202)
        (xy -6.455 -0.202)
        (xy -6.449 -0.158)
        (xy -6.432 -0.135)
        (xy -6.392 -0.113)
        (xy -6.35 -0.121)
        (xy -6.322 -0.143)
        (xy -6.303 -0.169)
        (xy -6.304 -0.193)
        (xy -6.316 -0.218)
        (xy -6.35 -0.254)
        (xy -6.39 -0.265)
        (xy -6.429 -0.247)
        (xy -6.432 -0.244)
        (xy -6.455 -0.202)
        (xy -7.976 -0.202)
        (xy -7.979 -0.218)
        (xy -7.999 -0.244)
        (xy -8.04 -0.265)
        (xy -8.078 -0.255)
        (xy -8.11 -0.218)
        (xy -8.124 -0.186)
        (xy -8.228 -0.186)
        (xy -8.224 -0.232)
        (xy -8.192 -0.297)
        (xy -8.177 -0.317)
        (xy -8.121 -0.358)
        (xy -8.055 -0.374)
        (xy -7.988 -0.365)
        (xy -7.927 -0.333)
        (xy -7.885 -0.284)
        (xy -7.857 -0.237)
        (xy -7.26 -0.237)
        (xy -7.26 -0.489)
        (xy -7.586 -0.489)
        (xy -7.721 -0.615)
        (xy -7.779 -0.669)
        (xy -7.821 -0.704)
        (xy -7.852 -0.726)
        (xy -7.879 -0.737)
        (xy -7.908 -0.74)
        (xy -7.934 -0.741)
        (xy -8.011 -0.752)
        (xy -8.068 -0.787)
        (xy -8.105 -0.846)
        (xy -8.112 -0.866)
        (xy -8.119 -0.923)
        (xy -8.016 -0.923)
        (xy -8.003 -0.887)
        (xy -7.969 -0.862)
        (xy -7.928 -0.852)
        (xy -7.888 -0.861)
        (xy -7.878 -0.87)
        (xy -7.86 -0.907)
        (xy -7.866 -0.949)
        (xy -7.894 -0.984)
        (xy -7.924 -1.002)
        (xy -7.941 -1.008)
        (xy -7.964 -0.997)
        (xy -7.991 -0.969)
        (xy -8.011 -0.939)
        (xy -8.016 -0.923)
        (xy -8.119 -0.923)
        (xy -8.121 -0.94)
        (xy -8.105 -1.004)
        (xy -8.069 -1.055)
        (xy -8.018 -1.091)
        (xy -7.958 -1.108)
        (xy -7.894 -1.104)
        (xy -7.831 -1.076)
        (xy -7.787 -1.036)
        (xy -7.762 -1.001)
        (xy -7.751 -0.968)
        (xy -7.751 -0.923)
        (xy -7.753 -0.905)
        (xy -7.762 -0.824)
        (xy -7.648 -0.711)
        (xy -7.535 -0.599)
        (xy -7.26 -0.599)
        (xy -7.26 -0.971)
        (xy -7.323 -0.998)
        (xy -7.396 -1.046)
        (xy -7.446 -1.114)
        (xy -7.465 -1.166)
        (xy -7.472 -1.24)
        (xy -7.365 -1.24)
        (xy -7.359 -1.204)
        (xy -7.347 -1.177)
        (xy -7.307 -1.123)
        (xy -7.254 -1.093)
        (xy -7.194 -1.09)
        (xy -7.134 -1.116)
        (xy -7.127 -1.121)
        (xy -7.081 -1.171)
        (xy -7.065 -1.225)
        (xy -7.078 -1.283)
        (xy -7.116 -1.342)
        (xy -7.166 -1.375)
        (xy -7.222 -1.384)
        (xy -7.278 -1.368)
        (xy -7.326 -1.326)
        (xy -7.354 -1.278)
        (xy -7.365 -1.24)
        (xy -7.472 -1.24)
        (xy -7.474 -1.25)
        (xy -7.455 -1.328)
        (xy -7.416 -1.396)
        (xy -7.358 -1.449)
        (xy -7.288 -1.484)
        (xy -7.21 -1.495)
        (xy -7.128 -1.48)
      )

      (stroke (width 0.00186) (type solid)) (fill solid) (layer "F.Mask"))
  )

  (footprint "sdi-mipi-bridge-footprints:C_0402_1005Metric" (layer "F.Cu")
    (at 110.69 117.77 180)
    (descr "Capacitor SMD 0402")
    (tags "capacitor SMD 0402")
    (property "Author" "Antmicro")
    (property "Dielectric" "X7R")
    (property "License" "Apache-2.0")
    (property "MPN" "GRM155R71H103KA88D")
    (property "Manufacturer" "Murata")
    (property "Sheetfile" "sdi-mipi-bridge.kicad_sch")
    (property "Sheetname" "")
    (property "Val" "10n")
    (property "Voltage" "50V")
    (property "ki_description" " ")
    (attr smd)
    (fp_text reference "C22" (at -0.91 0.57) (layer "F.SilkS")
        (effects (font (size 0.65 0.65) (thickness 0.15)) (justify right bottom))
    )
    (fp_text value "C_10n_0402" (at 0 1.4) (layer "F.Fab") hide
        (effects (font (size 0.7 0.7) (thickness 0.15)) (justify right bottom))
    )
    (fp_text user "License: Apache-2.0" (at -0.932 5.17) (layer "F.Fab") hide
        (effects (font (size 0.7 0.7) (thickness 0.15)) (justify right bottom))
    )
    (fp_text user "Author: Antmicro" (at -0.932 4.17) (layer "F.Fab") hide
        (effects (font (size 0.7 0.7) (thickness 0.15)) (justify right bottom))
    )
    (fp_text user "${REFERENCE}" (at -0.932 3.168) (layer "F.Fab") hide
        (effects (font (size 0.7 0.7) (thickness 0.15)) (justify right bottom))
    )
    (fp_rect (start -0.94 -0.47) (end 0.94 0.47)
      (stroke (width 0.05) (type solid)) (fill none) (layer "F.CrtYd"))
    (fp_rect (start -0.499 -0.249) (end 0.499 0.249)
      (stroke (width 0.15) (type solid)) (fill none) (layer "F.Fab"))
    (pad "1" smd roundrect (at -0.484 0 180) (size 0.59 0.64) (layers "F.Cu" "F.Paste" "F.Mask") (roundrect_rratio 0.25)
      (net 3 "GNDA") (pintype "passive"))
    (pad "2" smd roundrect (at 0.484 0 180) (size 0.59 0.64) (layers "F.Cu" "F.Paste" "F.Mask") (roundrect_rratio 0.25)
      (net 57 "VDD") (pintype "passive"))
  )

  (footprint "sdi-mipi-bridge-footprints:Conn_BNC_031-70526-21" (layer "F.Cu")
    (at 91.128 126 -90)
    (property "Author" "Antmicro")
    (property "License" "Apache-2.0")
    (property "MPN" "031-70526-21")
    (property "Manufacturer" "Amphenol")
    (property "Sheetfile" "sdi-mipi-bridge.kicad_sch")
    (property "Sheetname" "")
    (property "ki_description" "RF / Coaxial Connector, BNC Coaxial, Straight Bulkhead Jack, Board Edge / End Launch, 75 ohm")
    (property "ki_keywords" "HORIZONTAL, BULKHEAD, RF, CONNECTOR")
    (attr smd)
    (fp_text reference "J1" (at 0 -13.5 -90 unlocked) (layer "F.SilkS")
        (effects (font (size 0.7 0.7) (thickness 0.15)) (justify left bottom))
    )
    (fp_text value "Conn_BNC_031-70526-21" (at 0 13.9 90) (layer "F.Fab") hide
        (effects (font (size 0.7 0.7) (thickness 0.15)) (justify right bottom))
    )
    (fp_text user "License: Apache-2.0" (at -8.2 16.1 90) (layer "F.Fab") hide
        (effects (font (size 0.7 0.7) (thickness 0.15)) (justify right bottom))
    )
    (fp_text user "${REFERENCE}" (at -8.2 17.3 90) (layer "F.Fab") hide
        (effects (font (size 0.7 0.7) (thickness 0.15)) (justify right bottom))
    )
    (fp_text user "Author: Antmicro" (at -8.2 14.9 90) (layer "F.Fab") hide
        (effects (font (size 0.7 0.7) (thickness 0.15)) (justify right bottom))
    )
    (fp_line (start -8.2 -5.5) (end -8.2 -4.6)
      (stroke (width 0.05) (type solid)) (layer "B.CrtYd"))
    (fp_line (start -8.2 -4.6) (end -7.4 -4.6)
      (stroke (width 0.05) (type solid)) (layer "B.CrtYd"))
    (fp_line (start -7.4 -4.6) (end -7.4 12.9)
      (stroke (width 0.05) (type solid)) (layer "B.CrtYd"))
    (fp_line (start -6.6 -6.6) (end -6.6 -5.5)
      (stroke (width 0.05) (type solid)) (layer "B.CrtYd"))
    (fp_line (start -6.6 -5.5) (end -8.2 -5.5)
      (stroke (width 0.05) (type solid)) (layer "B.CrtYd"))
    (fp_line (start -5.7 -13.6) (end -5.7 -6.6)
      (stroke (width 0.05) (type solid)) (layer "B.CrtYd"))
    (fp_line (start -5.7 -6.6) (end -6.6 -6.6)
      (stroke (width 0.05) (type solid)) (layer "B.CrtYd"))
    (fp_line (start -4.2 -13.6) (end -5.7 -13.6)
      (stroke (width 0.05) (type solid)) (layer "B.CrtYd"))
    (fp_line (start -4.2 -13.6) (end -4.2 -12.9)
      (stroke (width 0.05) (type solid)) (layer "B.CrtYd"))
    (fp_line (start 4.1 -13.6) (end 4.1 -12.9)
      (stroke (width 0.05) (type solid)) (layer "B.CrtYd"))
    (fp_line (start 4.1 -13.6) (end 5.6 -13.6)
      (stroke (width 0.05) (type solid)) (layer "B.CrtYd"))
    (fp_line (start 4.1 -12.9) (end -4.2 -12.9)
      (stroke (width 0.05) (type solid)) (layer "B.CrtYd"))
    (fp_line (start 5.6 -13.6) (end 5.6 -6.6)
      (stroke (width 0.05) (type solid)) (layer "B.CrtYd"))
    (fp_line (start 5.6 -6.6) (end 6.5 -6.6)
      (stroke (width 0.05) (type solid)) (layer "B.CrtYd"))
    (fp_line (start 6.5 -6.6) (end 6.5 -5.5)
      (stroke (width 0.05) (type solid)) (layer "B.CrtYd"))
    (fp_line (start 6.5 -5.5) (end 8.1 -5.5)
      (stroke (width 0.05) (type solid)) (layer "B.CrtYd"))
    (fp_line (start 7.3 -4.6) (end 7.3 12.9)
      (stroke (width 0.05) (type solid)) (layer "B.CrtYd"))
    (fp_line (start 7.3 12.9) (end -7.4 12.9)
      (stroke (width 0.05) (type solid)) (layer "B.CrtYd"))
    (fp_line (start 8.1 -5.5) (end 8.1 -4.6)
      (stroke (width 0.05) (type solid)) (layer "B.CrtYd"))
    (fp_line (start 8.1 -4.6) (end 7.3 -4.6)
      (stroke (width 0.05) (type solid)) (layer "B.CrtYd"))
    (fp_line (start -8.2 -5.5) (end -8.2 -4.6)
      (stroke (width 0.05) (type solid)) (layer "F.CrtYd"))
    (fp_line (start -8.2 -4.6) (end -7.4 -4.6)
      (stroke (width 0.05) (type solid)) (layer "F.CrtYd"))
    (fp_line (start -7.4 -4.6) (end -7.4 12.9)
      (stroke (width 0.05) (type solid)) (layer "F.CrtYd"))
    (fp_line (start -7.4 12.9) (end 7.3 12.9)
      (stroke (width 0.05) (type solid)) (layer "F.CrtYd"))
    (fp_line (start -6.6 -6.6) (end -6.6 -5.5)
      (stroke (width 0.05) (type solid)) (layer "F.CrtYd"))
    (fp_line (start -6.6 -5.5) (end -8.2 -5.5)
      (stroke (width 0.05) (type solid)) (layer "F.CrtYd"))
    (fp_line (start -5.7 -13.6) (end -5.7 -6.6)
      (stroke (width 0.05) (type solid)) (layer "F.CrtYd"))
    (fp_line (start -5.7 -6.6) (end -6.6 -6.6)
      (stroke (width 0.05) (type solid)) (layer "F.CrtYd"))
    (fp_line (start -4.2 -13.6) (end -5.7 -13.6)
      (stroke (width 0.05) (type solid)) (layer "F.CrtYd"))
    (fp_line (start -4.2 -13.6) (end -4.2 -12.9)
      (stroke (width 0.05) (type solid)) (layer "F.CrtYd"))
    (fp_line (start -4.2 -12.9) (end 4.1 -12.9)
      (stroke (width 0.05) (type solid)) (layer "F.CrtYd"))
    (fp_line (start 4.1 -13.6) (end 4.1 -12.9)
      (stroke (width 0.05) (type solid)) (layer "F.CrtYd"))
    (fp_line (start 4.1 -13.6) (end 5.6 -13.6)
      (stroke (width 0.05) (type solid)) (layer "F.CrtYd"))
    (fp_line (start 5.6 -13.6) (end 5.6 -6.6)
      (stroke (width 0.05) (type solid)) (layer "F.CrtYd"))
    (fp_line (start 5.6 -6.6) (end 6.5 -6.6)
      (stroke (width 0.05) (type solid)) (layer "F.CrtYd"))
    (fp_line (start 6.5 -6.6) (end 6.5 -5.5)
      (stroke (width 0.05) (type solid)) (layer "F.CrtYd"))
    (fp_line (start 6.5 -5.5) (end 8.1 -5.5)
      (stroke (width 0.05) (type solid)) (layer "F.CrtYd"))
    (fp_line (start 7.3 -4.6) (end 7.3 12.9)
      (stroke (width 0.05) (type solid)) (layer "F.CrtYd"))
    (fp_line (start 8.1 -5.5) (end 8.1 -4.6)
      (stroke (width 0.05) (type solid)) (layer "F.CrtYd"))
    (fp_line (start 8.1 -4.6) (end 7.3 -4.6)
      (stroke (width 0.05) (type solid)) (layer "F.CrtYd"))
    (pad "1" smd rect (at 0 -7.872 270) (size 1.1 1.75) (layers "F.Cu" "F.Paste" "F.Mask")
      (net 140 "Net-(C31-Pad2)") (pinfunction "1") (pintype "passive"))
    (pad "2" smd rect (at -4.851 -10.221 270) (size 1.1 6.45) (layers "F.Cu" "F.Paste" "F.Mask")
      (net 3 "GNDA") (pinfunction "2") (pintype "passive"))
    (pad "2" smd rect (at 4.849 -10.221 270) (size 1.1 6.45) (layers "F.Cu" "F.Paste" "F.Mask")
      (net 3 "GNDA") (pinfunction "2") (pintype "passive"))
  )

  (footprint "sdi-mipi-bridge-footprints:Conn_BNC_031-70526-21" (layer "F.Cu")
    (at 91.128 107 -90)
    (property "Author" "Antmicro")
    (property "License" "Apache-2.0")
    (property "MPN" "031-70526-21")
    (property "Manufacturer" "Amphenol")
    (property "Sheetfile" "sdi-mipi-bridge.kicad_sch")
    (property "Sheetname" "")
    (property "ki_description" "RF / Coaxial Connector, BNC Coaxial, Straight Bulkhead Jack, Board Edge / End Launch, 75 ohm")
    (property "ki_keywords" "HORIZONTAL, BULKHEAD, RF, CONNECTOR")
    (attr smd)
    (fp_text reference "J2" (at 0 -13.5 -90 unlocked) (layer "F.SilkS")
        (effects (font (size 0.7 0.7) (thickness 0.15)) (justify left bottom))
    )
    (fp_text value "Conn_BNC_031-70526-21" (at 0 13.9 90) (layer "F.Fab") hide
        (effects (font (size 0.7 0.7) (thickness 0.15)) (justify right bottom))
    )
    (fp_text user "${REFERENCE}" (at -8.2 17.3 90) (layer "F.Fab") hide
        (effects (font (size 0.7 0.7) (thickness 0.15)) (justify right bottom))
    )
    (fp_text user "Author: Antmicro" (at -8.2 14.9 90) (layer "F.Fab") hide
        (effects (font (size 0.7 0.7) (thickness 0.15)) (justify right bottom))
    )
    (fp_text user "License: Apache-2.0" (at -8.2 16.1 90) (layer "F.Fab") hide
        (effects (font (size 0.7 0.7) (thickness 0.15)) (justify right bottom))
    )
    (fp_line (start -8.2 -5.5) (end -8.2 -4.6)
      (stroke (width 0.05) (type solid)) (layer "B.CrtYd"))
    (fp_line (start -8.2 -4.6) (end -7.4 -4.6)
      (stroke (width 0.05) (type solid)) (layer "B.CrtYd"))
    (fp_line (start -7.4 -4.6) (end -7.4 12.9)
      (stroke (width 0.05) (type solid)) (layer "B.CrtYd"))
    (fp_line (start -6.6 -6.6) (end -6.6 -5.5)
      (stroke (width 0.05) (type solid)) (layer "B.CrtYd"))
    (fp_line (start -6.6 -5.5) (end -8.2 -5.5)
      (stroke (width 0.05) (type solid)) (layer "B.CrtYd"))
    (fp_line (start -5.7 -13.6) (end -5.7 -6.6)
      (stroke (width 0.05) (type solid)) (layer "B.CrtYd"))
    (fp_line (start -5.7 -6.6) (end -6.6 -6.6)
      (stroke (width 0.05) (type solid)) (layer "B.CrtYd"))
    (fp_line (start -4.2 -13.6) (end -5.7 -13.6)
      (stroke (width 0.05) (type solid)) (layer "B.CrtYd"))
    (fp_line (start -4.2 -13.6) (end -4.2 -12.9)
      (stroke (width 0.05) (type solid)) (layer "B.CrtYd"))
    (fp_line (start 4.1 -13.6) (end 4.1 -12.9)
      (stroke (width 0.05) (type solid)) (layer "B.CrtYd"))
    (fp_line (start 4.1 -13.6) (end 5.6 -13.6)
      (stroke (width 0.05) (type solid)) (layer "B.CrtYd"))
    (fp_line (start 4.1 -12.9) (end -4.2 -12.9)
      (stroke (width 0.05) (type solid)) (layer "B.CrtYd"))
    (fp_line (start 5.6 -13.6) (end 5.6 -6.6)
      (stroke (width 0.05) (type solid)) (layer "B.CrtYd"))
    (fp_line (start 5.6 -6.6) (end 6.5 -6.6)
      (stroke (width 0.05) (type solid)) (layer "B.CrtYd"))
    (fp_line (start 6.5 -6.6) (end 6.5 -5.5)
      (stroke (width 0.05) (type solid)) (layer "B.CrtYd"))
    (fp_line (start 6.5 -5.5) (end 8.1 -5.5)
      (stroke (width 0.05) (type solid)) (layer "B.CrtYd"))
    (fp_line (start 7.3 -4.6) (end 7.3 12.9)
      (stroke (width 0.05) (type solid)) (layer "B.CrtYd"))
    (fp_line (start 7.3 12.9) (end -7.4 12.9)
      (stroke (width 0.05) (type solid)) (layer "B.CrtYd"))
    (fp_line (start 8.1 -5.5) (end 8.1 -4.6)
      (stroke (width 0.05) (type solid)) (layer "B.CrtYd"))
    (fp_line (start 8.1 -4.6) (end 7.3 -4.6)
      (stroke (width 0.05) (type solid)) (layer "B.CrtYd"))
    (fp_line (start -8.2 -5.5) (end -8.2 -4.6)
      (stroke (width 0.05) (type solid)) (layer "F.CrtYd"))
    (fp_line (start -8.2 -4.6) (end -7.4 -4.6)
      (stroke (width 0.05) (type solid)) (layer "F.CrtYd"))
    (fp_line (start -7.4 -4.6) (end -7.4 12.9)
      (stroke (width 0.05) (type solid)) (layer "F.CrtYd"))
    (fp_line (start -7.4 12.9) (end 7.3 12.9)
      (stroke (width 0.05) (type solid)) (layer "F.CrtYd"))
    (fp_line (start -6.6 -6.6) (end -6.6 -5.5)
      (stroke (width 0.05) (type solid)) (layer "F.CrtYd"))
    (fp_line (start -6.6 -5.5) (end -8.2 -5.5)
      (stroke (width 0.05) (type solid)) (layer "F.CrtYd"))
    (fp_line (start -5.7 -13.6) (end -5.7 -6.6)
      (stroke (width 0.05) (type solid)) (layer "F.CrtYd"))
    (fp_line (start -5.7 -6.6) (end -6.6 -6.6)
      (stroke (width 0.05) (type solid)) (layer "F.CrtYd"))
    (fp_line (start -4.2 -13.6) (end -5.7 -13.6)
      (stroke (width 0.05) (type solid)) (layer "F.CrtYd"))
    (fp_line (start -4.2 -13.6) (end -4.2 -12.9)
      (stroke (width 0.05) (type solid)) (layer "F.CrtYd"))
    (fp_line (start -4.2 -12.9) (end 4.1 -12.9)
      (stroke (width 0.05) (type solid)) (layer "F.CrtYd"))
    (fp_line (start 4.1 -13.6) (end 4.1 -12.9)
      (stroke (width 0.05) (type solid)) (layer "F.CrtYd"))
    (fp_line (start 4.1 -13.6) (end 5.6 -13.6)
      (stroke (width 0.05) (type solid)) (layer "F.CrtYd"))
    (fp_line (start 5.6 -13.6) (end 5.6 -6.6)
      (stroke (width 0.05) (type solid)) (layer "F.CrtYd"))
    (fp_line (start 5.6 -6.6) (end 6.5 -6.6)
      (stroke (width 0.05) (type solid)) (layer "F.CrtYd"))
    (fp_line (start 6.5 -6.6) (end 6.5 -5.5)
      (stroke (width 0.05) (type solid)) (layer "F.CrtYd"))
    (fp_line (start 6.5 -5.5) (end 8.1 -5.5)
      (stroke (width 0.05) (type solid)) (layer "F.CrtYd"))
    (fp_line (start 7.3 -4.6) (end 7.3 12.9)
      (stroke (width 0.05) (type solid)) (layer "F.CrtYd"))
    (fp_line (start 8.1 -5.5) (end 8.1 -4.6)
      (stroke (width 0.05) (type solid)) (layer "F.CrtYd"))
    (fp_line (start 8.1 -4.6) (end 7.3 -4.6)
      (stroke (width 0.05) (type solid)) (layer "F.CrtYd"))
    (pad "1" smd rect (at 0 -7.872 270) (size 1.1 1.75) (layers "F.Cu" "F.Paste" "F.Mask")
      (net 69 "Net-(C43-Pad1)") (pinfunction "1") (pintype "passive"))
    (pad "2" smd rect (at -4.851 -10.221 270) (size 1.1 6.45) (layers "F.Cu" "F.Paste" "F.Mask")
      (net 3 "GNDA") (pinfunction "2") (pintype "passive"))
    (pad "2" smd rect (at 4.849 -10.221 270) (size 1.1 6.45) (layers "F.Cu" "F.Paste" "F.Mask")
      (net 3 "GNDA") (pinfunction "2") (pintype "passive"))
  )

  (footprint "sdi-mipi-bridge-footprints:TDFN-8-1EP_2x2mm_P0.5mm" (layer "F.Cu")
    (at 129.6 133.303)
    (property "Author" "Antmicro")
    (property "License" "Apache-2.0")
    (property "MPN" "MAX8902B")
    (property "Manufacturer" "Maxim Integrated Products")
    (property "Sheetfile" "sdi-mipi-bridge.kicad_sch")
    (property "Sheetname" "")
    (property "ki_description" "LDO Voltage Regulator, Adjustable, 1.7V to 5.5V input, 150 mV drop., 0.6-5.3V/0.5A out, TDFN-8")
    (property "ki_keywords" "IC")
    (attr smd)
    (fp_text reference "U1" (at -1.6 2.9) (layer "F.SilkS")
        (effects (font (size 0.7 0.7) (thickness 0.15)) (justify left bottom))
    )
    (fp_text value "MAX8902B" (at 0.049 -2.053) (layer "F.Fab") hide
        (effects (font (size 0.7 0.7) (thickness 0.15)) (justify left bottom))
    )
    (fp_text user "." (at -1.9 -1.2 unlocked) (layer "F.SilkS") hide
        (effects (font (size 0.7 0.7) (thickness 0.15)) (justify left bottom))
    )
    (fp_text user "Author: Antmicro" (at -1.6 4.9) (layer "F.Fab") hide
        (effects (font (size 0.7 0.7) (thickness 0.15)) (justify left bottom))
    )
    (fp_text user "License: Apache-2.0" (at -1.6 7.3) (layer "F.Fab") hide
        (effects (font (size 0.7 0.7) (thickness 0.15)) (justify left bottom))
    )
    (fp_text user "${REFERENCE}" (at -1.6 6.1) (layer "F.Fab") hide
        (effects (font (size 0.7 0.7) (thickness 0.15)) (justify left bottom))
    )
    (fp_line (start -0.6 1.05) (end 0.499 1.05)
      (stroke (width 0.15) (type solid)) (layer "F.SilkS"))
    (fp_line (start 0.499 -1.051) (end -1 -1.051)
      (stroke (width 0.15) (type solid)) (layer "F.SilkS"))
    (fp_rect (start -1.6 -1.5) (end 1.6 1.498)
      (stroke (width 0.05) (type solid)) (fill none) (layer "F.CrtYd"))
    (fp_line (start -1 -0.6) (end -0.6 -1)
      (stroke (width 0.15) (type solid)) (layer "F.Fab"))
    (fp_line (start -1 1) (end -1 -0.6)
      (stroke (width 0.15) (type solid)) (layer "F.Fab"))
    (fp_line (start -0.6 -1) (end 1 -1)
      (stroke (width 0.15) (type solid)) (layer "F.Fab"))
    (fp_line (start 1 -1) (end 1 1)
      (stroke (width 0.15) (type solid)) (layer "F.Fab"))
    (fp_line (start 1 1) (end -1 1)
      (stroke (width 0.15) (type solid)) (layer "F.Fab"))
    (pad "1" smd roundrect (at -0.926 -0.75) (size 0.7 0.25) (layers "F.Cu" "F.Paste" "F.Mask") (roundrect_rratio 0.25)
      (net 6 "+3V3") (pinfunction "IN") (pintype "input"))
    (pad "2" smd roundrect (at -0.926 -0.252) (size 0.7 0.25) (layers "F.Cu" "F.Paste" "F.Mask") (roundrect_rratio 0.25)
      (net 1 "GNDREF") (pinfunction "GND") (pintype "power_in"))
    (pad "3" smd roundrect (at -0.926 0.246) (size 0.7 0.25) (layers "F.Cu" "F.Paste" "F.Mask") (roundrect_rratio 0.25)
      (net 6 "+3V3") (pinfunction "EN") (pintype "input"))
    (pad "4" smd roundrect (at -0.926 0.748) (size 0.7 0.25) (layers "F.Cu" "F.Paste" "F.Mask") (roundrect_rratio 0.25)
      (net 1 "GNDREF") (pinfunction "GS") (pintype "input"))
    (pad "5" smd roundrect (at 0.925 0.748) (size 0.7 0.25) (layers "F.Cu" "F.Paste" "F.Mask") (roundrect_rratio 0.25)
      (net 129 "Net-(U1-~{POK})") (pinfunction "~{POK}") (pintype "output"))
    (pad "6" smd roundrect (at 0.925 0.246) (size 0.7 0.25) (layers "F.Cu" "F.Paste" "F.Mask") (roundrect_rratio 0.25)
      (net 71 "Net-(U1-FB)") (pinfunction "FB") (pintype "input"))
    (pad "7" smd roundrect (at 0.925 -0.252) (size 0.7 0.25) (layers "F.Cu" "F.Paste" "F.Mask") (roundrect_rratio 0.25)
      (net 25 "Net-(U1-BYP)") (pinfunction "BYP") (pintype "input"))
    (pad "8" smd roundrect (at 0.925 -0.75) (size 0.7 0.25) (layers "F.Cu" "F.Paste" "F.Mask") (roundrect_rratio 0.25)
      (net 2 "+1V2") (pinfunction "OUT") (pintype "output"))
    (pad "9" smd roundrect (at 0 -0.003) (size 0.64 1.37) (layers "F.Cu" "F.Paste" "F.Mask") (roundrect_rratio 0.25)
      (net 1 "GNDREF") (pinfunction "EP") (pintype "passive") (zone_connect 0))
  )

  (footprint "sdi-mipi-bridge-footprints:R_0402_1005Metric" (layer "F.Cu")
    (at 130 107.4 90)
    (descr "Resistor SMD 0402")
    (tags "resistor SMD 0402")
    (property "Author" "Antmicro")
    (property "Current" "1A")
    (property "License" "Apache-2.0")
    (property "MPN" "ERJ2GE0R00X")
    (property "Manufacturer" "Panasonic")
    (property "Sheetfile" "sdi-mipi-bridge.kicad_sch")
    (property "Sheetname" "")
    (property "Tolerance" "")
    (property "Val" "0R")
    (property "ki_description" "0R resistor in 0402 package with unspecified tolerance")
    (attr smd)
    (fp_text reference "R31" (at -0.9 3.3 90) (layer "F.SilkS")
        (effects (font (size 0.65 0.65) (thickness 0.15)) (justify left bottom))
    )
    (fp_text value "R_0R_0402" (at 0 1.4 90) (layer "F.Fab") hide
        (effects (font (size 0.7 0.7) (thickness 0.15)) (justify left bottom))
    )
    (fp_text user "Author: Antmicro" (at -0.95 4.169 90) (layer "F.Fab") hide
        (effects (font (size 0.7 0.7) (thickness 0.15)) (justify left bottom))
    )
    (fp_text user "License: Apache-2.0" (at -0.95 5.169 90) (layer "F.Fab") hide
        (effects (font (size 0.7 0.7) (thickness 0.15)) (justify left bottom))
    )
    (fp_text user "${REFERENCE}" (at -0.95 3.168 90) (layer "F.Fab") hide
        (effects (font (size 0.7 0.7) (thickness 0.15)) (justify left bottom))
    )
    (fp_rect (start -0.93 -0.47) (end 0.93 0.47)
      (stroke (width 0.05) (type solid)) (fill none) (layer "F.CrtYd"))
    (fp_rect (start -0.5 -0.25) (end 0.5 0.25)
      (stroke (width 0.15) (type solid)) (fill none) (layer "F.Fab"))
    (pad "1" smd roundrect (at -0.485 0 90) (size 0.59 0.64) (layers "F.Cu" "F.Paste" "F.Mask") (roundrect_rratio 0.25)
      (net 20 "/LOCKED") (pintype "passive"))
    (pad "2" smd roundrect (at 0.485 0 90) (size 0.59 0.64) (layers "F.Cu" "F.Paste" "F.Mask") (roundrect_rratio 0.25)
      (net 87 "/LOCKED_CL") (pintype "passive"))
  )

  (footprint "sdi-mipi-bridge-footprints:WE_68715014522_ONE-SIDE" (layer "F.Cu")
    (at 164.6 116.7 90)
    (property "Author" "Antmicro")
    (property "License" "Apache-2.0")
    (property "MPN" "68715014522")
    (property "Manufacturer" "Würth Elektronik")
    (property "Sheetfile" "sdi-mipi-bridge.kicad_sch")
    (property "Sheetname" "")
    (attr smd)
    (fp_text reference "J3" (at 0 -3.4 90) (layer "F.SilkS")
        (effects (font (size 0.65 0.65) (thickness 0.15)) (justify left bottom))
    )
    (fp_text value "Conn_FFC_68715014522_ONE-SIDE" (at 0 4.499 90) (layer "F.Fab") hide
        (effects (font (size 0.7 0.7) (thickness 0.15)) (justify left bottom))
    )
    (fp_text user "${REFERENCE}" (at -16.2 8.9 90) (layer "F.Fab")
        (effects (font (size 0.7 0.7) (thickness 0.15)) (justify left bottom))
    )
    (fp_text user "Author: Antmicro" (at -16.2 6.499 90) (layer "F.Fab")
        (effects (font (size 0.7 0.7) (thickness 0.15)) (justify left bottom))
    )
    (fp_text user "License: Apache-2.0" (at -16.2 7.7 90) (layer "F.Fab")
        (effects (font (size 0.7 0.7) (thickness 0.15)) (justify left bottom))
    )
    (fp_line (start -15.85 -2.15) (end -12.5 -2.15)
      (stroke (width 0.15) (type solid)) (layer "F.SilkS"))
    (fp_line (start -15.85 2.7) (end -15.85 -2.15)
      (stroke (width 0.15) (type solid)) (layer "F.SilkS"))
    (fp_line (start -12.5 -2.976) (end 12.499 -2.976)
      (stroke (width 0.15) (type solid)) (layer "F.SilkS"))
    (fp_line (start -12.5 -2.15) (end -12.5 -2.976)
      (stroke (width 0.15) (type solid)) (layer "F.SilkS"))
    (fp_line (start 12.499 -2.15) (end 12.499 -2.976)
      (stroke (width 0.15) (type solid)) (layer "F.SilkS"))
    (fp_line (start 15.849 -2.15) (end 12.499 -2.15)
      (stroke (width 0.15) (type solid)) (layer "F.SilkS"))
    (fp_line (start 15.849 2.7) (end -15.85 2.7)
      (stroke (width 0.15) (type solid)) (layer "F.SilkS"))
    (fp_line (start 15.849 2.7) (end 15.849 -2.15)
      (stroke (width 0.15) (type solid)) (layer "F.SilkS"))
    (fp_circle (center -12.901 -2.9) (end -12.85 -2.851)
      (stroke (width 0.15) (type solid)) (fill solid) (layer "F.SilkS"))
    (fp_rect (start -16.2 -3.25) (end 16.19 3.55)
      (stroke (width 0.05) (type solid)) (fill none) (layer "F.CrtYd"))
    (pad "1" smd roundrect (at -12.25 -2.15 90) (size 0.3 1.2) (layers "F.Cu" "F.Paste" "F.Mask") (roundrect_rratio 0.25)
      (net 143 "/MIPI0_D3_N") (pintype "passive"))
    (pad "2" smd roundrect (at -11.75 -2.15 90) (size 0.3 1.2) (layers "F.Cu" "F.Paste" "F.Mask") (roundrect_rratio 0.25)
      (net 144 "/MIPI0_D3_P") (pintype "passive"))
    (pad "3" smd roundrect (at -11.25 -2.15 90) (size 0.3 1.2) (layers "F.Cu" "F.Paste" "F.Mask") (roundrect_rratio 0.25)
      (net 145 "/MIPI0_D2_N") (pintype "passive"))
    (pad "4" smd roundrect (at -10.75 -2.15 90) (size 0.3 1.2) (layers "F.Cu" "F.Paste" "F.Mask") (roundrect_rratio 0.25)
      (net 146 "/MIPI0_D2_P") (pintype "passive"))
    (pad "5" smd roundrect (at -10.25 -2.15 90) (size 0.3 1.2) (layers "F.Cu" "F.Paste" "F.Mask") (roundrect_rratio 0.25)
      (net 147 "/MIPI0_D1_N") (pintype "passive"))
    (pad "6" smd roundrect (at -9.75 -2.15 90) (size 0.3 1.2) (layers "F.Cu" "F.Paste" "F.Mask") (roundrect_rratio 0.25)
      (net 148 "/MIPI0_D1_P") (pintype "passive"))
    (pad "7" smd roundrect (at -9.25 -2.15 90) (size 0.3 1.2) (layers "F.Cu" "F.Paste" "F.Mask") (roundrect_rratio 0.25)
      (net 149 "/MIPI0_D0_N") (pintype "passive"))
    (pad "8" smd roundrect (at -8.75 -2.15 90) (size 0.3 1.2) (layers "F.Cu" "F.Paste" "F.Mask") (roundrect_rratio 0.25)
      (net 150 "/MIPI0_D0_P") (pintype "passive"))
    (pad "9" smd roundrect (at -8.25 -2.15 90) (size 0.3 1.2) (layers "F.Cu" "F.Paste" "F.Mask") (roundrect_rratio 0.25)
      (net 1 "GNDREF") (pintype "passive"))
    (pad "10" smd roundrect (at -7.75 -2.15 90) (size 0.3 1.2) (layers "F.Cu" "F.Paste" "F.Mask") (roundrect_rratio 0.25)
      (net 151 "/MIPI0_CLK_N") (pintype "passive"))
    (pad "11" smd roundrect (at -7.25 -2.15 90) (size 0.3 1.2) (layers "F.Cu" "F.Paste" "F.Mask") (roundrect_rratio 0.25)
      (net 152 "/MIPI0_CLK_P") (pintype "passive"))
    (pad "12" smd roundrect (at -6.75 -2.15 90) (size 0.3 1.2) (layers "F.Cu" "F.Paste" "F.Mask") (roundrect_rratio 0.25)
      (net 1 "GNDREF") (pintype "passive"))
    (pad "13" smd roundrect (at -6.25 -2.15 90) (size 0.3 1.2) (layers "F.Cu" "F.Paste" "F.Mask") (roundrect_rratio 0.25)
      (net 48 "unconnected-(J3-Pad13)") (pintype "passive+no_connect"))
    (pad "14" smd roundrect (at -5.75 -2.15 90) (size 0.3 1.2) (layers "F.Cu" "F.Paste" "F.Mask") (roundrect_rratio 0.25)
      (net 107 "unconnected-(J3-Pad14)") (pintype "passive+no_connect"))
    (pad "15" smd roundrect (at -5.25 -2.15 90) (size 0.3 1.2) (layers "F.Cu" "F.Paste" "F.Mask") (roundrect_rratio 0.25)
      (net 1 "GNDREF") (pintype "passive"))
    (pad "16" smd roundrect (at -4.75 -2.15 90) (size 0.3 1.2) (layers "F.Cu" "F.Paste" "F.Mask") (roundrect_rratio 0.25)
      (net 108 "unconnected-(J3-Pad16)") (pintype "passive+no_connect"))
    (pad "17" smd roundrect (at -4.25 -2.15 90) (size 0.3 1.2) (layers "F.Cu" "F.Paste" "F.Mask") (roundrect_rratio 0.25)
      (net 109 "unconnected-(J3-Pad17)") (pintype "passive+no_connect"))
    (pad "18" smd roundrect (at -3.75 -2.15 90) (size 0.3 1.2) (layers "F.Cu" "F.Paste" "F.Mask") (roundrect_rratio 0.25)
      (net 1 "GNDREF") (pintype "passive"))
    (pad "19" smd roundrect (at -3.25 -2.15 90) (size 0.3 1.2) (layers "F.Cu" "F.Paste" "F.Mask") (roundrect_rratio 0.25)
      (net 153 "/MIPI1_D3_N") (pintype "passive"))
    (pad "20" smd roundrect (at -2.75 -2.15 90) (size 0.3 1.2) (layers "F.Cu" "F.Paste" "F.Mask") (roundrect_rratio 0.25)
      (net 154 "/MIPI1_D3_P") (pintype "passive"))
    (pad "21" smd roundrect (at -2.25 -2.15 90) (size 0.3 1.2) (layers "F.Cu" "F.Paste" "F.Mask") (roundrect_rratio 0.25)
      (net 155 "/MIPI1_D2_N") (pintype "passive"))
    (pad "22" smd roundrect (at -1.75 -2.15 90) (size 0.3 1.2) (layers "F.Cu" "F.Paste" "F.Mask") (roundrect_rratio 0.25)
      (net 156 "/MIPI1_D2_P") (pintype "passive"))
    (pad "23" smd roundrect (at -1.25 -2.15 90) (size 0.3 1.2) (layers "F.Cu" "F.Paste" "F.Mask") (roundrect_rratio 0.25)
      (net 157 "/MIPI1_D1_N") (pintype "passive"))
    (pad "24" smd roundrect (at -0.75 -2.15 90) (size 0.3 1.2) (layers "F.Cu" "F.Paste" "F.Mask") (roundrect_rratio 0.25)
      (net 158 "/MIPI1_D1_P") (pintype "passive"))
    (pad "25" smd roundrect (at -0.25 -2.15 90) (size 0.3 1.2) (layers "F.Cu" "F.Paste" "F.Mask") (roundrect_rratio 0.25)
      (net 159 "/MIPI1_D0_N") (pintype "passive"))
    (pad "26" smd roundrect (at 0.247 -2.15 90) (size 0.3 1.2) (layers "F.Cu" "F.Paste" "F.Mask") (roundrect_rratio 0.25)
      (net 160 "/MIPI1_D0_P") (pintype "passive"))
    (pad "27" smd roundrect (at 0.747 -2.15 90) (size 0.3 1.2) (layers "F.Cu" "F.Paste" "F.Mask") (roundrect_rratio 0.25)
      (net 1 "GNDREF") (pintype "passive"))
    (pad "28" smd roundrect (at 1.249 -2.15 90) (size 0.3 1.2) (layers "F.Cu" "F.Paste" "F.Mask") (roundrect_rratio 0.25)
      (net 161 "/MIPI1_CLK_N") (pintype "passive"))
    (pad "29" smd roundrect (at 1.749 -2.15 90) (size 0.3 1.2) (layers "F.Cu" "F.Paste" "F.Mask") (roundrect_rratio 0.25)
      (net 162 "/MIPI1_CLK_P") (pintype "passive"))
    (pad "30" smd roundrect (at 2.249 -2.15 90) (size 0.3 1.2) (layers "F.Cu" "F.Paste" "F.Mask") (roundrect_rratio 0.25)
      (net 1 "GNDREF") (pintype "passive"))
    (pad "31" smd roundrect (at 2.749 -2.15 90) (size 0.3 1.2) (layers "F.Cu" "F.Paste" "F.Mask") (roundrect_rratio 0.25)
      (net 110 "unconnected-(J3-Pad31)") (pintype "passive+no_connect"))
    (pad "32" smd roundrect (at 3.249 -2.15 90) (size 0.3 1.2) (layers "F.Cu" "F.Paste" "F.Mask") (roundrect_rratio 0.25)
      (net 111 "unconnected-(J3-Pad32)") (pintype "passive+no_connect"))
    (pad "33" smd roundrect (at 3.749 -2.15 90) (size 0.3 1.2) (layers "F.Cu" "F.Paste" "F.Mask") (roundrect_rratio 0.25)
      (net 113 "/RST") (pintype "passive+no_connect"))
    (pad "34" smd roundrect (at 4.248 -2.15 90) (size 0.3 1.2) (layers "F.Cu" "F.Paste" "F.Mask") (roundrect_rratio 0.25)
      (net 112 "unconnected-(J3-Pad34)") (pintype "passive+no_connect"))
    (pad "35" smd roundrect (at 4.748 -2.15 90) (size 0.3 1.2) (layers "F.Cu" "F.Paste" "F.Mask") (roundrect_rratio 0.25)
      (net 114 "unconnected-(J3-Pad35)") (pintype "passive+no_connect"))
    (pad "36" smd roundrect (at 5.248 -2.15 90) (size 0.3 1.2) (layers "F.Cu" "F.Paste" "F.Mask") (roundrect_rratio 0.25)
      (net 115 "unconnected-(J3-Pad36)") (pintype "passive+no_connect"))
    (pad "37" smd roundrect (at 5.749 -2.15 90) (size 0.3 1.2) (layers "F.Cu" "F.Paste" "F.Mask") (roundrect_rratio 0.25)
      (net 116 "unconnected-(J3-Pad37)") (pintype "passive+no_connect"))
    (pad "38" smd roundrect (at 6.249 -2.15 90) (size 0.3 1.2) (layers "F.Cu" "F.Paste" "F.Mask") (roundrect_rratio 0.25)
      (net 117 "unconnected-(J3-Pad38)") (pintype "passive+no_connect"))
    (pad "39" smd roundrect (at 6.749 -2.15 90) (size 0.3 1.2) (layers "F.Cu" "F.Paste" "F.Mask") (roundrect_rratio 0.25)
      (net 83 "/SDA1") (pintype "passive"))
    (pad "40" smd roundrect (at 7.249 -2.15 90) (size 0.3 1.2) (layers "F.Cu" "F.Paste" "F.Mask") (roundrect_rratio 0.25)
      (net 82 "/SCL1") (pintype "passive"))
    (pad "41" smd roundrect (at 7.749 -2.15 90) (size 0.3 1.2) (layers "F.Cu" "F.Paste" "F.Mask") (roundrect_rratio 0.25)
      (net 81 "/SDA2") (pintype "passive"))
    (pad "42" smd roundrect (at 8.249 -2.15 90) (size 0.3 1.2) (layers "F.Cu" "F.Paste" "F.Mask") (roundrect_rratio 0.25)
      (net 80 "/SCL2") (pintype "passive"))
    (pad "43" smd roundrect (at 8.749 -2.15 90) (size 0.3 1.2) (layers "F.Cu" "F.Paste" "F.Mask") (roundrect_rratio 0.25)
      (net 118 "unconnected-(J3-Pad43)") (pintype "passive+no_connect"))
    (pad "44" smd roundrect (at 9.249 -2.15 90) (size 0.3 1.2) (layers "F.Cu" "F.Paste" "F.Mask") (roundrect_rratio 0.25)
      (net 119 "unconnected-(J3-Pad44)") (pintype "passive+no_connect"))
    (pad "45" smd roundrect (at 9.749 -2.15 90) (size 0.3 1.2) (layers "F.Cu" "F.Paste" "F.Mask") (roundrect_rratio 0.25)
      (net 120 "unconnected-(J3-Pad45)") (pintype "passive+no_connect"))
    (pad "46" smd roundrect (at 10.249 -2.15 90) (size 0.3 1.2) (layers "F.Cu" "F.Paste" "F.Mask") (roundrect_rratio 0.25)
      (net 121 "unconnected-(J3-Pad46)") (pintype "passive+no_connect"))
    (pad "47" smd roundrect (at 10.749 -2.15 90) (size 0.3 1.2) (layers "F.Cu" "F.Paste" "F.Mask") (roundrect_rratio 0.25)
      (net 136 "Net-(J3-Pad47)") (pintype "passive"))
    (pad "48" smd roundrect (at 11.249 -2.15 90) (size 0.3 1.2) (layers "F.Cu" "F.Paste" "F.Mask") (roundrect_rratio 0.25)
      (net 136 "Net-(J3-Pad47)") (pintype "passive"))
    (pad "49" smd roundrect (at 11.749 -2.15 90) (size 0.3 1.2) (layers "F.Cu" "F.Paste" "F.Mask") (roundrect_rratio 0.25)
      (net 122 "unconnected-(J3-Pad49)") (pintype "passive+no_connect"))
    (pad "50" smd roundrect (at 12.249 -2.15 90) (size 0.3 1.2) (layers "F.Cu" "F.Paste" "F.Mask") (roundrect_rratio 0.25)
      (net 123 "unconnected-(J3-Pad50)") (pintype "passive+no_connect"))
    (pad "SH" smd roundrect (at -14.199 -0.3 90) (size 2.7 3) (layers "F.Cu" "F.Paste" "F.Mask") (roundrect_rratio 0.05)
      (net 1 "GNDREF") (pintype "passive"))
    (pad "SH" smd roundrect (at 14.198 -0.3 90) (size 2.7 3) (layers "F.Cu" "F.Paste" "F.Mask") (roundrect_rratio 0.05)
      (net 1 "GNDREF") (pintype "passive"))
  )

  (footprint "sdi-mipi-bridge-footprints:R_0402_1005Metric" (layer "F.Cu")
    (at 156.945 111.3 180)
    (descr "Resistor SMD 0402")
    (tags "resistor SMD 0402")
    (property "Author" "Antmicro")
    (property "Current" "1A")
    (property "License" "Apache-2.0")
    (property "MPN" "ERJ2GE0R00X")
    (property "Manufacturer" "Panasonic")
    (property "Sheetfile" "sdi-mipi-bridge.kicad_sch")
    (property "Sheetname" "")
    (property "Tolerance" "")
    (property "Val" "0R")
    (property "ki_description" "0R resistor in 0402 package with unspecified tolerance")
    (attr smd)
    (fp_text reference "R38" (at -2.955 -0.4) (layer "F.SilkS")
        (effects (font (size 0.65 0.65) (thickness 0.15)) (justify right bottom))
    )
    (fp_text value "R_0R_0402" (at 0 1.4) (layer "F.Fab") hide
        (effects (font (size 0.7 0.7) (thickness 0.15)) (justify right bottom))
    )
    (fp_text user "License: Apache-2.0" (at -0.95 5.169) (layer "F.Fab") hide
        (effects (font (size 0.7 0.7) (thickness 0.15)) (justify right bottom))
    )
    (fp_text user "Author: Antmicro" (at -0.95 4.169) (layer "F.Fab") hide
        (effects (font (size 0.7 0.7) (thickness 0.15)) (justify right bottom))
    )
    (fp_text user "${REFERENCE}" (at -0.95 3.168) (layer "F.Fab") hide
        (effects (font (size 0.7 0.7) (thickness 0.15)) (justify right bottom))
    )
    (fp_rect (start -0.93 -0.47) (end 0.93 0.47)
      (stroke (width 0.05) (type solid)) (fill none) (layer "F.CrtYd"))
    (fp_rect (start -0.5 -0.25) (end 0.5 0.25)
      (stroke (width 0.15) (type solid)) (fill none) (layer "F.Fab"))
    (pad "1" smd roundrect (at -0.485 0 180) (size 0.59 0.64) (layers "F.Cu" "F.Paste" "F.Mask") (roundrect_rratio 0.25)
      (net 82 "/SCL1") (pintype "passive"))
    (pad "2" smd roundrect (at 0.485 0 180) (size 0.59 0.64) (layers "F.Cu" "F.Paste" "F.Mask") (roundrect_rratio 0.25)
      (net 99 "/SPI_SS(SCL)") (pintype "passive"))
  )

  (footprint "sdi-mipi-bridge-footprints:R_0402_1005Metric" (layer "F.Cu")
    (at 156.945 110.1 180)
    (descr "Resistor SMD 0402")
    (tags "resistor SMD 0402")
    (property "Author" "Antmicro")
    (property "Current" "1A")
    (property "License" "Apache-2.0")
    (property "MPN" "ERJ2GE0R00X")
    (property "Manufacturer" "Panasonic")
    (property "Sheetfile" "sdi-mipi-bridge.kicad_sch")
    (property "Sheetname" "")
    (property "Tolerance" "")
    (property "Val" "0R")
    (property "ki_description" "0R resistor in 0402 package with unspecified tolerance")
    (attr smd)
    (fp_text reference "R40" (at -2.955 -0.4) (layer "F.SilkS")
        (effects (font (size 0.65 0.65) (thickness 0.15)) (justify right bottom))
    )
    (fp_text value "R_0R_0402" (at 0 1.4) (layer "F.Fab") hide
        (effects (font (size 0.7 0.7) (thickness 0.15)) (justify right bottom))
    )
    (fp_text user "${REFERENCE}" (at -0.95 3.168) (layer "F.Fab") hide
        (effects (font (size 0.7 0.7) (thickness 0.15)) (justify right bottom))
    )
    (fp_text user "License: Apache-2.0" (at -0.95 5.169) (layer "F.Fab") hide
        (effects (font (size 0.7 0.7) (thickness 0.15)) (justify right bottom))
    )
    (fp_text user "Author: Antmicro" (at -0.95 4.169) (layer "F.Fab") hide
        (effects (font (size 0.7 0.7) (thickness 0.15)) (justify right bottom))
    )
    (fp_rect (start -0.93 -0.47) (end 0.93 0.47)
      (stroke (width 0.05) (type solid)) (fill none) (layer "F.CrtYd"))
    (fp_rect (start -0.5 -0.25) (end 0.5 0.25)
      (stroke (width 0.15) (type solid)) (fill none) (layer "F.Fab"))
    (pad "1" smd roundrect (at -0.485 0 180) (size 0.59 0.64) (layers "F.Cu" "F.Paste" "F.Mask") (roundrect_rratio 0.25)
      (net 82 "/SCL1") (pintype "passive"))
    (pad "2" smd roundrect (at 0.485 0 180) (size 0.59 0.64) (layers "F.Cu" "F.Paste" "F.Mask") (roundrect_rratio 0.25)
      (net 61 "/SCL_GS") (pintype "passive"))
  )

  (footprint "sdi-mipi-bridge-footprints:R_0402_1005Metric" (layer "F.Cu")
    (at 156.945 107.7 180)
    (descr "Resistor SMD 0402")
    (tags "resistor SMD 0402")
    (property "Author" "Antmicro")
    (property "Current" "1A")
    (property "DNP" "DNP")
    (property "License" "Apache-2.0")
    (property "MPN" "ERJ2GE0R00X")
    (property "Manufacturer" "Panasonic")
    (property "Sheetfile" "sdi-mipi-bridge.kicad_sch")
    (property "Sheetname" "")
    (property "Tolerance" "")
    (property "Val" "0R")
    (property "ki_description" "0R resistor in 0402 package with unspecified tolerance")
    (attr exclude_from_pos_files)
    (fp_text reference "R42" (at -2.955 -0.4) (layer "F.SilkS")
        (effects (font (size 0.65 0.65) (thickness 0.15)) (justify right bottom))
    )
    (fp_text value "R_0R_0402" (at 0 1.4) (layer "F.Fab") hide
        (effects (font (size 0.7 0.7) (thickness 0.15)) (justify right bottom))
    )
    (fp_text user "License: Apache-2.0" (at -0.95 5.169) (layer "F.Fab") hide
        (effects (font (size 0.7 0.7) (thickness 0.15)) (justify right bottom))
    )
    (fp_text user "${REFERENCE}" (at -0.95 3.168) (layer "F.Fab") hide
        (effects (font (size 0.7 0.7) (thickness 0.15)) (justify right bottom))
    )
    (fp_text user "Author: Antmicro" (at -0.95 4.169) (layer "F.Fab") hide
        (effects (font (size 0.7 0.7) (thickness 0.15)) (justify right bottom))
    )
    (fp_rect (start -0.93 -0.47) (end 0.93 0.47)
      (stroke (width 0.05) (type solid)) (fill none) (layer "F.CrtYd"))
    (fp_rect (start -0.5 -0.25) (end 0.5 0.25)
      (stroke (width 0.15) (type solid)) (fill none) (layer "F.Fab"))
    (pad "1" smd roundrect (at -0.485 0 180) (size 0.59 0.64) (layers "F.Cu" "F.Paste" "F.Mask") (roundrect_rratio 0.25)
      (net 80 "/SCL2") (pintype "passive"))
    (pad "2" smd roundrect (at 0.485 0 180) (size 0.59 0.64) (layers "F.Cu" "F.Paste" "F.Mask") (roundrect_rratio 0.25)
      (net 99 "/SPI_SS(SCL)") (pintype "passive"))
  )

  (footprint "sdi-mipi-bridge-footprints:R_0402_1005Metric" (layer "F.Cu")
    (at 156.945 113.7 180)
    (descr "Resistor SMD 0402")
    (tags "resistor SMD 0402")
    (property "Author" "Antmicro")
    (property "Current" "1A")
    (property "License" "Apache-2.0")
    (property "MPN" "ERJ2GE0R00X")
    (property "Manufacturer" "Panasonic")
    (property "Sheetfile" "sdi-mipi-bridge.kicad_sch")
    (property "Sheetname" "")
    (property "Tolerance" "")
    (property "Val" "0R")
    (property "ki_description" "0R resistor in 0402 package with unspecified tolerance")
    (attr smd)
    (fp_text reference "R37" (at -2.955 -0.4) (layer "F.SilkS")
        (effects (font (size 0.65 0.65) (thickness 0.15)) (justify right bottom))
    )
    (fp_text value "R_0R_0402" (at 0 1.4) (layer "F.Fab") hide
        (effects (font (size 0.7 0.7) (thickness 0.15)) (justify right bottom))
    )
    (fp_text user "Author: Antmicro" (at -0.95 4.169) (layer "F.Fab") hide
        (effects (font (size 0.7 0.7) (thickness 0.15)) (justify right bottom))
    )
    (fp_text user "${REFERENCE}" (at -0.95 3.168) (layer "F.Fab") hide
        (effects (font (size 0.7 0.7) (thickness 0.15)) (justify right bottom))
    )
    (fp_text user "License: Apache-2.0" (at -0.95 5.169) (layer "F.Fab") hide
        (effects (font (size 0.7 0.7) (thickness 0.15)) (justify right bottom))
    )
    (fp_rect (start -0.93 -0.47) (end 0.93 0.47)
      (stroke (width 0.05) (type solid)) (fill none) (layer "F.CrtYd"))
    (fp_rect (start -0.5 -0.25) (end 0.5 0.25)
      (stroke (width 0.15) (type solid)) (fill none) (layer "F.Fab"))
    (pad "1" smd roundrect (at -0.485 0 180) (size 0.59 0.64) (layers "F.Cu" "F.Paste" "F.Mask") (roundrect_rratio 0.25)
      (net 83 "/SDA1") (pintype "passive"))
    (pad "2" smd roundrect (at 0.485 0 180) (size 0.59 0.64) (layers "F.Cu" "F.Paste" "F.Mask") (roundrect_rratio 0.25)
      (net 102 "/SPI_SCK(SDA)") (pintype "passive"))
  )

  (footprint "sdi-mipi-bridge-footprints:R_0402_1005Metric" (layer "F.Cu")
    (at 156.945 108.9 180)
    (descr "Resistor SMD 0402")
    (tags "resistor SMD 0402")
    (property "Author" "Antmicro")
    (property "Current" "1A")
    (property "DNP" "DNP")
    (property "License" "Apache-2.0")
    (property "MPN" "ERJ2GE0R00X")
    (property "Manufacturer" "Panasonic")
    (property "Sheetfile" "sdi-mipi-bridge.kicad_sch")
    (property "Sheetname" "")
    (property "Tolerance" "")
    (property "Val" "0R")
    (property "ki_description" "0R resistor in 0402 package with unspecified tolerance")
    (attr exclude_from_pos_files)
    (fp_text reference "R41" (at -2.955 -0.4) (layer "F.SilkS")
        (effects (font (size 0.65 0.65) (thickness 0.15)) (justify right bottom))
    )
    (fp_text value "R_0R_0402" (at 0 1.4) (layer "F.Fab") hide
        (effects (font (size 0.7 0.7) (thickness 0.15)) (justify right bottom))
    )
    (fp_text user "License: Apache-2.0" (at -0.95 5.169) (layer "F.Fab") hide
        (effects (font (size 0.7 0.7) (thickness 0.15)) (justify right bottom))
    )
    (fp_text user "Author: Antmicro" (at -0.95 4.169) (layer "F.Fab") hide
        (effects (font (size 0.7 0.7) (thickness 0.15)) (justify right bottom))
    )
    (fp_text user "${REFERENCE}" (at -0.95 3.168) (layer "F.Fab") hide
        (effects (font (size 0.7 0.7) (thickness 0.15)) (justify right bottom))
    )
    (fp_rect (start -0.93 -0.47) (end 0.93 0.47)
      (stroke (width 0.05) (type solid)) (fill none) (layer "F.CrtYd"))
    (fp_rect (start -0.5 -0.25) (end 0.5 0.25)
      (stroke (width 0.15) (type solid)) (fill none) (layer "F.Fab"))
    (pad "1" smd roundrect (at -0.485 0 180) (size 0.59 0.64) (layers "F.Cu" "F.Paste" "F.Mask") (roundrect_rratio 0.25)
      (net 81 "/SDA2") (pintype "passive"))
    (pad "2" smd roundrect (at 0.485 0 180) (size 0.59 0.64) (layers "F.Cu" "F.Paste" "F.Mask") (roundrect_rratio 0.25)
      (net 102 "/SPI_SCK(SDA)") (pintype "passive"))
  )

  (footprint "sdi-mipi-bridge-footprints:BGA-80_7x7mm_Layout10x10_P0.65mm" (layer "F.Cu")
    (at 145.57 115.89 -90)
    (property "Author" "Antmicro")
    (property "License" "Apache-2.0")
    (property "MPN" "LIF-MD6000-6JMG80I")
    (property "Manufacturer" "Lattice Semiconductor")
    (property "Sheetfile" "sdi-mipi-bridge.kicad_sch")
    (property "Sheetname" "")
    (property "ki_description" "FPGA, CrossLink, PLL37 I/O, 400 MHz, 5936 Cells, 1.14 V to 1.26 V, CTFBGA-80")
    (property "ki_keywords" "SMT, FPGA, IC")
    (attr smd)
    (fp_text reference "U4" (at -1.901 -4.55 90) (layer "F.SilkS")
        (effects (font (size 0.7 0.7) (thickness 0.15)) (justify right bottom))
    )
    (fp_text value "CrossLink_LIF-MD6000-6JMG80I" (at 0 4.65 90) (layer "F.Fab") hide
        (effects (font (size 0.7 0.7) (thickness 0.15)) (justify right bottom))
    )
    (fp_text user "${REFERENCE}" (at -3.75 7.85 90) (layer "F.Fab") hide
        (effects (font (size 0.7 0.7) (thickness 0.15)) (justify right bottom))
    )
    (fp_text user "License: Apache-2.0" (at -3.75 6.65 90) (layer "F.Fab") hide
        (effects (font (size 0.7 0.7) (thickness 0.15)) (justify right bottom))
    )
    (fp_text user "Author: Antmicro" (at -3.75 9.05 90) (layer "F.Fab") hide
        (effects (font (size 0.7 0.7) (thickness 0.15)) (justify right bottom))
    )
    (fp_line (start -3.621 -2.801) (end -3.621 -1.871)
      (stroke (width 0.15) (type solid)) (layer "F.SilkS"))
    (fp_line (start -3.621 3.62) (end -3.621 1.87)
      (stroke (width 0.15) (type solid)) (layer "F.SilkS"))
    (fp_line (start -2.801 -3.621) (end -3.621 -2.801)
      (stroke (width 0.15) (type solid)) (layer "F.SilkS"))
    (fp_line (start -1.871 -3.621) (end -2.801 -3.621)
      (stroke (width 0.15) (type solid)) (layer "F.SilkS"))
    (fp_line (start -1.871 3.62) (end -3.621 3.62)
      (stroke (width 0.15) (type solid)) (layer "F.SilkS"))
    (fp_line (start 1.87 -3.621) (end 3.62 -3.621)
      (stroke (width 0.15) (type solid)) (layer "F.SilkS"))
    (fp_line (start 1.87 -3.621) (end 3.62 -3.621)
      (stroke (width 0.15) (type solid)) (layer "F.SilkS"))
    (fp_line (start 1.87 -3.621) (end 3.62 -3.621)
      (stroke (width 0.15) (type solid)) (layer "F.SilkS"))
    (fp_line (start 1.87 3.62) (end 3.62 3.62)
      (stroke (width 0.15) (type solid)) (layer "F.SilkS"))
    (fp_line (start 3.62 -3.621) (end 3.62 -1.871)
      (stroke (width 0.15) (type solid)) (layer "F.SilkS"))
    (fp_line (start 3.62 -3.621) (end 3.62 -1.871)
      (stroke (width 0.15) (type solid)) (layer "F.SilkS"))
    (fp_line (start 3.62 -3.621) (end 3.62 -1.871)
      (stroke (width 0.15) (type solid)) (layer "F.SilkS"))
    (fp_line (start 3.62 3.62) (end 3.62 1.87)
      (stroke (width 0.15) (type solid)) (layer "F.SilkS"))
    (fp_circle (center -2.925 -4.05) (end -2.875 -4.05)
      (stroke (width 0.15) (type solid)) (fill solid) (layer "F.SilkS"))
    (fp_rect (start -3.75 -3.75) (end 3.75 3.75)
      (stroke (width 0.05) (type solid)) (fill none) (layer "F.CrtYd"))
    (fp_line (start -3.5 -2.5) (end -3.5 3.499)
      (stroke (width 0.15) (type solid)) (layer "F.Fab"))
    (fp_line (start -3.5 3.499) (end 3.499 3.499)
      (stroke (width 0.15) (type solid)) (layer "F.Fab"))
    (fp_line (start -2.5 -3.5) (end -3.5 -2.5)
      (stroke (width 0.15) (type solid)) (layer "F.Fab"))
    (fp_line (start 3.499 -3.5) (end -2.5 -3.5)
      (stroke (width 0.15) (type solid)) (layer "F.Fab"))
    (fp_line (start 3.499 3.499) (end 3.499 -3.5)
      (stroke (width 0.15) (type solid)) (layer "F.Fab"))
    (pad "A1" smd circle (at -2.925 -2.925 270) (size 0.35 0.35) (layers "F.Cu" "F.Paste" "F.Mask")
      (net 155 "/MIPI1_D2_N") (pinfunction "DPHY1_DN2") (pintype "bidirectional") (solder_mask_margin -0.025) (solder_paste_margin -0.025))
    (pad "A2" smd circle (at -2.275 -2.925 270) (size 0.35 0.35) (layers "F.Cu" "F.Paste" "F.Mask")
      (net 159 "/MIPI1_D0_N") (pinfunction "DPHY1_DN0") (pintype "bidirectional") (solder_mask_margin -0.025) (solder_paste_margin -0.025))
    (pad "A3" smd circle (at -1.625 -2.925 270) (size 0.35 0.35) (layers "F.Cu" "F.Paste" "F.Mask")
      (net 161 "/MIPI1_CLK_N") (pinfunction "DPHY1_CKN") (pintype "bidirectional") (solder_mask_margin -0.025) (solder_paste_margin -0.025))
    (pad "A4" smd circle (at -0.975 -2.925 270) (size 0.35 0.35) (layers "F.Cu" "F.Paste" "F.Mask")
      (net 157 "/MIPI1_D1_N") (pinfunction "DPHY1_DN1") (pintype "bidirectional") (solder_mask_margin -0.025) (solder_paste_margin -0.025))
    (pad "A5" smd circle (at -0.325 -2.925 270) (size 0.35 0.35) (layers "F.Cu" "F.Paste" "F.Mask")
      (net 153 "/MIPI1_D3_N") (pinfunction "DPHY1_DN3") (pintype "bidirectional") (solder_mask_margin -0.025) (solder_paste_margin -0.025))
    (pad "A6" smd circle (at 0.325 -2.925 270) (size 0.35 0.35) (layers "F.Cu" "F.Paste" "F.Mask")
      (net 145 "/MIPI0_D2_N") (pinfunction "DPHY0_DN2") (pintype "bidirectional") (solder_mask_margin -0.025) (solder_paste_margin -0.025))
    (pad "A7" smd circle (at 0.975 -2.925 270) (size 0.35 0.35) (layers "F.Cu" "F.Paste" "F.Mask")
      (net 149 "/MIPI0_D0_N") (pinfunction "DPHY0_DN0") (pintype "bidirectional") (solder_mask_margin -0.025) (solder_paste_margin -0.025))
    (pad "A8" smd circle (at 1.625 -2.925 270) (size 0.35 0.35) (layers "F.Cu" "F.Paste" "F.Mask")
      (net 151 "/MIPI0_CLK_N") (pinfunction "DPHY0_CKN") (pintype "bidirectional") (solder_mask_margin -0.025) (solder_paste_margin -0.025))
    (pad "A9" smd circle (at 2.275 -2.925 270) (size 0.35 0.35) (layers "F.Cu" "F.Paste" "F.Mask")
      (net 147 "/MIPI0_D1_N") (pinfunction "DPHY0_DN1") (pintype "bidirectional") (solder_mask_margin -0.025) (solder_paste_margin -0.025))
    (pad "A10" smd circle (at 2.925 -2.925 270) (size 0.35 0.35) (layers "F.Cu" "F.Paste" "F.Mask")
      (net 143 "/MIPI0_D3_N") (pinfunction "DPHY0_DN3") (pintype "bidirectional") (solder_mask_margin -0.025) (solder_paste_margin -0.025))
    (pad "B1" smd circle (at -2.925 -2.275 270) (size 0.35 0.35) (layers "F.Cu" "F.Paste" "F.Mask")
      (net 156 "/MIPI1_D2_P") (pinfunction "DPHY1_DP2") (pintype "bidirectional") (solder_mask_margin -0.025) (solder_paste_margin -0.025))
    (pad "B2" smd circle (at -2.275 -2.275 270) (size 0.35 0.35) (layers "F.Cu" "F.Paste" "F.Mask")
      (net 160 "/MIPI1_D0_P") (pinfunction "DPHY1_DP0") (pintype "bidirectional") (solder_mask_margin -0.025) (solder_paste_margin -0.025))
    (pad "B3" smd circle (at -1.625 -2.275 270) (size 0.35 0.35) (layers "F.Cu" "F.Paste" "F.Mask")
      (net 162 "/MIPI1_CLK_P") (pinfunction "DPHY1_CKP") (pintype "bidirectional") (solder_mask_margin -0.025) (solder_paste_margin -0.025))
    (pad "B4" smd circle (at -0.975 -2.275 270) (size 0.35 0.35) (layers "F.Cu" "F.Paste" "F.Mask")
      (net 158 "/MIPI1_D1_P") (pinfunction "DPHY1_DP1") (pintype "bidirectional") (solder_mask_margin -0.025) (solder_paste_margin -0.025))
    (pad "B5" smd circle (at -0.325 -2.275 270) (size 0.35 0.35) (layers "F.Cu" "F.Paste" "F.Mask")
      (net 154 "/MIPI1_D3_P") (pinfunction "DPHY1_DP3") (pintype "bidirectional") (solder_mask_margin -0.025) (solder_paste_margin -0.025))
    (pad "B6" smd circle (at 0.325 -2.275 270) (size 0.35 0.35) (layers "F.Cu" "F.Paste" "F.Mask")
      (net 146 "/MIPI0_D2_P") (pinfunction "DPHY0_DP2") (pintype "bidirectional") (solder_mask_margin -0.025) (solder_paste_margin -0.025))
    (pad "B7" smd circle (at 0.975 -2.275 270) (size 0.35 0.35) (layers "F.Cu" "F.Paste" "F.Mask")
      (net 150 "/MIPI0_D0_P") (pinfunction "DPHY0_DP0") (pintype "bidirectional") (solder_mask_margin -0.025) (solder_paste_margin -0.025))
    (pad "B8" smd circle (at 1.625 -2.275 270) (size 0.35 0.35) (layers "F.Cu" "F.Paste" "F.Mask")
      (net 152 "/MIPI0_CLK_P") (pinfunction "DPHY0_CKP") (pintype "bidirectional") (solder_mask_margin -0.025) (solder_paste_margin -0.025))
    (pad "B9" smd circle (at 2.275 -2.275 270) (size 0.35 0.35) (layers "F.Cu" "F.Paste" "F.Mask")
      (net 148 "/MIPI0_D1_P") (pinfunction "DPHY0_DP1") (pintype "bidirectional") (solder_mask_margin -0.025) (solder_paste_margin -0.025))
    (pad "B10" smd circle (at 2.925 -2.275 270) (size 0.35 0.35) (layers "F.Cu" "F.Paste" "F.Mask")
      (net 144 "/MIPI0_D3_P") (pinfunction "DPHY0_DP3") (pintype "bidirectional") (solder_mask_margin -0.025) (solder_paste_margin -0.025))
    (pad "C1" smd circle (at -2.925 -1.625 270) (size 0.35 0.35) (layers "F.Cu" "F.Paste" "F.Mask")
      (net 1 "GNDREF") (pinfunction "GND") (pintype "power_in") (solder_mask_margin -0.025) (solder_paste_margin -0.025))
    (pad "C2" smd circle (at -2.275 -1.625 270) (size 0.35 0.35) (layers "F.Cu" "F.Paste" "F.Mask")
      (net 1 "GNDREF") (pinfunction "GNDA_DPHY1") (pintype "power_in") (solder_mask_margin -0.025) (solder_paste_margin -0.025))
    (pad "C9" smd circle (at 2.275 -1.625 270) (size 0.35 0.35) (layers "F.Cu" "F.Paste" "F.Mask")
      (net 1 "GNDREF") (pinfunction "GNDA_DPHY0") (pintype "power_in") (solder_mask_margin -0.025) (solder_paste_margin -0.025))
    (pad "C10" smd circle (at 2.925 -1.625 270) (size 0.35 0.35) (layers "F.Cu" "F.Paste" "F.Mask")
      (net 1 "GNDREF") (pinfunction "GND") (pintype "passive") (solder_mask_margin -0.025) (solder_paste_margin -0.025))
    (pad "D1" smd circle (at -2.925 -0.975 270) (size 0.35 0.35) (layers "F.Cu" "F.Paste" "F.Mask")
      (net 103 "/USER_SDA") (pinfunction "PB48/PCLKT0_1/USER_SCL") (pintype "bidirectional") (solder_mask_margin -0.025) (solder_paste_margin -0.025))
    (pad "D2" smd circle (at -2.275 -0.975 270) (size 0.35 0.35) (layers "F.Cu" "F.Paste" "F.Mask")
      (net 85 "Net-(U4-VCCA_DPHY1)") (pinfunction "VCCPLL_DPHY1") (pintype "power_in") (solder_mask_margin -0.025) (solder_paste_margin -0.025))
    (pad "D4" smd circle (at -0.975 -0.975 270) (size 0.35 0.35) (layers "F.Cu" "F.Paste" "F.Mask")
      (net 85 "Net-(U4-VCCA_DPHY1)") (pinfunction "VCCA_DPHY1") (pintype "power_in") (solder_mask_margin -0.025) (solder_paste_margin -0.025))
    (pad "D5" smd circle (at -0.325 -0.975 270) (size 0.35 0.35) (layers "F.Cu" "F.Paste" "F.Mask")
      (net 6 "+3V3") (pinfunction "VCCAUX") (pintype "power_in") (solder_mask_margin -0.025) (solder_paste_margin -0.025))
    (pad "D6" smd circle (at 0.325 -0.975 270) (size 0.35 0.35) (layers "F.Cu" "F.Paste" "F.Mask")
      (net 58 "/GNDPLL_DPHY") (pinfunction "GNDPLL_DPHY_X") (pintype "power_in") (solder_mask_margin -0.025) (solder_paste_margin -0.025))
    (pad "D7" smd circle (at 0.975 -0.975 270) (size 0.35 0.35) (layers "F.Cu" "F.Paste" "F.Mask")
      (net 104 "Net-(U4-VCCA_DPHY0)") (pinfunction "VCCPLL_DPHY0") (pintype "bidirectional") (solder_mask_margin -0.025) (solder_paste_margin -0.025))
    (pad "D9" smd circle (at 2.275 -0.975 270) (size 0.35 0.35) (layers "F.Cu" "F.Paste" "F.Mask")
      (net 44 "/JTAG_~{HOST}") (pinfunction "PB16A/PCLKT2_0") (pintype "bidirectional") (solder_mask_margin -0.025) (solder_paste_margin -0.025))
    (pad "D10" smd circle (at 2.925 -0.975 270) (size 0.35 0.35) (layers "F.Cu" "F.Paste" "F.Mask")
      (net 127 "/~{RST_TRST_SOFT}") (pinfunction "PB16B/PCLKC2_0") (pintype "bidirectional") (solder_mask_margin -0.025) (solder_paste_margin -0.025))
    (pad "E1" smd circle (at -2.925 -0.325 270) (size 0.35 0.35) (layers "F.Cu" "F.Paste" "F.Mask")
      (net 172 "/DOUT14") (pinfunction "PB34A/GR_PCLK1_0") (pintype "input") (solder_mask_margin -0.025) (solder_paste_margin -0.025))
    (pad "E2" smd circle (at -2.275 -0.325 270) (size 0.35 0.35) (layers "F.Cu" "F.Paste" "F.Mask")
      (net 87 "/LOCKED_CL") (pinfunction "PB34B") (pintype "bidirectional") (solder_mask_margin -0.025) (solder_paste_margin -0.025))
    (pad "E4" smd circle (at -0.975 -0.325 270) (size 0.35 0.35) (layers "F.Cu" "F.Paste" "F.Mask")
      (net 2 "+1V2") (pinfunction "VCC") (pintype "power_in") (solder_mask_margin -0.025) (solder_paste_margin -0.025))
    (pad "E5" smd circle (at -0.325 -0.325 270) (size 0.35 0.35) (layers "F.Cu" "F.Paste" "F.Mask")
      (net 1 "GNDREF") (pinfunction "GND") (pintype "passive") (solder_mask_margin -0.025) (solder_paste_margin -0.025))
    (pad "E6" smd circle (at 0.325 -0.325 270) (size 0.35 0.35) (layers "F.Cu" "F.Paste" "F.Mask")
      (net 2 "+1V2") (pinfunction "VCC") (pintype "passive") (solder_mask_margin -0.025) (solder_paste_margin -0.025))
    (pad "E7" smd circle (at 0.975 -0.325 270) (size 0.35 0.35) (layers "F.Cu" "F.Paste" "F.Mask")
      (net 104 "Net-(U4-VCCA_DPHY0)") (pinfunction "VCCA_DPHY0") (pintype "power_in") (solder_mask_margin -0.025) (solder_paste_margin -0.025))
    (pad "E9" smd circle (at 2.275 -0.325 270) (size 0.35 0.35) (layers "F.Cu" "F.Paste" "F.Mask")
      (net 54 "/STANDBY") (pinfunction "PB12A/GPLLT2_0") (pintype "input") (solder_mask_margin -0.025) (solder_paste_margin -0.025))
    (pad "E10" smd circle (at 2.925 -0.325 270) (size 0.35 0.35) (layers "F.Cu" "F.Paste" "F.Mask")
      (net 22 "/~{DATA_ERROR}") (pinfunction "PB12B/GPLLC2_0") (pintype "input") (solder_mask_margin -0.025) (solder_paste_margin -0.025))
    (pad "F1" smd circle (at -2.925 0.325 270) (size 0.35 0.35) (layers "F.Cu" "F.Paste" "F.Mask")
      (net 14 "/H_HSYNC") (pinfunction "PB38A") (pintype "bidirectional") (solder_mask_margin -0.025) (solder_paste_margin -0.025))
    (pad "F2" smd circle (at -2.275 0.325 270) (size 0.35 0.35) (layers "F.Cu" "F.Paste" "F.Mask")
      (net 15 "/V_VSYNC") (pinfunction "PB38B") (pintype "bidirectional") (solder_mask_margin -0.025) (solder_paste_margin -0.025))
    (pad "F4" smd circle (at -0.975 0.325 270) (size 0.35 0.35) (layers "F.Cu" "F.Paste" "F.Mask")
      (net 79 "VCC_IO") (pinfunction "VCCIO0") (pintype "power_in") (solder_mask_margin -0.025) (solder_paste_margin -0.025))
    (pad "F5" smd circle (at -0.325 0.325 270) (size 0.35 0.35) (layers "F.Cu" "F.Paste" "F.Mask")
      (net 79 "VCC_IO") (pinfunction "VCCIO1") (pintype "power_in") (solder_mask_margin -0.025) (solder_paste_margin -0.025))
    (pad "F6" smd circle (at 0.325 0.325 270) (size 0.35 0.35) (layers "F.Cu" "F.Paste" "F.Mask")
      (net 79 "VCC_IO") (pinfunction "VCCIO2") (pintype "power_in") (solder_mask_margin -0.025) (solder_paste_margin -0.025))
    (pad "F7" smd circle (at 0.975 0.325 270) (size 0.35 0.35) (layers "F.Cu" "F.Paste" "F.Mask")
      (net 79 "VCC_IO") (pinfunction "VCCIO2") (pintype "passive") (solder_mask_margin -0.025) (solder_paste_margin -0.025))
    (pad "F9" smd circle (at 2.275 0.325 270) (size 0.35 0.35) (layers "F.Cu" "F.Paste" "F.Mask")
      (net 19 "/F_DE") (pinfunction "PB6A/GR_PCLK2_0") (pintype "input") (solder_mask_margin -0.025) (solder_paste_margin -0.025))
    (pad "F10" smd circle (at 2.925 0.325 270) (size 0.35 0.35) (layers "F.Cu" "F.Paste" "F.Mask")
      (net 21 "/Y_1ANC") (pinfunction "PB6B") (pintype "bidirectional") (solder_mask_margin -0.025) (solder_paste_margin -0.025))
    (pad "G1" smd circle (at -2.925 0.975 270) (size 0.35 0.35) (layers "F.Cu" "F.Paste" "F.Mask")
      (net 97 "/MOSI") (pinfunction "PB50/MOSI") (pintype "bidirectional") (solder_mask_margin -0.025) (solder_paste_margin -0.025))
    (pad "G2" smd circle (at -2.275 0.975 270) (size 0.35 0.35) (layers "F.Cu" "F.Paste" "F.Mask")
      (net 1 "GNDREF") (pinfunction "GND") (pintype "passive") (solder_mask_margin -0.025) (solder_paste_margin -0.025))
    (pad "G4" smd circle (at -0.975 0.975 270) (size 0.35 0.35) (layers "F.Cu" "F.Paste" "F.Mask")
      (net 79 "VCC_IO") (pinfunction "VCCIO1") (pintype "passive") (solder_mask_margin -0.025) (solder_paste_margin -0.025))
    (pad "G5" smd circle (at -0.325 0.975 270) (size 0.35 0.35) (layers "F.Cu" "F.Paste" "F.Mask")
      (net 1 "GNDREF") (pinfunction "GND") (pintype "passive") (solder_mask_margin -0.025) (solder_paste_margin -0.025))
    (pad "G6" smd circle (at 0.325 0.975 270) (size 0.35 0.35) (layers "F.Cu" "F.Paste" "F.Mask")
      (net 89 "VCCGPLL") (pinfunction "VCCGPLL") (pintype "power_in") (solder_mask_margin -0.025) (solder_paste_margin -0.025))
    (pad "G7" smd circle (at 0.975 0.975 270) (size 0.35 0.35) (layers "F.Cu" "F.Paste" "F.Mask")
      (net 59 "/GNDGPLL") (pinfunction "GNDGPLL") (pintype "power_in") (solder_mask_margin -0.025) (solder_paste_margin -0.025))
    (pad "G9" smd circle (at 2.275 0.975 270) (size 0.35 0.35) (layers "F.Cu" "F.Paste" "F.Mask")
      (net 23 "/TIM_861") (pinfunction "PB2A") (pintype "bidirectional") (solder_mask_margin -0.025) (solder_paste_margin -0.025))
    (pad "G10" smd circle (at 2.925 0.975 270) (size 0.35 0.35) (layers "F.Cu" "F.Paste" "F.Mask")
      (net 24 "/~{RC_BYP}") (pinfunction "PB2B") (pintype "bidirectional") (solder_mask_margin -0.025) (solder_paste_margin -0.025))
    (pad "H1" smd circle (at -2.925 1.625 270) (size 0.35 0.35) (layers "F.Cu" "F.Paste" "F.Mask")
      (net 99 "/SPI_SS(SCL)") (pinfunction "PB52/SPI_SS/CSN/SCL") (pintype "bidirectional") (solder_mask_margin -0.025) (solder_paste_margin -0.025))
    (pad "H2" smd circle (at -2.275 1.625 270) (size 0.35 0.35) (layers "F.Cu" "F.Paste" "F.Mask")
      (net 100 "/CRESET_B") (pinfunction "CRESET_B") (pintype "input") (solder_mask_margin -0.025) (solder_paste_margin -0.025))
    (pad "H9" smd circle (at 2.275 1.625 270) (size 0.35 0.35) (layers "F.Cu" "F.Paste" "F.Mask")
      (net 47 "/SW_EN") (pinfunction "PB2D/MIPI_CLKC2_0") (pintype "bidirectional") (solder_mask_margin -0.025) (solder_paste_margin -0.025))
    (pad "H10" smd circle (at 2.925 1.625 270) (size 0.35 0.35) (layers "F.Cu" "F.Paste" "F.Mask")
      (net 41 "/IOPROC_EN_~{DIS}") (pinfunction "PB2C/MIPI_CLKT2_0") (pintype "bidirectional") (solder_mask_margin -0.025) (solder_paste_margin -0.025))
    (pad "J1" smd circle (at -2.925 2.275 270) (size 0.35 0.35) (layers "F.Cu" "F.Paste" "F.Mask")
      (net 128 "Net-(U4-PB53{slash}SPI_SCK{slash}MCK{slash}SDA)") (pinfunction "PB53/SPI_SCK/MCK/SDA") (pintype "bidirectional") (solder_mask_margin -0.025) (solder_paste_margin -0.025))
    (pad "J2" smd circle (at -2.275 2.275 270) (size 0.35 0.35) (layers "F.Cu" "F.Paste" "F.Mask")
      (net 88 "/CDONE") (pinfunction "PB49/PMU_WKUPN/CDONE") (pintype "passive") (solder_mask_margin -0.025) (solder_paste_margin -0.025))
    (pad "J3" smd circle (at -1.625 2.275 270) (size 0.35 0.35) (layers "F.Cu" "F.Paste" "F.Mask")
      (net 173 "/DOUT13") (pinfunction "PB43D") (pintype "bidirectional") (solder_mask_margin -0.025) (solder_paste_margin -0.025))
    (pad "J4" smd circle (at -0.975 2.275 270) (size 0.35 0.35) (layers "F.Cu" "F.Paste" "F.Mask")
      (net 171 "/DOUT12") (pinfunction "PB38D") (pintype "bidirectional") (solder_mask_margin -0.025) (solder_paste_margin -0.025))
    (pad "J5" smd circle (at -0.325 2.275 270) (size 0.35 0.35) (layers "F.Cu" "F.Paste" "F.Mask")
      (net 175 "/DOUT11") (pinfunction "PB34D/MIPI_CLKC1_0") (pintype "bidirectional") (solder_mask_margin -0.025) (solder_paste_margin -0.025))
    (pad "J6" smd circle (at 0.325 2.275 270) (size 0.35 0.35) (layers "F.Cu" "F.Paste" "F.Mask")
      (net 174 "/DOUT10") (pinfunction "PB29D/PCLKC1_1") (pintype "bidirectional") (solder_mask_margin -0.025) (solder_paste_margin -0.025))
    (pad "J7" smd circle (at 0.975 2.275 270) (size 0.35 0.35) (layers "F.Cu" "F.Paste" "F.Mask")
      (net 13 "/PCLK") (pinfunction "PB29A/PCLKT1_0") (pintype "bidirectional") (solder_mask_margin -0.025) (solder_paste_margin -0.025))
    (pad "J8" smd circle (at 1.625 2.275 270) (size 0.35 0.35) (layers "F.Cu" "F.Paste" "F.Mask")
      (net 53 "/Audio_EN_~{DIS}") (pinfunction "PB16D/PCLKC2_1") (pintype "bidirectional") (solder_mask_margin -0.025) (solder_paste_margin -0.025))
    (pad "J9" smd circle (at 2.275 2.275 270) (size 0.35 0.35) (layers "F.Cu" "F.Paste" "F.Mask")
      (net 105 "/USER_SW") (pinfunction "PB6D") (pintype "bidirectional") (solder_mask_margin -0.025) (solder_paste_margin -0.025))
    (pad "J10" smd circle (at 2.925 2.275 270) (size 0.35 0.35) (layers "F.Cu" "F.Paste" "F.Mask")
      (net 106 "/USER_LED") (pinfunction "PB6C") (pintype "bidirectional") (solder_mask_margin -0.025) (solder_paste_margin -0.025))
    (pad "K1" smd circle (at -2.925 2.925 270) (size 0.35 0.35) (layers "F.Cu" "F.Paste" "F.Mask")
      (net 96 "/MISO") (pinfunction "PB51/MISO") (pintype "bidirectional") (solder_mask_margin -0.025) (solder_paste_margin -0.025))
    (pad "K2" smd circle (at -2.275 2.925 270) (size 0.35 0.35) (layers "F.Cu" "F.Paste" "F.Mask")
      (net 101 "/USER_SCL") (pinfunction "PB47/PCLKT0_0/USER_SDA") (pintype "bidirectional") (solder_mask_margin -0.025) (solder_paste_margin -0.025))
    (pad "K3" smd circle (at -1.625 2.925 270) (size 0.35 0.35) (layers "F.Cu" "F.Paste" "F.Mask")
      (net 168 "/DOUT19") (pinfunction "PB43C") (pintype "bidirectional") (solder_mask_margin -0.025) (solder_paste_margin -0.025))
    (pad "K4" smd circle (at -0.975 2.925 270) (size 0.35 0.35) (layers "F.Cu" "F.Paste" "F.Mask")
      (net 166 "/DOUT18") (pinfunction "PB38C") (pintype "bidirectional") (solder_mask_margin -0.025) (solder_paste_margin -0.025))
    (pad "K5" smd circle (at -0.325 2.925 270) (size 0.35 0.35) (layers "F.Cu" "F.Paste" "F.Mask")
      (net 167 "/DOUT17") (pinfunction "PB34C/MIPI_CLKT1_0") (pintype "bidirectional") (solder_mask_margin -0.025) (solder_paste_margin -0.025))
    (pad "K6" smd circle (at 0.325 2.925 270) (size 0.35 0.35) (layers "F.Cu" "F.Paste" "F.Mask")
      (net 169 "/DOUT16") (pinfunction "PB29C/PCLKT1_1") (pintype "bidirectional") (solder_mask_margin -0.025) (solder_paste_margin -0.025))
    (pad "K7" smd circle (at 0.975 2.925 270) (size 0.35 0.35) (layers "F.Cu" "F.Paste" "F.Mask")
      (net 170 "/DOUT15") (pinfunction "PB29B/PCLKC1_0") (pintype "bidirectional") (solder_mask_margin -0.025) (solder_paste_margin -0.025))
    (pad "K8" smd circle (at 1.625 2.925 270) (size 0.35 0.35) (layers "F.Cu" "F.Paste" "F.Mask")
      (net 16 "/20bit_~{10bit}") (pinfunction "PB16C/PCLKT2_1") (pintype "bidirectional") (solder_mask_margin -0.025) (solder_paste_margin -0.025))
    (pad "K9" smd circle (at 2.275 2.925 270) (size 0.35 0.35) (layers "F.Cu" "F.Paste" "F.Mask")
      (net 17 "/~{SMPTE_BYPASS}") (pinfunction "PB12D") (pintype "bidirectional") (solder_mask_margin -0.025) (solder_paste_margin -0.025))
    (pad "K10" smd circle (at 2.925 2.925 270) (size 0.35 0.35) (layers "F.Cu" "F.Paste" "F.Mask")
      (net 18 "/DVB_ASI") (pinfunction "PB12C") (pintype "bidirectional") (solder_mask_margin -0.025) (solder_paste_margin -0.025))
  )

  (footprint "sdi-mipi-bridge-footprints:R_0402_1005Metric" (layer "F.Cu")
    (at 131 107.4 -90)
    (descr "Resistor SMD 0402")
    (tags "resistor SMD 0402")
    (property "Author" "Antmicro")
    (property "License" "Apache-2.0")
    (property "MPN" "CR0402-FX-1000GLF")
    (property "Manufacturer" "Bourns")
    (property "Sheetfile" "sdi-mipi-bridge.kicad_sch")
    (property "Sheetname" "")
    (property "Tolerance" "1%")
    (property "Val" "100R")
    (property "ki_description" "100R resistor in 0402 package with 1% tolerance")
    (attr smd)
    (fp_text reference "R88" (at 0.9 -3.3 -90) (layer "F.SilkS")
        (effects (font (size 0.65 0.65) (thickness 0.15)) (justify left bottom))
    )
    (fp_text value "R_100R_0402" (at 0 1.4 -90) (layer "F.Fab") hide
        (effects (font (size 0.7 0.7) (thickness 0.15)) (justify left bottom))
    )
    (fp_text user "Author: Antmicro" (at -0.95 4.169 -90) (layer "F.Fab") hide
        (effects (font (size 0.7 0.7) (thickness 0.15)) (justify left bottom))
    )
    (fp_text user "License: Apache-2.0" (at -0.95 5.169 -90) (layer "F.Fab") hide
        (effects (font (size 0.7 0.7) (thickness 0.15)) (justify left bottom))
    )
    (fp_text user "${REFERENCE}" (at -0.95 3.168 -90) (layer "F.Fab") hide
        (effects (font (size 0.7 0.7) (thickness 0.15)) (justify left bottom))
    )
    (fp_rect (start -0.93 -0.47) (end 0.93 0.47)
      (stroke (width 0.05) (type solid)) (fill none) (layer "F.CrtYd"))
    (fp_rect (start -0.5 -0.25) (end 0.5 0.25)
      (stroke (width 0.15) (type solid)) (fill none) (layer "F.Fab"))
    (pad "1" smd roundrect (at -0.485 0 270) (size 0.59 0.64) (layers "F.Cu" "F.Paste" "F.Mask") (roundrect_rratio 0.25)
      (net 86 "Net-(D2-Pad1)") (pintype "passive"))
    (pad "2" smd roundrect (at 0.485 0 270) (size 0.59 0.64) (layers "F.Cu" "F.Paste" "F.Mask") (roundrect_rratio 0.25)
      (net 88 "/CDONE") (pintype "passive"))
  )

  (footprint "sdi-mipi-bridge-footprints:C_0402_1005Metric" (layer "F.Cu")
    (at 117.5 106.4 90)
    (descr "Capacitor SMD 0402")
    (tags "capacitor SMD 0402")
    (property "Author" "Antmicro")
    (property "Dielectric" "")
    (property "License" "Apache-2.0")
    (property "MPN" "MC0402X473K160CT")
    (property "Manufacturer" "Multicomp")
    (property "Sheetfile" "sdi-mipi-bridge.kicad_sch")
    (property "Sheetname" "")
    (property "Val" "47n")
    (property "Voltage" "")
    (property "ki_description" " ")
    (attr smd)
    (fp_text reference "C63" (at -2.9 0.4 90) (layer "F.SilkS")
        (effects (font (size 0.65 0.65) (thickness 0.15)) (justify left bottom))
    )
    (fp_text value "C_47n_0402" (at 0 1.4 90) (layer "F.Fab") hide
        (effects (font (size 0.7 0.7) (thickness 0.15)) (justify left bottom))
    )
    (fp_text user "License: Apache-2.0" (at -0.932 5.17 90) (layer "F.Fab") hide
        (effects (font (size 0.7 0.7) (thickness 0.15)) (justify left bottom))
    )
    (fp_text user "${REFERENCE}" (at -0.932 3.168 90) (layer "F.Fab") hide
        (effects (font (size 0.7 0.7) (thickness 0.15)) (justify left bottom))
    )
    (fp_text user "Author: Antmicro" (at -0.932 4.17 90) (layer "F.Fab") hide
        (effects (font (size 0.7 0.7) (thickness 0.15)) (justify left bottom))
    )
    (fp_rect (start -0.94 -0.47) (end 0.94 0.47)
      (stroke (width 0.05) (type solid)) (fill none) (layer "F.CrtYd"))
    (fp_rect (start -0.499 -0.249) (end 0.499 0.249)
      (stroke (width 0.15) (type solid)) (fill none) (layer "F.Fab"))
    (pad "1" smd roundrect (at -0.484 0 90) (size 0.59 0.64) (layers "F.Cu" "F.Paste" "F.Mask") (roundrect_rratio 0.25)
      (net 10 "/LF") (pintype "passive"))
    (pad "2" smd roundrect (at 0.484 0 90) (size 0.59 0.64) (layers "F.Cu" "F.Paste" "F.Mask") (roundrect_rratio 0.25)
      (net 3 "GNDA") (pintype "passive"))
  )

  (footprint "sdi-mipi-bridge-footprints:LED_0603_1608Metric_G" (layer "F.Cu")
    (at 131 104.4 90)
    (descr "LED SMD 0603 Green")
    (tags "LED SMD 0603 Green")
    (property "Author" "Antmicro")
    (property "License" "Apache-2.0")
    (property "MPN" "LG L29K-G2J1-24-Z")
    (property "Manufacturer" "Osram")
    (property "Sheetfile" "sdi-mipi-bridge.kicad_sch")
    (property "Sheetname" "")
    (attr smd)
    (fp_text reference "D2" (at 0.2 -0.7 90) (layer "F.SilkS")
        (effects (font (size 0.65 0.65) (thickness 0.15)) (justify left bottom))
    )
    (fp_text value "LED_G_0603_LG_L29K-G2J1-24-Z" (at 0 1.6 90) (layer "F.Fab") hide
        (effects (font (size 0.7 0.7) (thickness 0.15)) (justify left bottom))
    )
    (fp_text user "License: Apache-2.0" (at -1.31 5.769 90) (layer "F.Fab") hide
        (effects (font (size 0.7 0.7) (thickness 0.15)) (justify left bottom))
    )
    (fp_text user "Author: Antmicro" (at -1.31 4.769 90) (layer "F.Fab") hide
        (effects (font (size 0.7 0.7) (thickness 0.15)) (justify left bottom))
    )
    (fp_text user "${REFERENCE}" (at -1.31 3.769 90) (layer "F.Fab") hide
        (effects (font (size 0.7 0.7) (thickness 0.15)) (justify left bottom))
    )
    (fp_line (start -0.27 -0.35) (end 0.27 -0.35)
      (stroke (width 0.15) (type solid)) (layer "F.SilkS"))
    (fp_line (start -0.27 0.351) (end 0.27 0.351)
      (stroke (width 0.15) (type solid)) (layer "F.SilkS"))
    (fp_line (start -0.106328 -0.200008) (end -0.106328 0.199992)
      (stroke (width 0.1) (type solid)) (layer "F.SilkS"))
    (fp_line (start -0.106328 -0.200008) (end 0.093672 -0.000008)
      (stroke (width 0.1) (type solid)) (layer "F.SilkS"))
    (fp_line (start -0.106328 -0.000008) (end -0.29 0)
      (stroke (width 0.1) (type solid)) (layer "F.SilkS"))
    (fp_line (start 0.093672 -0.200008) (end 0.093672 0.199992)
      (stroke (width 0.1) (type solid)) (layer "F.SilkS"))
    (fp_line (start 0.093672 -0.000008) (end -0.106328 0.199992)
      (stroke (width 0.1) (type solid)) (layer "F.SilkS"))
    (fp_line (start 0.093672 -0.000008) (end 0.293672 -0.000008)
      (stroke (width 0.1) (type solid)) (layer "F.SilkS"))
    (fp_line (start 1.25 0.32) (end 1.25 -0.32)
      (stroke (width 0.15) (type solid)) (layer "F.SilkS"))
    (fp_rect (start 1.26 0.65) (end -1.26 -0.65)
      (stroke (width 0.05) (type solid)) (fill none) (layer "F.CrtYd"))
    (fp_line (start -0.599 0) (end -0.201 0)
      (stroke (width 0.15) (type solid)) (layer "F.Fab"))
    (fp_line (start -0.201 -0.2) (end -0.201 0)
      (stroke (width 0.15) (type solid)) (layer "F.Fab"))
    (fp_line (start -0.201 0) (end -0.201 0.202)
      (stroke (width 0.15) (type solid)) (layer "F.Fab"))
    (fp_line (start -0.201 0.202) (end 0.101 0)
      (stroke (width 0.15) (type solid)) (layer "F.Fab"))
    (fp_line (start 0.101 0) (end -0.201 -0.2)
      (stroke (width 0.15) (type solid)) (layer "F.Fab"))
    (fp_line (start 0.199 -0.2) (end 0.199 -0.1)
      (stroke (width 0.15) (type solid)) (layer "F.Fab"))
    (fp_line (start 0.199 0) (end 0.597 0)
      (stroke (width 0.15) (type solid)) (layer "F.Fab"))
    (fp_line (start 0.199 0.202) (end 0.199 -0.1)
      (stroke (width 0.15) (type solid)) (layer "F.Fab"))
    (fp_rect (start -0.848 -0.4) (end 0.85 0.402)
      (stroke (width 0.15) (type solid)) (fill none) (layer "F.Fab"))
    (pad "1" smd rect (at -0.75 0 270) (size 0.8 0.8) (layers "F.Cu" "F.Paste" "F.Mask")
      (net 86 "Net-(D2-Pad1)") (pintype "passive"))
    (pad "2" smd rect (at 0.75 0 270) (size 0.8 0.8) (layers "F.Cu" "F.Paste" "F.Mask")
      (net 1 "GNDREF") (pinfunction "2") (pintype "passive"))
  )

  (footprint "sdi-mipi-bridge-footprints:Testpoint_smd_1mm" (layer "F.Cu")
    (at 122.5125 97.0398)
    (property "Author" "Antmicro")
    (property "License" "Apache-2.0")
    (property "MPN" "")
    (property "Manufacturer" "")
    (property "Sheetfile" "sdi-mipi-bridge.kicad_sch")
    (property "Sheetname" "")
    (property "ki_description" "Test Point 1mm")
    (attr smd)
    (fp_text reference "TP19" (at 0.2875 3.3602 90) (layer "F.SilkS")
        (effects (font (size 0.65 0.65) (thickness 0.15)) (justify left bottom))
    )
    (fp_text value "TP_1mm_SMD" (at 0 1.4) (layer "F.Fab") hide
        (effects (font (size 0.7 0.7) (thickness 0.15)) (justify left bottom))
    )
    (fp_text user "License: Apache-2.0" (at -0.5 5.2) (layer "F.Fab") hide
        (effects (font (size 0.7 0.7) (thickness 0.15)) (justify left bottom))
    )
    (fp_text user "${REFERENCE}" (at -0.5 2.8) (layer "F.Fab") hide
        (effects (font (size 0.7 0.7) (thickness 0.15)) (justify left bottom))
    )
    (fp_text user "Author: Antmicro" (at -0.5 4) (layer "F.Fab") hide
        (effects (font (size 0.7 0.7) (thickness 0.15)) (justify left bottom))
    )
    (pad "1" smd circle (at 0 0) (size 1 1) (layers "F.Cu" "F.Mask")
      (net 19 "/F_DE") (pinfunction "1") (pintype "passive"))
  )

  (footprint "sdi-mipi-bridge-footprints:Testpoint_smd_1mm" (layer "F.Cu")
    (at 124.329 97.0398)
    (property "Author" "Antmicro")
    (property "License" "Apache-2.0")
    (property "MPN" "")
    (property "Manufacturer" "")
    (property "Sheetfile" "sdi-mipi-bridge.kicad_sch")
    (property "Sheetname" "")
    (property "ki_description" "Test Point 1mm")
    (attr smd)
    (fp_text reference "TP20" (at 0.271 3.3602 90) (layer "F.SilkS")
        (effects (font (size 0.65 0.65) (thickness 0.15)) (justify left bottom))
    )
    (fp_text value "TP_1mm_SMD" (at 0 1.4) (layer "F.Fab") hide
        (effects (font (size 0.7 0.7) (thickness 0.15)) (justify left bottom))
    )
    (fp_text user "Author: Antmicro" (at -0.5 4) (layer "F.Fab") hide
        (effects (font (size 0.7 0.7) (thickness 0.15)) (justify left bottom))
    )
    (fp_text user "${REFERENCE}" (at -0.5 2.8) (layer "F.Fab") hide
        (effects (font (size 0.7 0.7) (thickness 0.15)) (justify left bottom))
    )
    (fp_text user "License: Apache-2.0" (at -0.5 5.2) (layer "F.Fab") hide
        (effects (font (size 0.7 0.7) (thickness 0.15)) (justify left bottom))
    )
    (pad "1" smd circle (at 0 0) (size 1 1) (layers "F.Cu" "F.Mask")
      (net 20 "/LOCKED") (pinfunction "1") (pintype "passive"))
  )

  (footprint "sdi-mipi-bridge-footprints:Testpoint_smd_1mm" (layer "F.Cu")
    (at 120.696 97.0398)
    (property "Author" "Antmicro")
    (property "License" "Apache-2.0")
    (property "MPN" "")
    (property "Manufacturer" "")
    (property "Sheetfile" "sdi-mipi-bridge.kicad_sch")
    (property "Sheetname" "")
    (property "ki_description" "Test Point 1mm")
    (attr smd)
    (fp_text reference "TP21" (at 0.304 3.3602 90) (layer "F.SilkS")
        (effects (font (size 0.65 0.65) (thickness 0.15)) (justify left bottom))
    )
    (fp_text value "TP_1mm_SMD" (at 0 1.4) (layer "F.Fab") hide
        (effects (font (size 0.7 0.7) (thickness 0.15)) (justify left bottom))
    )
    (fp_text user "${REFERENCE}" (at -0.5 2.8) (layer "F.Fab") hide
        (effects (font (size 0.7 0.7) (thickness 0.15)) (justify left bottom))
    )
    (fp_text user "Author: Antmicro" (at -0.5 4) (layer "F.Fab") hide
        (effects (font (size 0.7 0.7) (thickness 0.15)) (justify left bottom))
    )
    (fp_text user "License: Apache-2.0" (at -0.5 5.2) (layer "F.Fab") hide
        (effects (font (size 0.7 0.7) (thickness 0.15)) (justify left bottom))
    )
    (pad "1" smd circle (at 0 0) (size 1 1) (layers "F.Cu" "F.Mask")
      (net 21 "/Y_1ANC") (pinfunction "1") (pintype "passive"))
  )

  (footprint "sdi-mipi-bridge-footprints:Testpoint_smd_1mm" (layer "F.Cu")
    (at 131.6108 135.99 90)
    (property "Author" "Antmicro")
    (property "License" "Apache-2.0")
    (property "MPN" "")
    (property "Manufacturer" "")
    (property "Sheetfile" "sdi-mipi-bridge.kicad_sch")
    (property "Sheetname" "")
    (property "ki_description" "Test Point 1mm")
    (attr smd)
    (fp_text reference "TP6" (at -0.41 0.6892 180) (layer "F.SilkS")
        (effects (font (size 0.65 0.65) (thickness 0.15)) (justify left bottom))
    )
    (fp_text value "TP_1mm_SMD" (at 0 1.4 90) (layer "F.Fab") hide
        (effects (font (size 0.7 0.7) (thickness 0.15)) (justify left bottom))
    )
    (fp_text user "Author: Antmicro" (at -0.5 4 90) (layer "F.Fab") hide
        (effects (font (size 0.7 0.7) (thickness 0.15)) (justify left bottom))
    )
    (fp_text user "License: Apache-2.0" (at -0.5 5.2 90) (layer "F.Fab") hide
        (effects (font (size 0.7 0.7) (thickness 0.15)) (justify left bottom))
    )
    (fp_text user "${REFERENCE}" (at -0.5 2.8 90) (layer "F.Fab") hide
        (effects (font (size 0.7 0.7) (thickness 0.15)) (justify left bottom))
    )
    (pad "1" smd circle (at 0 0 90) (size 1 1) (layers "F.Cu" "F.Mask")
      (net 129 "Net-(U1-~{POK})") (pinfunction "1") (pintype "passive"))
  )

  (footprint "sdi-mipi-bridge-footprints:R_0402_1005Metric" (layer "F.Cu")
    (at 156.945 112.5 180)
    (descr "Resistor SMD 0402")
    (tags "resistor SMD 0402")
    (property "Author" "Antmicro")
    (property "Current" "1A")
    (property "License" "Apache-2.0")
    (property "MPN" "ERJ2GE0R00X")
    (property "Manufacturer" "Panasonic")
    (property "Sheetfile" "sdi-mipi-bridge.kicad_sch")
    (property "Sheetname" "")
    (property "Tolerance" "")
    (property "Val" "0R")
    (property "ki_description" "0R resistor in 0402 package with unspecified tolerance")
    (attr smd)
    (fp_text reference "R39" (at -2.955 -0.4) (layer "F.SilkS")
        (effects (font (size 0.65 0.65) (thickness 0.15)) (justify right bottom))
    )
    (fp_text value "R_0R_0402" (at 0 1.4) (layer "F.Fab") hide
        (effects (font (size 0.7 0.7) (thickness 0.15)) (justify right bottom))
    )
    (fp_text user "Author: Antmicro" (at -0.95 4.169) (layer "F.Fab") hide
        (effects (font (size 0.7 0.7) (thickness 0.15)) (justify right bottom))
    )
    (fp_text user "${REFERENCE}" (at -0.95 3.168) (layer "F.Fab") hide
        (effects (font (size 0.7 0.7) (thickness 0.15)) (justify right bottom))
    )
    (fp_text user "License: Apache-2.0" (at -0.95 5.169) (layer "F.Fab") hide
        (effects (font (size 0.7 0.7) (thickness 0.15)) (justify right bottom))
    )
    (fp_rect (start -0.93 -0.47) (end 0.93 0.47)
      (stroke (width 0.05) (type solid)) (fill none) (layer "F.CrtYd"))
    (fp_rect (start -0.5 -0.25) (end 0.5 0.25)
      (stroke (width 0.15) (type solid)) (fill none) (layer "F.Fab"))
    (pad "1" smd roundrect (at -0.485 0 180) (size 0.59 0.64) (layers "F.Cu" "F.Paste" "F.Mask") (roundrect_rratio 0.25)
      (net 83 "/SDA1") (pintype "passive"))
    (pad "2" smd roundrect (at 0.485 0 180) (size 0.59 0.64) (layers "F.Cu" "F.Paste" "F.Mask") (roundrect_rratio 0.25)
      (net 62 "/SDA_GS") (pintype "passive"))
  )

  (footprint "sdi-mipi-bridge-footprints:C_0402_1005Metric" (layer "F.Cu")
    (at 113.83 112.9)
    (descr "Capacitor SMD 0402")
    (tags "capacitor SMD 0402")
    (property "Author" "Antmicro")
    (property "Dielectric" "")
    (property "License" "Apache-2.0")
    (property "MPN" "C1005X6S1A105K050BC")
    (property "Manufacturer" "TDK")
    (property "Sheetfile" "sdi-mipi-bridge.kicad_sch")
    (property "Sheetname" "")
    (property "Val" "1u")
    (property "Voltage" "")
    (property "ki_description" " ")
    (attr smd)
    (fp_text reference "C55" (at -7.23 -0.925) (layer "F.SilkS")
        (effects (font (size 0.65 0.65) (thickness 0.15)) (justify left bottom))
    )
    (fp_text value "C_1u_0402" (at 0 1.4) (layer "F.Fab") hide
        (effects (font (size 0.7 0.7) (thickness 0.15)) (justify left bottom))
    )
    (fp_text user "License: Apache-2.0" (at -0.932 5.17) (layer "F.Fab") hide
        (effects (font (size 0.7 0.7) (thickness 0.15)) (justify left bottom))
    )
    (fp_text user "Author: Antmicro" (at -0.932 4.17) (layer "F.Fab") hide
        (effects (font (size 0.7 0.7) (thickness 0.15)) (justify left bottom))
    )
    (fp_text user "${REFERENCE}" (at -0.932 3.168) (layer "F.Fab") hide
        (effects (font (size 0.7 0.7) (thickness 0.15)) (justify left bottom))
    )
    (fp_rect (start -0.94 -0.47) (end 0.94 0.47)
      (stroke (width 0.05) (type solid)) (fill none) (layer "F.CrtYd"))
    (fp_rect (start -0.499 -0.249) (end 0.499 0.249)
      (stroke (width 0.15) (type solid)) (fill none) (layer "F.Fab"))
    (pad "1" smd roundrect (at -0.484 0) (size 0.59 0.64) (layers "F.Cu" "F.Paste" "F.Mask") (roundrect_rratio 0.25)
      (net 70 "Net-(C43-Pad2)") (pintype "passive"))
    (pad "2" smd roundrect (at 0.484 0) (size 0.59 0.64) (layers "F.Cu" "F.Paste" "F.Mask") (roundrect_rratio 0.25)
      (net 90 "/SDI_P") (pintype "passive"))
  )

  (footprint "sdi-mipi-bridge-footprints:R_0603_1608Metric" (layer "F.Cu")
    (at 111.47 112.2 90)
    (descr "Resistor SMD 0603")
    (tags "resistor SMD 0603")
    (property "Author" "Antmicro")
    (property "License" "Apache-2.0")
    (property "MPN" "CR0603-FX-75R0ELF")
    (property "Manufacturer" "Bourns")
    (property "Sheetfile" "sdi-mipi-bridge.kicad_sch")
    (property "Sheetname" "")
    (property "Tolerance" "1%")
    (property "Val" "75R")
    (property "ki_description" "75R resistor in 0603 package with 1% tolerance")
    (attr smd)
    (fp_text reference "R27" (at 3.4 0.33 270) (layer "F.SilkS")
        (effects (font (size 0.65 0.65) (thickness 0.15)) (justify right bottom))
    )
    (fp_text value "R_75R_0603" (at 0 1.6 90) (layer "F.Fab") hide
        (effects (font (size 0.7 0.7) (thickness 0.15)) (justify left bottom))
    )
    (fp_text user "Author: Antmicro" (at -1.25 4.9 90) (layer "F.Fab") hide
        (effects (font (size 0.7 0.7) (thickness 0.15)) (justify left bottom))
    )
    (fp_text user "${REFERENCE}" (at -1.25 3.898 90) (layer "F.Fab") hide
        (effects (font (size 0.7 0.7) (thickness 0.15)) (justify left bottom))
    )
    (fp_text user "License: Apache-2.0" (at -1.25 5.9 90) (layer "F.Fab") hide
        (effects (font (size 0.7 0.7) (thickness 0.15)) (justify left bottom))
    )
    (fp_line (start -0.3 -0.3) (end 0.3 -0.3)
      (stroke (width 0.15) (type solid)) (layer "F.SilkS"))
    (fp_line (start -0.3 0.3) (end 0.3 0.3)
      (stroke (width 0.15) (type solid)) (layer "F.SilkS"))
    (fp_rect (start -1.25 -0.7) (end 1.25 0.7)
      (stroke (width 0.05) (type solid)) (fill none) (layer "F.CrtYd"))
    (fp_rect (start -0.8 -0.4) (end 0.8 0.4)
      (stroke (width 0.15) (type solid)) (fill none) (layer "F.Fab"))
    (pad "1" smd roundrect (at -0.7 0 90) (size 0.6 0.8) (layers "F.Cu" "F.Paste" "F.Mask") (roundrect_rratio 0.2)
      (net 70 "Net-(C43-Pad2)") (pintype "passive"))
    (pad "2" smd roundrect (at 0.7 0 90) (size 0.6 0.8) (layers "F.Cu" "F.Paste" "F.Mask") (roundrect_rratio 0.2)
      (net 69 "Net-(C43-Pad1)") (pintype "passive"))
  )

  (footprint "sdi-mipi-bridge-footprints:R_0603_1608Metric" (layer "F.Cu")
    (at 113.35 110.99 90)
    (descr "Resistor SMD 0603")
    (tags "resistor SMD 0603")
    (property "Author" "Antmicro")
    (property "License" "Apache-2.0")
    (property "MPN" "CR0603-FX-75R0ELF")
    (property "Manufacturer" "Bourns")
    (property "Sheetfile" "sdi-mipi-bridge.kicad_sch")
    (property "Sheetname" "")
    (property "Tolerance" "1%")
    (property "Val" "75R")
    (property "ki_description" "75R resistor in 0603 package with 1% tolerance")
    (attr smd)
    (fp_text reference "R28" (at 3.59 0.25 90) (layer "F.SilkS")
        (effects (font (size 0.65 0.65) (thickness 0.15)) (justify right bottom))
    )
    (fp_text value "R_75R_0603" (at 0 1.6 90) (layer "F.Fab") hide
        (effects (font (size 0.7 0.7) (thickness 0.15)) (justify left bottom))
    )
    (fp_text user "Author: Antmicro" (at -1.25 4.9 90) (layer "F.Fab") hide
        (effects (font (size 0.7 0.7) (thickness 0.15)) (justify left bottom))
    )
    (fp_text user "License: Apache-2.0" (at -1.25 5.9 90) (layer "F.Fab") hide
        (effects (font (size 0.7 0.7) (thickness 0.15)) (justify left bottom))
    )
    (fp_text user "${REFERENCE}" (at -1.25 3.898 90) (layer "F.Fab") hide
        (effects (font (size 0.7 0.7) (thickness 0.15)) (justify left bottom))
    )
    (fp_line (start -0.3 -0.3) (end 0.3 -0.3)
      (stroke (width 0.15) (type solid)) (layer "F.SilkS"))
    (fp_line (start -0.3 0.3) (end 0.3 0.3)
      (stroke (width 0.15) (type solid)) (layer "F.SilkS"))
    (fp_rect (start -1.25 -0.7) (end 1.25 0.7)
      (stroke (width 0.05) (type solid)) (fill none) (layer "F.CrtYd"))
    (fp_rect (start -0.8 -0.4) (end 0.8 0.4)
      (stroke (width 0.15) (type solid)) (fill none) (layer "F.Fab"))
    (pad "1" smd roundrect (at -0.7 0 90) (size 0.6 0.8) (layers "F.Cu" "F.Paste" "F.Mask") (roundrect_rratio 0.2)
      (net 70 "Net-(C43-Pad2)") (pintype "passive"))
    (pad "2" smd roundrect (at 0.7 0 90) (size 0.6 0.8) (layers "F.Cu" "F.Paste" "F.Mask") (roundrect_rratio 0.2)
      (net 3 "GNDA") (pintype "passive"))
  )

  (footprint "sdi-mipi-bridge-footprints:C_0402_1005Metric" (layer "F.Cu")
    (at 113.82 113.9)
    (descr "Capacitor SMD 0402")
    (tags "capacitor SMD 0402")
    (property "Author" "Antmicro")
    (property "Dielectric" "")
    (property "License" "Apache-2.0")
    (property "MPN" "C1005X6S1A105K050BC")
    (property "Manufacturer" "TDK")
    (property "Sheetfile" "sdi-mipi-bridge.kicad_sch")
    (property "Sheetname" "")
    (property "Val" "1u")
    (property "Voltage" "")
    (property "ki_description" " ")
    (attr smd)
    (fp_text reference "C56" (at -7.22 -0.85) (layer "F.SilkS")
        (effects (font (size 0.65 0.65) (thickness 0.15)) (justify left bottom))
    )
    (fp_text value "C_1u_0402" (at 0 1.4) (layer "F.Fab") hide
        (effects (font (size 0.7 0.7) (thickness 0.15)) (justify left bottom))
    )
    (fp_text user "Author: Antmicro" (at -0.932 4.17) (layer "F.Fab") hide
        (effects (font (size 0.7 0.7) (thickness 0.15)) (justify left bottom))
    )
    (fp_text user "License: Apache-2.0" (at -0.932 5.17) (layer "F.Fab") hide
        (effects (font (size 0.7 0.7) (thickness 0.15)) (justify left bottom))
    )
    (fp_text user "${REFERENCE}" (at -0.932 3.168) (layer "F.Fab") hide
        (effects (font (size 0.7 0.7) (thickness 0.15)) (justify left bottom))
    )
    (fp_rect (start -0.94 -0.47) (end 0.94 0.47)
      (stroke (width 0.05) (type solid)) (fill none) (layer "F.CrtYd"))
    (fp_rect (start -0.499 -0.249) (end 0.499 0.249)
      (stroke (width 0.15) (type solid)) (fill none) (layer "F.Fab"))
    (pad "1" smd roundrect (at -0.484 0) (size 0.59 0.64) (layers "F.Cu" "F.Paste" "F.Mask") (roundrect_rratio 0.25)
      (net 142 "Net-(C56-Pad1)") (pintype "passive"))
    (pad "2" smd roundrect (at 0.484 0) (size 0.59 0.64) (layers "F.Cu" "F.Paste" "F.Mask") (roundrect_rratio 0.25)
      (net 92 "/SDI_N") (pintype "passive"))
  )

  (footprint "sdi-mipi-bridge-footprints:C_0603_1608Metric" (layer "F.Cu")
    (at 109.5 112.2 -90)
    (descr "Capacitor SMD 0603")
    (tags "capacitor 0603")
    (property "Author" "Antmicro")
    (property "Dielectric" "")
    (property "License" "Apache-2.0")
    (property "MPN" "C0603C622J5GACAUTO")
    (property "Manufacturer" "KEMET")
    (property "Sheetfile" "sdi-mipi-bridge.kicad_sch")
    (property "Sheetname" "")
    (property "Val" "6n2")
    (property "Voltage" "")
    (property "ki_description" " ")
    (attr smd)
    (fp_text reference "C43" (at -3.4 -0.3 -90) (layer "F.SilkS")
        (effects (font (size 0.65 0.65) (thickness 0.15)) (justify right bottom))
    )
    (fp_text value "C_6n2_0603" (at 0 1.6 90) (layer "F.Fab") hide
        (effects (font (size 0.7 0.7) (thickness 0.15)) (justify right bottom))
    )
    (fp_text user "License: Apache-2.0" (at -1.682 5.895 90) (layer "F.Fab") hide
        (effects (font (size 0.7 0.7) (thickness 0.15)) (justify right bottom))
    )
    (fp_text user "${REFERENCE}" (at -1.682 3.895 90) (layer "F.Fab") hide
        (effects (font (size 0.7 0.7) (thickness 0.15)) (justify right bottom))
    )
    (fp_text user "Author: Antmicro" (at -1.682 4.894 90) (layer "F.Fab") hide
        (effects (font (size 0.7 0.7) (thickness 0.15)) (justify right bottom))
    )
    (fp_line (start -0.3 -0.3) (end 0.3 -0.3)
      (stroke (width 0.15) (type solid)) (layer "F.SilkS"))
    (fp_line (start -0.3 0.3) (end 0.3 0.3)
      (stroke (width 0.15) (type solid)) (layer "F.SilkS"))
    (fp_rect (start -1.24 -0.7) (end 1.24 0.7)
      (stroke (width 0.05) (type solid)) (fill none) (layer "F.CrtYd"))
    (fp_rect (start -0.8 -0.4) (end 0.8 0.4)
      (stroke (width 0.15) (type solid)) (fill none) (layer "F.Fab"))
    (pad "1" smd roundrect (at -0.7 0 270) (size 0.6 0.8) (layers "F.Cu" "F.Paste" "F.Mask") (roundrect_rratio 0.2)
      (net 69 "Net-(C43-Pad1)") (pintype "passive"))
    (pad "2" smd roundrect (at 0.7 0 270) (size 0.6 0.8) (layers "F.Cu" "F.Paste" "F.Mask") (roundrect_rratio 0.2)
      (net 70 "Net-(C43-Pad2)") (pintype "passive"))
  )

  (footprint "sdi-mipi-bridge-footprints:R_0402_1005Metric" (layer "F.Cu")
    (at 112.84 114.95 180)
    (descr "Resistor SMD 0402")
    (tags "resistor SMD 0402")
    (property "Author" "Antmicro")
    (property "License" "Apache-2.0")
    (property "MPN" "CR0402-FX-37R4GLF")
    (property "Manufacturer" "Bourns")
    (property "Sheetfile" "sdi-mipi-bridge.kicad_sch")
    (property "Sheetname" "")
    (property "Tolerance" "1%")
    (property "Val" "37R4")
    (property "ki_description" "37R4 resistor in 0402 package with 1% tolerance")
    (attr smd)
    (fp_text reference "R29" (at 6.74 0.85 180) (layer "F.SilkS")
        (effects (font (size 0.65 0.65) (thickness 0.15)) (justify bottom))
    )
    (fp_text value "R_37R4_0402" (at 0 1.4 180) (layer "F.Fab") hide
        (effects (font (size 0.7 0.7) (thickness 0.15)) (justify left bottom))
    )
    (fp_text user "License: Apache-2.0" (at -0.95 5.169 180) (layer "F.Fab") hide
        (effects (font (size 0.7 0.7) (thickness 0.15)) (justify left bottom))
    )
    (fp_text user "Author: Antmicro" (at -0.95 4.169 180) (layer "F.Fab") hide
        (effects (font (size 0.7 0.7) (thickness 0.15)) (justify left bottom))
    )
    (fp_text user "${REFERENCE}" (at -0.95 3.168 180) (layer "F.Fab") hide
        (effects (font (size 0.7 0.7) (thickness 0.15)) (justify left bottom))
    )
    (fp_rect (start -0.93 -0.47) (end 0.93 0.47)
      (stroke (width 0.05) (type solid)) (fill none) (layer "F.CrtYd"))
    (fp_rect (start -0.5 -0.25) (end 0.5 0.25)
      (stroke (width 0.15) (type solid)) (fill none) (layer "F.Fab"))
    (pad "1" smd roundrect (at -0.485 0 180) (size 0.59 0.64) (layers "F.Cu" "F.Paste" "F.Mask") (roundrect_rratio 0.25)
      (net 142 "Net-(C56-Pad1)") (pintype "passive"))
    (pad "2" smd roundrect (at 0.485 0 180) (size 0.59 0.64) (layers "F.Cu" "F.Paste" "F.Mask") (roundrect_rratio 0.25)
      (net 3 "GNDA") (pintype "passive"))
  )

  (footprint "sdi-mipi-bridge-footprints:QFN-16_1EP_4x4mm_P0.65mm" (layer "F.Cu")
    (at 111.9 120.9 180)
    (property "Author" "Antmicro")
    (property "License" "Apache-2.0")
    (property "MPN" "GS2988-INE3")
    (property "Manufacturer" "Semtech")
    (property "Sheetfile" "sdi-mipi-bridge.kicad_sch")
    (property "Sheetname" "")
    (property "ki_description" "LVPECL/CML Cable driver 3Gb/s")
    (property "ki_keywords" "LVPECL/CML Cable driver 3Gb/s")
    (attr smd)
    (fp_text reference "U3" (at -2.4 -1.9 180) (layer "F.SilkS")
        (effects (font (size 0.65 0.65) (thickness 0.15)) (justify left bottom))
    )
    (fp_text value "GS2988" (at 0 3.3 180) (layer "F.Fab") hide
        (effects (font (size 0.7 0.7) (thickness 0.15)) (justify left bottom))
    )
    (fp_text user "License: Apache-2.0" (at -2.35 7.999 180) (layer "F.Fab") hide
        (effects (font (size 0.7 0.7) (thickness 0.15)) (justify left bottom))
    )
    (fp_text user "Author: Antmicro" (at -2.35 6.799 180) (layer "F.Fab") hide
        (effects (font (size 0.7 0.7) (thickness 0.15)) (justify left bottom))
    )
    (fp_text user "${REFERENCE}" (at -2.35 5.599 180) (layer "F.Fab") hide
        (effects (font (size 0.7 0.7) (thickness 0.15)) (justify left bottom))
    )
    (fp_line (start -2.101 1.398) (end -2.101 2.1)
      (stroke (width 0.15) (type solid)) (layer "F.SilkS"))
    (fp_line (start -2.101 2.1) (end -1.5 2.1)
      (stroke (width 0.15) (type solid)) (layer "F.SilkS"))
    (fp_line (start -2.1 -2.1) (end -2.101 -1.4)
      (stroke (width 0.15) (type solid)) (layer "F.SilkS"))
    (fp_line (start -1.4 -2.1) (end -2.1 -2.1)
      (stroke (width 0.15) (type solid)) (layer "F.SilkS"))
    (fp_line (start 1.499 -2.101) (end 2.1 -2.101)
      (stroke (width 0.15) (type solid)) (layer "F.SilkS"))
    (fp_line (start 1.499 2.1) (end 2.1 2.1)
      (stroke (width 0.15) (type solid)) (layer "F.SilkS"))
    (fp_line (start 2.1 -2.101) (end 2.1 -1.401)
      (stroke (width 0.15) (type solid)) (layer "F.SilkS"))
    (fp_line (start 2.1 2.1) (end 2.1 1.398)
      (stroke (width 0.15) (type solid)) (layer "F.SilkS"))
    (fp_circle (center -2.35 -1.4) (end -2.3 -1.4)
      (stroke (width 0.15) (type solid)) (fill solid) (layer "F.SilkS"))
    (fp_rect (start -2.35 -2.35) (end 2.35 2.35)
      (stroke (width 0.05) (type solid)) (fill none) (layer "F.CrtYd"))
    (fp_line (start -1.5 -2) (end -2 -1.5)
      (stroke (width 0.15) (type solid)) (layer "F.Fab"))
    (fp_rect (start 2 2) (end -2 -2)
      (stroke (width 0.15) (type solid)) (fill none) (layer "F.Fab"))
    (pad "1" smd rect (at -1.901 -0.975 180) (size 0.8 0.4) (layers "F.Cu" "F.Paste" "F.Mask")
      (net 94 "/SDO_P") (pinfunction "DDI+") (pintype "input"))
    (pad "2" smd rect (at -1.901 -0.327 180) (size 0.8 0.4) (layers "F.Cu" "F.Paste" "F.Mask")
      (net 93 "/SDO_N") (pinfunction "DDI-") (pintype "input"))
    (pad "3" smd rect (at -1.901 0.325 180) (size 0.8 0.4) (layers "F.Cu" "F.Paste" "F.Mask")
      (net 3 "GNDA") (pinfunction "V_{EE}") (pintype "power_in"))
    (pad "4" smd rect (at -1.901 0.973 180) (size 0.8 0.4) (layers "F.Cu" "F.Paste" "F.Mask")
      (net 67 "Net-(U3-RSET)") (pinfunction "RSET") (pintype "passive"))
    (pad "5" smd rect (at -0.975 1.898 180) (size 0.4 0.8) (layers "F.Cu" "F.Paste" "F.Mask")
      (net 134 "unconnected-(U3-NC-Pad5)") (pinfunction "NC") (pintype "no_connect"))
    (pad "6" smd rect (at -0.327 1.898 180) (size 0.4 0.8) (layers "F.Cu" "F.Paste" "F.Mask")
      (net 55 "/SDO_EN_DIS") (pinfunction "~{DISABLE}") (pintype "input"))
    (pad "7" smd rect (at 0.325 1.898 180) (size 0.4 0.8) (layers "F.Cu" "F.Paste" "F.Mask")
      (net 135 "unconnected-(U3-NC-Pad7)") (pinfunction "NC") (pintype "no_connect"))
    (pad "8" smd rect (at 0.973 1.898 180) (size 0.4 0.8) (layers "F.Cu" "F.Paste" "F.Mask")
      (net 137 "unconnected-(U3-NC-Pad8)") (pinfunction "NC") (pintype "no_connect"))
    (pad "9" smd rect (at 1.898 0.973 180) (size 0.8 0.4) (layers "F.Cu" "F.Paste" "F.Mask")
      (net 57 "VDD") (pinfunction "V_{CC}") (pintype "power_in"))
    (pad "10" smd rect (at 1.898 0.325 180) (size 0.8 0.4) (layers "F.Cu" "F.Paste" "F.Mask")
      (net 3 "GNDA") (pinfunction "SD/~{HD}") (pintype "input"))
    (pad "11" smd rect (at 1.898 -0.327 180) (size 0.8 0.4) (layers "F.Cu" "F.Paste" "F.Mask")
      (net 29 "Net-(U3-SDO-)") (pinfunction "SDO-") (pintype "output"))
    (pad "12" smd rect (at 1.898 -0.975 180) (size 0.8 0.4) (layers "F.Cu" "F.Paste" "F.Mask")
      (net 27 "Net-(U3-SDO+)") (pinfunction "SDO+") (pintype "output"))
    (pad "13" smd rect (at 0.973 -1.901 180) (size 0.4 0.8) (layers "F.Cu" "F.Paste" "F.Mask")
      (net 138 "unconnected-(U3-NC-Pad13)") (pinfunction "NC") (pintype "no_connect"))
    (pad "14" smd rect (at 0.325 -1.901 180) (size 0.4 0.8) (layers "F.Cu" "F.Paste" "F.Mask")
      (net 131 "Net-(U3-~{OSP})") (pinfunction "~{OSP}") (pintype "output"))
    (pad "15" smd rect (at -0.327 -1.901 180) (size 0.4 0.8) (layers "F.Cu" "F.Paste" "F.Mask")
      (net 139 "unconnected-(U3-NC-Pad15)") (pinfunction "NC") (pintype "no_connect"))
    (pad "16" smd rect (at -0.975 -1.901 180) (size 0.4 0.8) (layers "F.Cu" "F.Paste" "F.Mask")
      (net 73 "Net-(U3-~{EQ_EN})") (pinfunction "~{EQ_EN}") (pintype "input"))
    (pad "17" smd rect (at 0 0 180) (size 2.3 2.3) (layers "F.Cu" "F.Paste" "F.Mask")
      (net 3 "GNDA") (pinfunction "EP") (pintype "passive"))
  )

  (footprint "sdi-mipi-bridge-footprints:Testpoint_smd_1mm" (layer "F.Cu")
    (at 111.61 124.19 180)
    (property "Author" "Antmicro")
    (property "License" "Apache-2.0")
    (property "MPN" "")
    (property "Manufacturer" "")
    (property "Sheetfile" "sdi-mipi-bridge.kicad_sch")
    (property "Sheetname" "")
    (property "ki_description" "Test Point 1mm")
    (attr smd)
    (fp_text reference "TP18" (at -1.39 -1.31) (layer "F.SilkS")
        (effects (font (size 0.65 0.65) (thickness 0.15)) (justify right bottom))
    )
    (fp_text value "TP_1mm_SMD" (at 0 1.4) (layer "F.Fab") hide
        (effects (font (size 0.7 0.7) (thickness 0.15)) (justify right bottom))
    )
    (fp_text user "${REFERENCE}" (at -0.5 2.8) (layer "F.Fab") hide
        (effects (font (size 0.7 0.7) (thickness 0.15)) (justify right bottom))
    )
    (fp_text user "Author: Antmicro" (at -0.5 4) (layer "F.Fab") hide
        (effects (font (size 0.7 0.7) (thickness 0.15)) (justify right bottom))
    )
    (fp_text user "License: Apache-2.0" (at -0.5 5.2) (layer "F.Fab") hide
        (effects (font (size 0.7 0.7) (thickness 0.15)) (justify right bottom))
    )
    (pad "1" smd circle (at 0 0 180) (size 1 1) (layers "F.Cu" "F.Mask")
      (net 131 "Net-(U3-~{OSP})") (pinfunction "1") (pintype "passive"))
  )

  (footprint "sdi-mipi-bridge-footprints:C_0402_1005Metric" (layer "F.Cu")
    (at 106.95 122.8 90)
    (descr "Capacitor SMD 0402")
    (tags "capacitor SMD 0402")
    (property "Author" "Antmicro")
    (property "Dielectric" "")
    (property "License" "Apache-2.0")
    (property "MPN" "GRM155R61A475MEAAD")
    (property "Manufacturer" "Murata")
    (property "Sheetfile" "sdi-mipi-bridge.kicad_sch")
    (property "Sheetname" "")
    (property "Val" "4u7")
    (property "Voltage" "")
    (property "ki_description" " ")
    (attr smd)
    (fp_text reference "C23" (at -10.1 1.65 90) (layer "F.SilkS")
        (effects (font (size 0.65 0.65) (thickness 0.15)) (justify left bottom))
    )
    (fp_text value "C_4u7_0402" (at 0 1.4 90) (layer "F.Fab") hide
        (effects (font (size 0.7 0.7) (thickness 0.15)) (justify left bottom))
    )
    (fp_text user "License: Apache-2.0" (at -0.932 5.17 90) (layer "F.Fab") hide
        (effects (font (size 0.7 0.7) (thickness 0.15)) (justify left bottom))
    )
    (fp_text user "Author: Antmicro" (at -0.932 4.17 90) (layer "F.Fab") hide
        (effects (font (size 0.7 0.7) (thickness 0.15)) (justify left bottom))
    )
    (fp_text user "${REFERENCE}" (at -0.932 3.168 90) (layer "F.Fab") hide
        (effects (font (size 0.7 0.7) (thickness 0.15)) (justify left bottom))
    )
    (fp_rect (start -0.94 -0.47) (end 0.94 0.47)
      (stroke (width 0.05) (type solid)) (fill none) (layer "F.CrtYd"))
    (fp_rect (start -0.499 -0.249) (end 0.499 0.249)
      (stroke (width 0.15) (type solid)) (fill none) (layer "F.Fab"))
    (pad "1" smd roundrect (at -0.484 0 90) (size 0.59 0.64) (layers "F.Cu" "F.Paste" "F.Mask") (roundrect_rratio 0.25)
      (net 65 "Net-(C23-Pad1)") (pintype "passive"))
    (pad "2" smd roundrect (at 0.484 0 90) (size 0.59 0.64) (layers "F.Cu" "F.Paste" "F.Mask") (roundrect_rratio 0.25)
      (net 27 "Net-(U3-SDO+)") (pintype "passive"))
  )

  (footprint "sdi-mipi-bridge-footprints:R_0603_1608Metric" (layer "F.Cu")
    (at 107.65 125.15 180)
    (descr "Resistor SMD 0603")
    (tags "resistor SMD 0603")
    (property "Author" "Antmicro")
    (property "License" "Apache-2.0")
    (property "MPN" "CR0603-FX-75R0ELF")
    (property "Manufacturer" "Bourns")
    (property "Sheetfile" "sdi-mipi-bridge.kicad_sch")
    (property "Sheetname" "")
    (property "Tolerance" "1%")
    (property "Val" "75R")
    (property "ki_description" "75R resistor in 0603 package with 1% tolerance")
    (attr smd)
    (fp_text reference "R20" (at -0.15 -9.35 180) (layer "F.SilkS")
        (effects (font (size 0.65 0.65) (thickness 0.15)) (justify left bottom))
    )
    (fp_text value "R_75R_0603" (at 0 1.6 180) (layer "F.Fab") hide
        (effects (font (size 0.7 0.7) (thickness 0.15)) (justify left bottom))
    )
    (fp_text user "${REFERENCE}" (at -1.25 3.898 180) (layer "F.Fab") hide
        (effects (font (size 0.7 0.7) (thickness 0.15)) (justify left bottom))
    )
    (fp_text user "License: Apache-2.0" (at -1.25 5.9 180) (layer "F.Fab") hide
        (effects (font (size 0.7 0.7) (thickness 0.15)) (justify left bottom))
    )
    (fp_text user "Author: Antmicro" (at -1.25 4.9 180) (layer "F.Fab") hide
        (effects (font (size 0.7 0.7) (thickness 0.15)) (justify left bottom))
    )
    (fp_line (start -0.3 -0.3) (end 0.3 -0.3)
      (stroke (width 0.15) (type solid)) (layer "F.SilkS"))
    (fp_line (start -0.3 0.3) (end 0.3 0.3)
      (stroke (width 0.15) (type solid)) (layer "F.SilkS"))
    (fp_rect (start -1.25 -0.7) (end 1.25 0.7)
      (stroke (width 0.05) (type solid)) (fill none) (layer "F.CrtYd"))
    (fp_rect (start -0.8 -0.4) (end 0.8 0.4)
      (stroke (width 0.15) (type solid)) (fill none) (layer "F.Fab"))
    (pad "1" smd roundrect (at -0.7 0 180) (size 0.6 0.8) (layers "F.Cu" "F.Paste" "F.Mask") (roundrect_rratio 0.2)
      (net 3 "GNDA") (pintype "passive"))
    (pad "2" smd roundrect (at 0.7 0 180) (size 0.6 0.8) (layers "F.Cu" "F.Paste" "F.Mask") (roundrect_rratio 0.2)
      (net 65 "Net-(C23-Pad1)") (pintype "passive"))
  )

  (footprint "sdi-mipi-bridge-footprints:R_0603_1608Metric" (layer "F.Cu")
    (at 108.35 122.9 -90)
    (descr "Resistor SMD 0603")
    (tags "resistor SMD 0603")
    (property "Author" "Antmicro")
    (property "License" "Apache-2.0")
    (property "MPN" "CR0603-FX-75R0ELF")
    (property "Manufacturer" "Bourns")
    (property "Sheetfile" "sdi-mipi-bridge.kicad_sch")
    (property "Sheetname" "")
    (property "Tolerance" "1%")
    (property "Val" "75R")
    (property "ki_description" "75R resistor in 0603 package with 1% tolerance")
    (attr smd)
    (fp_text reference "R18" (at 8 -1.45 90) (layer "F.SilkS")
        (effects (font (size 0.65 0.65) (thickness 0.15)) (justify right bottom))
    )
    (fp_text value "R_75R_0603" (at 0 1.6 90) (layer "F.Fab") hide
        (effects (font (size 0.7 0.7) (thickness 0.15)) (justify right bottom))
    )
    (fp_text user "${REFERENCE}" (at -1.25 3.898 90) (layer "F.Fab") hide
        (effects (font (size 0.7 0.7) (thickness 0.15)) (justify right bottom))
    )
    (fp_text user "Author: Antmicro" (at -1.25 4.9 90) (layer "F.Fab") hide
        (effects (font (size 0.7 0.7) (thickness 0.15)) (justify right bottom))
    )
    (fp_text user "License: Apache-2.0" (at -1.25 5.9 90) (layer "F.Fab") hide
        (effects (font (size 0.7 0.7) (thickness 0.15)) (justify right bottom))
    )
    (fp_line (start -0.3 -0.3) (end 0.3 -0.3)
      (stroke (width 0.15) (type solid)) (layer "F.SilkS"))
    (fp_line (start -0.3 0.3) (end 0.3 0.3)
      (stroke (width 0.15) (type solid)) (layer "F.SilkS"))
    (fp_rect (start -1.25 -0.7) (end 1.25 0.7)
      (stroke (width 0.05) (type solid)) (fill none) (layer "F.CrtYd"))
    (fp_rect (start -0.8 -0.4) (end 0.8 0.4)
      (stroke (width 0.15) (type solid)) (fill none) (layer "F.Fab"))
    (pad "1" smd roundrect (at -0.7 0 270) (size 0.6 0.8) (layers "F.Cu" "F.Paste" "F.Mask") (roundrect_rratio 0.2)
      (net 27 "Net-(U3-SDO+)") (pintype "passive"))
    (pad "2" smd roundrect (at 0.7 0 270) (size 0.6 0.8) (layers "F.Cu" "F.Paste" "F.Mask") (roundrect_rratio 0.2)
      (net 57 "VDD") (pintype "passive"))
  )

  (footprint "sdi-mipi-bridge-footprints:C_0402_1005Metric" (layer "F.Cu")
    (at 107.9 118.18 180)
    (descr "Capacitor SMD 0402")
    (tags "capacitor SMD 0402")
    (property "Author" "Antmicro")
    (property "Dielectric" "X7R")
    (property "License" "Apache-2.0")
    (property "MPN" "GRM155R71H103KA88D")
    (property "Manufacturer" "Murata")
    (property "Sheetfile" "sdi-mipi-bridge.kicad_sch")
    (property "Sheetname" "")
    (property "Val" "10n")
    (property "Voltage" "50V")
    (property "ki_description" " ")
    (attr smd)
    (fp_text reference "C36" (at -1 0.48) (layer "F.SilkS")
        (effects (font (size 0.65 0.65) (thickness 0.15)) (justify right bottom))
    )
    (fp_text value "C_10n_0402" (at 0 1.4) (layer "F.Fab") hide
        (effects (font (size 0.7 0.7) (thickness 0.15)) (justify right bottom))
    )
    (fp_text user "${REFERENCE}" (at -0.932 3.168) (layer "F.Fab") hide
        (effects (font (size 0.7 0.7) (thickness 0.15)) (justify right bottom))
    )
    (fp_text user "License: Apache-2.0" (at -0.932 5.17) (layer "F.Fab") hide
        (effects (font (size 0.7 0.7) (thickness 0.15)) (justify right bottom))
    )
    (fp_text user "Author: Antmicro" (at -0.932 4.17) (layer "F.Fab") hide
        (effects (font (size 0.7 0.7) (thickness 0.15)) (justify right bottom))
    )
    (fp_rect (start -0.94 -0.47) (end 0.94 0.47)
      (stroke (width 0.05) (type solid)) (fill none) (layer "F.CrtYd"))
    (fp_rect (start -0.499 -0.249) (end 0.499 0.249)
      (stroke (width 0.15) (type solid)) (fill none) (layer "F.Fab"))
    (pad "1" smd roundrect (at -0.484 0 180) (size 0.59 0.64) (layers "F.Cu" "F.Paste" "F.Mask") (roundrect_rratio 0.25)
      (net 57 "VDD") (pintype "passive"))
    (pad "2" smd roundrect (at 0.484 0 180) (size 0.59 0.64) (layers "F.Cu" "F.Paste" "F.Mask") (roundrect_rratio 0.25)
      (net 3 "GNDA") (pintype "passive"))
  )

  (footprint "sdi-mipi-bridge-footprints:C_0402_1005Metric" (layer "F.Cu")
    (at 105.55 122.8 -90)
    (descr "Capacitor SMD 0402")
    (tags "capacitor SMD 0402")
    (property "Author" "Antmicro")
    (property "Dielectric" "")
    (property "License" "Apache-2.0")
    (property "MPN" "GRM155R61A475MEAAD")
    (property "Manufacturer" "Murata")
    (property "Sheetfile" "sdi-mipi-bridge.kicad_sch")
    (property "Sheetname" "")
    (property "Val" "4u7")
    (property "Voltage" "")
    (property "ki_description" " ")
    (attr smd)
    (fp_text reference "C31" (at 8.1 -1.65 90) (layer "F.SilkS")
        (effects (font (size 0.65 0.65) (thickness 0.15)) (justify right bottom))
    )
    (fp_text value "C_4u7_0402" (at 0 1.4 90) (layer "F.Fab") hide
        (effects (font (size 0.7 0.7) (thickness 0.15)) (justify right bottom))
    )
    (fp_text user "License: Apache-2.0" (at -0.932 5.17 90) (layer "F.Fab") hide
        (effects (font (size 0.7 0.7) (thickness 0.15)) (justify right bottom))
    )
    (fp_text user "Author: Antmicro" (at -0.932 4.17 90) (layer "F.Fab") hide
        (effects (font (size 0.7 0.7) (thickness 0.15)) (justify right bottom))
    )
    (fp_text user "${REFERENCE}" (at -0.932 3.168 90) (layer "F.Fab") hide
        (effects (font (size 0.7 0.7) (thickness 0.15)) (justify right bottom))
    )
    (fp_rect (start -0.94 -0.47) (end 0.94 0.47)
      (stroke (width 0.05) (type solid)) (fill none) (layer "F.CrtYd"))
    (fp_rect (start -0.499 -0.249) (end 0.499 0.249)
      (stroke (width 0.15) (type solid)) (fill none) (layer "F.Fab"))
    (pad "1" smd roundrect (at -0.484 0 270) (size 0.59 0.64) (layers "F.Cu" "F.Paste" "F.Mask") (roundrect_rratio 0.25)
      (net 68 "Net-(C27-Pad2)") (pintype "passive"))
    (pad "2" smd roundrect (at 0.484 0 270) (size 0.59 0.64) (layers "F.Cu" "F.Paste" "F.Mask") (roundrect_rratio 0.25)
      (net 140 "Net-(C31-Pad2)") (pintype "passive"))
  )

  (footprint "sdi-mipi-bridge-footprints:R_0402_1005Metric" (layer "F.Cu")
    (at 114.3 124.282 180)
    (descr "Resistor SMD 0402")
    (tags "resistor SMD 0402")
    (property "Author" "Antmicro")
    (property "Current" "1A")
    (property "License" "Apache-2.0")
    (property "MPN" "ERJ2GE0R00X")
    (property "Manufacturer" "Panasonic")
    (property "Sheetfile" "sdi-mipi-bridge.kicad_sch")
    (property "Sheetname" "")
    (property "Tolerance" "")
    (property "Val" "0R")
    (property "ki_description" "0R resistor in 0402 package with unspecified tolerance")
    (attr smd)
    (fp_text reference "R71" (at 1 -2.318 180) (layer "F.SilkS")
        (effects (font (size 0.65 0.65) (thickness 0.15)) (justify left bottom))
    )
    (fp_text value "R_0R_0402" (at 0 1.4 180) (layer "F.Fab") hide
        (effects (font (size 0.7 0.7) (thickness 0.15)) (justify left bottom))
    )
    (fp_text user "Author: Antmicro" (at -0.95 4.169 180) (layer "F.Fab") hide
        (effects (font (size 0.7 0.7) (thickness 0.15)) (justify left bottom))
    )
    (fp_text user "${REFERENCE}" (at -0.95 3.168 180) (layer "F.Fab") hide
        (effects (font (size 0.7 0.7) (thickness 0.15)) (justify left bottom))
    )
    (fp_text user "License: Apache-2.0" (at -0.95 5.169 180) (layer "F.Fab") hide
        (effects (font (size 0.7 0.7) (thickness 0.15)) (justify left bottom))
    )
    (fp_rect (start -0.93 -0.47) (end 0.93 0.47)
      (stroke (width 0.05) (type solid)) (fill none) (layer "F.CrtYd"))
    (fp_rect (start -0.5 -0.25) (end 0.5 0.25)
      (stroke (width 0.15) (type solid)) (fill none) (layer "F.Fab"))
    (pad "1" smd roundrect (at -0.485 0 180) (size 0.59 0.64) (layers "F.Cu" "F.Paste" "F.Mask") (roundrect_rratio 0.25)
      (net 57 "VDD") (pintype "passive"))
    (pad "2" smd roundrect (at 0.485 0 180) (size 0.59 0.64) (layers "F.Cu" "F.Paste" "F.Mask") (roundrect_rratio 0.25)
      (net 73 "Net-(U3-~{EQ_EN})") (pintype "passive"))
  )

  (footprint "sdi-mipi-bridge-footprints:C_0402_1005Metric" (layer "F.Cu")
    (at 106.25 119.52 180)
    (descr "Capacitor SMD 0402")
    (tags "capacitor SMD 0402")
    (property "Author" "Antmicro")
    (property "Dielectric" "")
    (property "License" "Apache-2.0")
    (property "MPN" "MC0402B562K160CT")
    (property "Manufacturer" "Multicomp")
    (property "Sheetfile" "sdi-mipi-bridge.kicad_sch")
    (property "Sheetname" "")
    (property "Val" "5n6")
    (property "Voltage" "")
    (property "ki_description" " ")
    (attr smd)
    (fp_text reference "C27" (at -2.15 -9.58) (layer "F.SilkS")
        (effects (font (size 0.65 0.65) (thickness 0.15)) (justify right bottom))
    )
    (fp_text value "C_5n6_0402" (at 0 1.4) (layer "F.Fab") hide
        (effects (font (size 0.7 0.7) (thickness 0.15)) (justify right bottom))
    )
    (fp_text user "Author: Antmicro" (at -0.932 4.17) (layer "F.Fab") hide
        (effects (font (size 0.7 0.7) (thickness 0.15)) (justify right bottom))
    )
    (fp_text user "License: Apache-2.0" (at -0.932 5.17) (layer "F.Fab") hide
        (effects (font (size 0.7 0.7) (thickness 0.15)) (justify right bottom))
    )
    (fp_text user "${REFERENCE}" (at -0.932 3.168) (layer "F.Fab") hide
        (effects (font (size 0.7 0.7) (thickness 0.15)) (justify right bottom))
    )
    (fp_rect (start -0.94 -0.47) (end 0.94 0.47)
      (stroke (width 0.05) (type solid)) (fill none) (layer "F.CrtYd"))
    (fp_rect (start -0.499 -0.249) (end 0.499 0.249)
      (stroke (width 0.15) (type solid)) (fill none) (layer "F.Fab"))
    (pad "1" smd roundrect (at -0.484 0 180) (size 0.59 0.64) (layers "F.Cu" "F.Paste" "F.Mask") (roundrect_rratio 0.25)
      (net 29 "Net-(U3-SDO-)") (pintype "passive"))
    (pad "2" smd roundrect (at 0.484 0 180) (size 0.59 0.64) (layers "F.Cu" "F.Paste" "F.Mask") (roundrect_rratio 0.25)
      (net 68 "Net-(C27-Pad2)") (pintype "passive"))
  )

  (footprint "sdi-mipi-bridge-footprints:C_0402_1005Metric" (layer "F.Cu")
    (at 113.76 116.4)
    (descr "Capacitor SMD 0402")
    (tags "capacitor SMD 0402")
    (property "Author" "Antmicro")
    (property "Dielectric" "")
    (property "License" "Apache-2.0")
    (property "MPN" "C1005X5R1E474M050BB")
    (property "Manufacturer" "TDK")
    (property "Sheetfile" "sdi-mipi-bridge.kicad_sch")
    (property "Sheetname" "")
    (property "Val" "470n")
    (property "Voltage" "")
    (property "ki_description" " ")
    (attr smd)
    (fp_text reference "C64" (at -7.16 -0.9) (layer "F.SilkS")
        (effects (font (size 0.65 0.65) (thickness 0.15)) (justify left bottom))
    )
    (fp_text value "C_470n_0402" (at 0 1.4) (layer "F.Fab") hide
        (effects (font (size 0.7 0.7) (thickness 0.15)) (justify left bottom))
    )
    (fp_text user "${REFERENCE}" (at -0.932 3.168) (layer "F.Fab") hide
        (effects (font (size 0.7 0.7) (thickness 0.15)) (justify left bottom))
    )
    (fp_text user "Author: Antmicro" (at -0.932 4.17) (layer "F.Fab") hide
        (effects (font (size 0.7 0.7) (thickness 0.15)) (justify left bottom))
    )
    (fp_text user "License: Apache-2.0" (at -0.932 5.17) (layer "F.Fab") hide
        (effects (font (size 0.7 0.7) (thickness 0.15)) (justify left bottom))
    )
    (fp_rect (start -0.94 -0.47) (end 0.94 0.47)
      (stroke (width 0.05) (type solid)) (fill none) (layer "F.CrtYd"))
    (fp_rect (start -0.499 -0.249) (end 0.499 0.249)
      (stroke (width 0.15) (type solid)) (fill none) (layer "F.Fab"))
    (pad "1" smd roundrect (at -0.484 0) (size 0.59 0.64) (layers "F.Cu" "F.Paste" "F.Mask") (roundrect_rratio 0.25)
      (net 12 "/AGCN") (pintype "passive"))
    (pad "2" smd roundrect (at 0.484 0) (size 0.59 0.64) (layers "F.Cu" "F.Paste" "F.Mask") (roundrect_rratio 0.25)
      (net 9 "/AGCP") (pintype "passive"))
  )

  (footprint "sdi-mipi-bridge-footprints:C_0402_1005Metric" (layer "F.Cu")
    (at 113.76 117.4)
    (descr "Capacitor SMD 0402")
    (tags "capacitor SMD 0402")
    (property "Author" "Antmicro")
    (property "Dielectric" "")
    (property "License" "Apache-2.0")
    (property "MPN" "C1005X5R1E474M050BB")
    (property "Manufacturer" "TDK")
    (property "Sheetfile" "sdi-mipi-bridge.kicad_sch")
    (property "Sheetname" "")
    (property "Val" "470n")
    (property "Voltage" "")
    (property "ki_description" " ")
    (attr smd)
    (fp_text reference "C61" (at -7.16 -0.9) (layer "F.SilkS")
        (effects (font (size 0.65 0.65) (thickness 0.15)) (justify left bottom))
    )
    (fp_text value "C_470n_0402" (at 0 1.4) (layer "F.Fab") hide
        (effects (font (size 0.7 0.7) (thickness 0.15)) (justify left bottom))
    )
    (fp_text user "License: Apache-2.0" (at -0.932 5.17) (layer "F.Fab") hide
        (effects (font (size 0.7 0.7) (thickness 0.15)) (justify left bottom))
    )
    (fp_text user "${REFERENCE}" (at -0.932 3.168) (layer "F.Fab") hide
        (effects (font (size 0.7 0.7) (thickness 0.15)) (justify left bottom))
    )
    (fp_text user "Author: Antmicro" (at -0.932 4.17) (layer "F.Fab") hide
        (effects (font (size 0.7 0.7) (thickness 0.15)) (justify left bottom))
    )
    (fp_rect (start -0.94 -0.47) (end 0.94 0.47)
      (stroke (width 0.05) (type solid)) (fill none) (layer "F.CrtYd"))
    (fp_rect (start -0.499 -0.249) (end 0.499 0.249)
      (stroke (width 0.15) (type solid)) (fill none) (layer "F.Fab"))
    (pad "1" smd roundrect (at -0.484 0) (size 0.59 0.64) (layers "F.Cu" "F.Paste" "F.Mask") (roundrect_rratio 0.25)
      (net 12 "/AGCN") (pintype "passive"))
    (pad "2" smd roundrect (at 0.484 0) (size 0.59 0.64) (layers "F.Cu" "F.Paste" "F.Mask") (roundrect_rratio 0.25)
      (net 3 "GNDA") (pintype "passive"))
  )

  (footprint "sdi-mipi-bridge-footprints:R_0603_1608Metric" (layer "F.Cu")
    (at 106.25 121.07 180)
    (descr "Resistor SMD 0603")
    (tags "resistor SMD 0603")
    (property "Author" "Antmicro")
    (property "License" "Apache-2.0")
    (property "MPN" "CR0603-FX-75R0ELF")
    (property "Manufacturer" "Bourns")
    (property "Sheetfile" "sdi-mipi-bridge.kicad_sch")
    (property "Sheetname" "")
    (property "Tolerance" "1%")
    (property "Val" "75R")
    (property "ki_description" "75R resistor in 0603 package with 1% tolerance")
    (attr smd)
    (fp_text reference "R17" (at -2.15 -9.43) (layer "F.SilkS")
        (effects (font (size 0.65 0.65) (thickness 0.15)) (justify right bottom))
    )
    (fp_text value "R_75R_0603" (at 0 1.6) (layer "F.Fab") hide
        (effects (font (size 0.7 0.7) (thickness 0.15)) (justify right bottom))
    )
    (fp_text user "License: Apache-2.0" (at -1.25 5.9) (layer "F.Fab") hide
        (effects (font (size 0.7 0.7) (thickness 0.15)) (justify right bottom))
    )
    (fp_text user "Author: Antmicro" (at -1.25 4.9) (layer "F.Fab") hide
        (effects (font (size 0.7 0.7) (thickness 0.15)) (justify right bottom))
    )
    (fp_text user "${REFERENCE}" (at -1.25 3.898) (layer "F.Fab") hide
        (effects (font (size 0.7 0.7) (thickness 0.15)) (justify right bottom))
    )
    (fp_line (start -0.3 -0.3) (end 0.3 -0.3)
      (stroke (width 0.15) (type solid)) (layer "F.SilkS"))
    (fp_line (start -0.3 0.3) (end 0.3 0.3)
      (stroke (width 0.15) (type solid)) (layer "F.SilkS"))
    (fp_rect (start -1.25 -0.7) (end 1.25 0.7)
      (stroke (width 0.05) (type solid)) (fill none) (layer "F.CrtYd"))
    (fp_rect (start -0.8 -0.4) (end 0.8 0.4)
      (stroke (width 0.15) (type solid)) (fill none) (layer "F.Fab"))
    (pad "1" smd roundrect (at -0.7 0 180) (size 0.6 0.8) (layers "F.Cu" "F.Paste" "F.Mask") (roundrect_rratio 0.2)
      (net 29 "Net-(U3-SDO-)") (pintype "passive"))
    (pad "2" smd roundrect (at 0.7 0 180) (size 0.6 0.8) (layers "F.Cu" "F.Paste" "F.Mask") (roundrect_rratio 0.2)
      (net 68 "Net-(C27-Pad2)") (pintype "passive"))
  )

  (footprint "sdi-mipi-bridge-footprints:R_0603_1608Metric" (layer "F.Cu")
    (at 108.35 120.340001 90)
    (descr "Resistor SMD 0603")
    (tags "resistor SMD 0603")
    (property "Author" "Antmicro")
    (property "License" "Apache-2.0")
    (property "MPN" "CR0603-FX-75R0ELF")
    (property "Manufacturer" "Bourns")
    (property "Sheetfile" "sdi-mipi-bridge.kicad_sch")
    (property "Sheetname" "")
    (property "Tolerance" "1%")
    (property "Val" "75R")
    (property "ki_description" "75R resistor in 0603 package with 1% tolerance")
    (attr smd)
    (fp_text reference "R19" (at -9.959999 1.45 90) (layer "F.SilkS")
        (effects (font (size 0.65 0.65) (thickness 0.15)) (justify left bottom))
    )
    (fp_text value "R_75R_0603" (at 0 1.6 90) (layer "F.Fab") hide
        (effects (font (size 0.7 0.7) (thickness 0.15)) (justify left bottom))
    )
    (fp_text user "License: Apache-2.0" (at -1.25 5.9 90) (layer "F.Fab") hide
        (effects (font (size 0.7 0.7) (thickness 0.15)) (justify left bottom))
    )
    (fp_text user "Author: Antmicro" (at -1.25 4.9 90) (layer "F.Fab") hide
        (effects (font (size 0.7 0.7) (thickness 0.15)) (justify left bottom))
    )
    (fp_text user "${REFERENCE}" (at -1.25 3.898 90) (layer "F.Fab") hide
        (effects (font (size 0.7 0.7) (thickness 0.15)) (justify left bottom))
    )
    (fp_line (start -0.3 -0.3) (end 0.3 -0.3)
      (stroke (width 0.15) (type solid)) (layer "F.SilkS"))
    (fp_line (start -0.3 0.3) (end 0.3 0.3)
      (stroke (width 0.15) (type solid)) (layer "F.SilkS"))
    (fp_rect (start -1.25 -0.7) (end 1.25 0.7)
      (stroke (width 0.05) (type solid)) (fill none) (layer "F.CrtYd"))
    (fp_rect (start -0.8 -0.4) (end 0.8 0.4)
      (stroke (width 0.15) (type solid)) (fill none) (layer "F.Fab"))
    (pad "1" smd roundrect (at -0.7 0 90) (size 0.6 0.8) (layers "F.Cu" "F.Paste" "F.Mask") (roundrect_rratio 0.2)
      (net 29 "Net-(U3-SDO-)") (pintype "passive"))
    (pad "2" smd roundrect (at 0.7 0 90) (size 0.6 0.8) (layers "F.Cu" "F.Paste" "F.Mask") (roundrect_rratio 0.2)
      (net 57 "VDD") (pintype "passive"))
  )

  (footprint "sdi-mipi-bridge-footprints:C_0402_1005Metric" (layer "F.Cu")
    (at 114.302 125.277)
    (descr "Capacitor SMD 0402")
    (tags "capacitor SMD 0402")
    (property "Author" "Antmicro")
    (property "Dielectric" "X7R")
    (property "License" "Apache-2.0")
    (property "MPN" "GRM155R71H103KA88D")
    (property "Manufacturer" "Murata")
    (property "Sheetfile" "sdi-mipi-bridge.kicad_sch")
    (property "Sheetname" "")
    (property "Val" "10n")
    (property "Voltage" "50V")
    (property "ki_description" " ")
    (attr smd)
    (fp_text reference "C18" (at -1.002 2.223) (layer "F.SilkS")
        (effects (font (size 0.65 0.65) (thickness 0.15)) (justify left bottom))
    )
    (fp_text value "C_10n_0402" (at 0 1.4) (layer "F.Fab") hide
        (effects (font (size 0.7 0.7) (thickness 0.15)) (justify left bottom))
    )
    (fp_text user "Author: Antmicro" (at -0.932 4.17) (layer "F.Fab") hide
        (effects (font (size 0.7 0.7) (thickness 0.15)) (justify left bottom))
    )
    (fp_text user "${REFERENCE}" (at -0.932 3.168) (layer "F.Fab") hide
        (effects (font (size 0.7 0.7) (thickness 0.15)) (justify left bottom))
    )
    (fp_text user "License: Apache-2.0" (at -0.932 5.17) (layer "F.Fab") hide
        (effects (font (size 0.7 0.7) (thickness 0.15)) (justify left bottom))
    )
    (fp_rect (start -0.94 -0.47) (end 0.94 0.47)
      (stroke (width 0.05) (type solid)) (fill none) (layer "F.CrtYd"))
    (fp_rect (start -0.499 -0.249) (end 0.499 0.249)
      (stroke (width 0.15) (type solid)) (fill none) (layer "F.Fab"))
    (pad "1" smd roundrect (at -0.484 0) (size 0.59 0.64) (layers "F.Cu" "F.Paste" "F.Mask") (roundrect_rratio 0.25)
      (net 3 "GNDA") (pintype "passive"))
    (pad "2" smd roundrect (at 0.484 0) (size 0.59 0.64) (layers "F.Cu" "F.Paste" "F.Mask") (roundrect_rratio 0.25)
      (net 57 "VDD") (pintype "passive"))
  )

  (footprint "sdi-mipi-bridge-footprints:C_0402_1005Metric" (layer "F.Cu")
    (at 109.9 124.6 -90)
    (descr "Capacitor SMD 0402")
    (tags "capacitor SMD 0402")
    (property "Author" "Antmicro")
    (property "Dielectric" "X7R")
    (property "License" "Apache-2.0")
    (property "MPN" "GRM155R71H103KA88D")
    (property "Manufacturer" "Murata")
    (property "Sheetfile" "sdi-mipi-bridge.kicad_sch")
    (property "Sheetname" "")
    (property "Val" "10n")
    (property "Voltage" "50V")
    (property "ki_description" " ")
    (attr smd)
    (fp_text reference "C65" (at 1.5 -0.4 90) (layer "F.SilkS")
        (effects (font (size 0.65 0.65) (thickness 0.15)) (justify right bottom))
    )
    (fp_text value "C_10n_0402" (at 0 1.4 90) (layer "F.Fab") hide
        (effects (font (size 0.7 0.7) (thickness 0.15)) (justify right bottom))
    )
    (fp_text user "Author: Antmicro" (at -0.932 4.17 90) (layer "F.Fab") hide
        (effects (font (size 0.7 0.7) (thickness 0.15)) (justify right bottom))
    )
    (fp_text user "${REFERENCE}" (at -0.932 3.168 90) (layer "F.Fab") hide
        (effects (font (size 0.7 0.7) (thickness 0.15)) (justify right bottom))
    )
    (fp_text user "License: Apache-2.0" (at -0.932 5.17 90) (layer "F.Fab") hide
        (effects (font (size 0.7 0.7) (thickness 0.15)) (justify right bottom))
    )
    (fp_rect (start -0.94 -0.47) (end 0.94 0.47)
      (stroke (width 0.05) (type solid)) (fill none) (layer "F.CrtYd"))
    (fp_rect (start -0.499 -0.249) (end 0.499 0.249)
      (stroke (width 0.15) (type solid)) (fill none) (layer "F.Fab"))
    (pad "1" smd roundrect (at -0.484 0 270) (size 0.59 0.64) (layers "F.Cu" "F.Paste" "F.Mask") (roundrect_rratio 0.25)
      (net 57 "VDD") (pintype "passive"))
    (pad "2" smd roundrect (at 0.484 0 270) (size 0.59 0.64) (layers "F.Cu" "F.Paste" "F.Mask") (roundrect_rratio 0.25)
      (net 3 "GNDA") (pintype "passive"))
  )

  (footprint "sdi-mipi-bridge-footprints:LED_0603_1608Metric_G" (layer "F.Cu")
    (at 133 104.4 90)
    (descr "LED SMD 0603 Green")
    (tags "LED SMD 0603 Green")
    (property "Author" "Antmicro")
    (property "License" "Apache-2.0")
    (property "MPN" "LG L29K-G2J1-24-Z")
    (property "Manufacturer" "Osram")
    (property "Sheetfile" "sdi-mipi-bridge.kicad_sch")
    (property "Sheetname" "")
    (attr smd)
    (fp_text reference "D5" (at 0.2 -0.7 90) (layer "F.SilkS")
        (effects (font (size 0.65 0.65) (thickness 0.15)) (justify left bottom))
    )
    (fp_text value "LED_G_0603_LG_L29K-G2J1-24-Z" (at 0 1.6 90) (layer "F.Fab") hide
        (effects (font (size 0.7 0.7) (thickness 0.15)) (justify left bottom))
    )
    (fp_text user "Author: Antmicro" (at -1.31 4.769 90) (layer "F.Fab") hide
        (effects (font (size 0.7 0.7) (thickness 0.15)) (justify left bottom))
    )
    (fp_text user "${REFERENCE}" (at -1.31 3.769 90) (layer "F.Fab") hide
        (effects (font (size 0.7 0.7) (thickness 0.15)) (justify left bottom))
    )
    (fp_text user "License: Apache-2.0" (at -1.31 5.769 90) (layer "F.Fab") hide
        (effects (font (size 0.7 0.7) (thickness 0.15)) (justify left bottom))
    )
    (fp_line (start -0.27 -0.35) (end 0.27 -0.35)
      (stroke (width 0.15) (type solid)) (layer "F.SilkS"))
    (fp_line (start -0.27 0.351) (end 0.27 0.351)
      (stroke (width 0.15) (type solid)) (layer "F.SilkS"))
    (fp_line (start -0.106328 -0.200008) (end -0.106328 0.199992)
      (stroke (width 0.1) (type solid)) (layer "F.SilkS"))
    (fp_line (start -0.106328 -0.200008) (end 0.093672 -0.000008)
      (stroke (width 0.1) (type solid)) (layer "F.SilkS"))
    (fp_line (start -0.106328 -0.000008) (end -0.29 0)
      (stroke (width 0.1) (type solid)) (layer "F.SilkS"))
    (fp_line (start 0.093672 -0.200008) (end 0.093672 0.199992)
      (stroke (width 0.1) (type solid)) (layer "F.SilkS"))
    (fp_line (start 0.093672 -0.000008) (end -0.106328 0.199992)
      (stroke (width 0.1) (type solid)) (layer "F.SilkS"))
    (fp_line (start 0.093672 -0.000008) (end 0.293672 -0.000008)
      (stroke (width 0.1) (type solid)) (layer "F.SilkS"))
    (fp_line (start 1.25 0.32) (end 1.25 -0.32)
      (stroke (width 0.15) (type solid)) (layer "F.SilkS"))
    (fp_rect (start 1.26 0.65) (end -1.26 -0.65)
      (stroke (width 0.05) (type solid)) (fill none) (layer "F.CrtYd"))
    (fp_line (start -0.599 0) (end -0.201 0)
      (stroke (width 0.15) (type solid)) (layer "F.Fab"))
    (fp_line (start -0.201 -0.2) (end -0.201 0)
      (stroke (width 0.15) (type solid)) (layer "F.Fab"))
    (fp_line (start -0.201 0) (end -0.201 0.202)
      (stroke (width 0.15) (type solid)) (layer "F.Fab"))
    (fp_line (start -0.201 0.202) (end 0.101 0)
      (stroke (width 0.15) (type solid)) (layer "F.Fab"))
    (fp_line (start 0.101 0) (end -0.201 -0.2)
      (stroke (width 0.15) (type solid)) (layer "F.Fab"))
    (fp_line (start 0.199 -0.2) (end 0.199 -0.1)
      (stroke (width 0.15) (type solid)) (layer "F.Fab"))
    (fp_line (start 0.199 0) (end 0.597 0)
      (stroke (width 0.15) (type solid)) (layer "F.Fab"))
    (fp_line (start 0.199 0.202) (end 0.199 -0.1)
      (stroke (width 0.15) (type solid)) (layer "F.Fab"))
    (fp_rect (start -0.848 -0.4) (end 0.85 0.402)
      (stroke (width 0.15) (type solid)) (fill none) (layer "F.Fab"))
    (pad "1" smd rect (at -0.75 0 270) (size 0.8 0.8) (layers "F.Cu" "F.Paste" "F.Mask")
      (net 95 "Net-(D5-Pad1)") (pintype "passive"))
    (pad "2" smd rect (at 0.75 0 270) (size 0.8 0.8) (layers "F.Cu" "F.Paste" "F.Mask")
      (net 1 "GNDREF") (pinfunction "2") (pintype "passive"))
  )

  (footprint "sdi-mipi-bridge-footprints:R_0402_1005Metric" (layer "F.Cu")
    (at 138 129.75 90)
    (descr "Resistor SMD 0402")
    (tags "resistor SMD 0402")
    (property "Author" "Antmicro")
    (property "License" "Apache-2.0")
    (property "MPN" "CR0402-FX-1002GLF")
    (property "Manufacturer" "Bourns")
    (property "Sheetfile" "sdi-mipi-bridge.kicad_sch")
    (property "Sheetname" "")
    (property "Tolerance" "1%")
    (property "Val" "10k")
    (property "ki_description" "10k resistor in 0402 package with 1% tolerance")
    (attr smd)
    (fp_text reference "R65" (at -5.75 0.4 90) (layer "F.SilkS")
        (effects (font (size 0.65 0.65) (thickness 0.15)) (justify left bottom))
    )
    (fp_text value "R_10k_0402" (at 0 1.4 90) (layer "F.Fab") hide
        (effects (font (size 0.7 0.7) (thickness 0.15)) (justify left bottom))
    )
    (fp_text user "${REFERENCE}" (at -0.95 3.168 90) (layer "F.Fab") hide
        (effects (font (size 0.7 0.7) (thickness 0.15)) (justify left bottom))
    )
    (fp_text user "Author: Antmicro" (at -0.95 4.169 90) (layer "F.Fab") hide
        (effects (font (size 0.7 0.7) (thickness 0.15)) (justify left bottom))
    )
    (fp_text user "License: Apache-2.0" (at -0.95 5.169 90) (layer "F.Fab") hide
        (effects (font (size 0.7 0.7) (thickness 0.15)) (justify left bottom))
    )
    (fp_rect (start -0.93 -0.47) (end 0.93 0.47)
      (stroke (width 0.05) (type solid)) (fill none) (layer "F.CrtYd"))
    (fp_rect (start -0.5 -0.25) (end 0.5 0.25)
      (stroke (width 0.15) (type solid)) (fill none) (layer "F.Fab"))
    (pad "1" smd roundrect (at -0.485 0 90) (size 0.59 0.64) (layers "F.Cu" "F.Paste" "F.Mask") (roundrect_rratio 0.25)
      (net 105 "/USER_SW") (pintype "passive"))
    (pad "2" smd roundrect (at 0.485 0 90) (size 0.59 0.64) (layers "F.Cu" "F.Paste" "F.Mask") (roundrect_rratio 0.25)
      (net 76 "IO_VDD") (pintype "passive"))
  )

  (footprint "sdi-mipi-bridge-footprints:R_0402_1005Metric" (layer "F.Cu")
    (at 138 131.765 90)
    (descr "Resistor SMD 0402")
    (tags "resistor SMD 0402")
    (property "Author" "Antmicro")
    (property "DNP" "DNP")
    (property "License" "Apache-2.0")
    (property "MPN" "CR0402-FX-1002GLF")
    (property "Manufacturer" "Bourns")
    (property "Sheetfile" "sdi-mipi-bridge.kicad_sch")
    (property "Sheetname" "")
    (property "Tolerance" "1%")
    (property "Val" "10k")
    (property "ki_description" "10k resistor in 0402 package with 1% tolerance")
    (attr exclude_from_pos_files)
    (fp_text reference "R66" (at -5.75 0.4 90) (layer "F.SilkS")
        (effects (font (size 0.65 0.65) (thickness 0.15)) (justify left bottom))
    )
    (fp_text value "R_10k_0402" (at 0 1.4 90) (layer "F.Fab") hide
        (effects (font (size 0.7 0.7) (thickness 0.15)) (justify left bottom))
    )
    (fp_text user "License: Apache-2.0" (at -0.95 5.169 90) (layer "F.Fab") hide
        (effects (font (size 0.7 0.7) (thickness 0.15)) (justify left bottom))
    )
    (fp_text user "${REFERENCE}" (at -0.95 3.168 90) (layer "F.Fab") hide
        (effects (font (size 0.7 0.7) (thickness 0.15)) (justify left bottom))
    )
    (fp_text user "Author: Antmicro" (at -0.95 4.169 90) (layer "F.Fab") hide
        (effects (font (size 0.7 0.7) (thickness 0.15)) (justify left bottom))
    )
    (fp_rect (start -0.93 -0.47) (end 0.93 0.47)
      (stroke (width 0.05) (type solid)) (fill none) (layer "F.CrtYd"))
    (fp_rect (start -0.5 -0.25) (end 0.5 0.25)
      (stroke (width 0.15) (type solid)) (fill none) (layer "F.Fab"))
    (pad "1" smd roundrect (at -0.485 0 90) (size 0.59 0.64) (layers "F.Cu" "F.Paste" "F.Mask") (roundrect_rratio 0.25)
      (net 3 "GNDA") (pintype "passive"))
    (pad "2" smd roundrect (at 0.485 0 90) (size 0.59 0.64) (layers "F.Cu" "F.Paste" "F.Mask") (roundrect_rratio 0.25)
      (net 105 "/USER_SW") (pintype "passive"))
  )

  (footprint "sdi-mipi-bridge-footprints:R_0402_1005Metric" (layer "F.Cu")
    (at 139.25 129.765 90)
    (descr "Resistor SMD 0402")
    (tags "resistor SMD 0402")
    (property "Author" "Antmicro")
    (property "License" "Apache-2.0")
    (property "MPN" "CR0402-FX-1002GLF")
    (property "Manufacturer" "Bourns")
    (property "Sheetfile" "sdi-mipi-bridge.kicad_sch")
    (property "Sheetname" "")
    (property "Tolerance" "1%")
    (property "Val" "10k")
    (property "ki_description" "10k resistor in 0402 package with 1% tolerance")
    (attr smd)
    (fp_text reference "R68" (at -5.75 0.4 90) (layer "F.SilkS")
        (effects (font (size 0.65 0.65) (thickness 0.15)) (justify left bottom))
    )
    (fp_text value "R_10k_0402" (at 0 1.4 90) (layer "F.Fab") hide
        (effects (font (size 0.7 0.7) (thickness 0.15)) (justify left bottom))
    )
    (fp_text user "${REFERENCE}" (at -0.95 3.168 90) (layer "F.Fab") hide
        (effects (font (size 0.7 0.7) (thickness 0.15)) (justify left bottom))
    )
    (fp_text user "Author: Antmicro" (at -0.95 4.169 90) (layer "F.Fab") hide
        (effects (font (size 0.7 0.7) (thickness 0.15)) (justify left bottom))
    )
    (fp_text user "License: Apache-2.0" (at -0.95 5.169 90) (layer "F.Fab") hide
        (effects (font (size 0.7 0.7) (thickness 0.15)) (justify left bottom))
    )
    (fp_rect (start -0.93 -0.47) (end 0.93 0.47)
      (stroke (width 0.05) (type solid)) (fill none) (layer "F.CrtYd"))
    (fp_rect (start -0.5 -0.25) (end 0.5 0.25)
      (stroke (width 0.15) (type solid)) (fill none) (layer "F.Fab"))
    (pad "1" smd roundrect (at -0.485 0 90) (size 0.59 0.64) (layers "F.Cu" "F.Paste" "F.Mask") (roundrect_rratio 0.25)
      (net 55 "/SDO_EN_DIS") (pintype "passive"))
    (pad "2" smd roundrect (at 0.485 0 90) (size 0.59 0.64) (layers "F.Cu" "F.Paste" "F.Mask") (roundrect_rratio 0.25)
      (net 76 "IO_VDD") (pintype "passive"))
  )

  (footprint "sdi-mipi-bridge-footprints:R_0402_1005Metric" (layer "F.Cu")
    (at 139.25 131.78 90)
    (descr "Resistor SMD 0402")
    (tags "resistor SMD 0402")
    (property "Author" "Antmicro")
    (property "DNP" "DNP")
    (property "License" "Apache-2.0")
    (property "MPN" "CR0402-FX-1002GLF")
    (property "Manufacturer" "Bourns")
    (property "Sheetfile" "sdi-mipi-bridge.kicad_sch")
    (property "Sheetname" "")
    (property "Tolerance" "1%")
    (property "Val" "10k")
    (property "ki_description" "10k resistor in 0402 package with 1% tolerance")
    (attr exclude_from_pos_files)
    (fp_text reference "R75" (at -5.75 0.4 90) (layer "F.SilkS")
        (effects (font (size 0.65 0.65) (thickness 0.15)) (justify left bottom))
    )
    (fp_text value "R_10k_0402" (at 0 1.4 90) (layer "F.Fab") hide
        (effects (font (size 0.7 0.7) (thickness 0.15)) (justify left bottom))
    )
    (fp_text user "${REFERENCE}" (at -0.95 3.168 90) (layer "F.Fab") hide
        (effects (font (size 0.7 0.7) (thickness 0.15)) (justify left bottom))
    )
    (fp_text user "Author: Antmicro" (at -0.95 4.169 90) (layer "F.Fab") hide
        (effects (font (size 0.7 0.7) (thickness 0.15)) (justify left bottom))
    )
    (fp_text user "License: Apache-2.0" (at -0.95 5.169 90) (layer "F.Fab") hide
        (effects (font (size 0.7 0.7) (thickness 0.15)) (justify left bottom))
    )
    (fp_rect (start -0.93 -0.47) (end 0.93 0.47)
      (stroke (width 0.05) (type solid)) (fill none) (layer "F.CrtYd"))
    (fp_rect (start -0.5 -0.25) (end 0.5 0.25)
      (stroke (width 0.15) (type solid)) (fill none) (layer "F.Fab"))
    (pad "1" smd roundrect (at -0.485 0 90) (size 0.59 0.64) (layers "F.Cu" "F.Paste" "F.Mask") (roundrect_rratio 0.25)
      (net 3 "GNDA") (pintype "passive"))
    (pad "2" smd roundrect (at 0.485 0 90) (size 0.59 0.64) (layers "F.Cu" "F.Paste" "F.Mask") (roundrect_rratio 0.25)
      (net 55 "/SDO_EN_DIS") (pintype "passive"))
  )

  (footprint "sdi-mipi-bridge-footprints:R_0402_1005Metric" (layer "F.Cu")
    (at 141.75 129.75 90)
    (descr "Resistor SMD 0402")
    (tags "resistor SMD 0402")
    (property "Author" "Antmicro")
    (property "License" "Apache-2.0")
    (property "MPN" "CR0402-FX-1002GLF")
    (property "Manufacturer" "Bourns")
    (property "Sheetfile" "sdi-mipi-bridge.kicad_sch")
    (property "Sheetname" "")
    (property "Tolerance" "1%")
    (property "Val" "10k")
    (property "ki_description" "10k resistor in 0402 package with 1% tolerance")
    (attr smd)
    (fp_text reference "R78" (at -5.75 0.4 90) (layer "F.SilkS")
        (effects (font (size 0.65 0.65) (thickness 0.15)) (justify left bottom))
    )
    (fp_text value "R_10k_0402" (at 0 1.4 90) (layer "F.Fab") hide
        (effects (font (size 0.7 0.7) (thickness 0.15)) (justify left bottom))
    )
    (fp_text user "License: Apache-2.0" (at -0.95 5.169 90) (layer "F.Fab") hide
        (effects (font (size 0.7 0.7) (thickness 0.15)) (justify left bottom))
    )
    (fp_text user "${REFERENCE}" (at -0.95 3.168 90) (layer "F.Fab") hide
        (effects (font (size 0.7 0.7) (thickness 0.15)) (justify left bottom))
    )
    (fp_text user "Author: Antmicro" (at -0.95 4.169 90) (layer "F.Fab") hide
        (effects (font (size 0.7 0.7) (thickness 0.15)) (justify left bottom))
    )
    (fp_rect (start -0.93 -0.47) (end 0.93 0.47)
      (stroke (width 0.05) (type solid)) (fill none) (layer "F.CrtYd"))
    (fp_rect (start -0.5 -0.25) (end 0.5 0.25)
      (stroke (width 0.15) (type solid)) (fill none) (layer "F.Fab"))
    (pad "1" smd roundrect (at -0.485 0 90) (size 0.59 0.64) (layers "F.Cu" "F.Paste" "F.Mask") (roundrect_rratio 0.25)
      (net 41 "/IOPROC_EN_~{DIS}") (pintype "passive"))
    (pad "2" smd roundrect (at 0.485 0 90) (size 0.59 0.64) (layers "F.Cu" "F.Paste" "F.Mask") (roundrect_rratio 0.25)
      (net 76 "IO_VDD") (pintype "passive"))
  )

  (footprint "sdi-mipi-bridge-footprints:R_0402_1005Metric" (layer "F.Cu")
    (at 141.75 131.75 90)
    (descr "Resistor SMD 0402")
    (tags "resistor SMD 0402")
    (property "Author" "Antmicro")
    (property "DNP" "DNP")
    (property "License" "Apache-2.0")
    (property "MPN" "CR0402-FX-1002GLF")
    (property "Manufacturer" "Bourns")
    (property "Sheetfile" "sdi-mipi-bridge.kicad_sch")
    (property "Sheetname" "")
    (property "Tolerance" "1%")
    (property "Val" "10k")
    (property "ki_description" "10k resistor in 0402 package with 1% tolerance")
    (attr exclude_from_pos_files)
    (fp_text reference "R79" (at -5.75 0.4 90) (layer "F.SilkS")
        (effects (font (size 0.65 0.65) (thickness 0.15)) (justify left bottom))
    )
    (fp_text value "R_10k_0402" (at 0 1.4 90) (layer "F.Fab") hide
        (effects (font (size 0.7 0.7) (thickness 0.15)) (justify left bottom))
    )
    (fp_text user "${REFERENCE}" (at -0.95 3.168 90) (layer "F.Fab") hide
        (effects (font (size 0.7 0.7) (thickness 0.15)) (justify left bottom))
    )
    (fp_text user "Author: Antmicro" (at -0.95 4.169 90) (layer "F.Fab") hide
        (effects (font (size 0.7 0.7) (thickness 0.15)) (justify left bottom))
    )
    (fp_text user "License: Apache-2.0" (at -0.95 5.169 90) (layer "F.Fab") hide
        (effects (font (size 0.7 0.7) (thickness 0.15)) (justify left bottom))
    )
    (fp_rect (start -0.93 -0.47) (end 0.93 0.47)
      (stroke (width 0.05) (type solid)) (fill none) (layer "F.CrtYd"))
    (fp_rect (start -0.5 -0.25) (end 0.5 0.25)
      (stroke (width 0.15) (type solid)) (fill none) (layer "F.Fab"))
    (pad "1" smd roundrect (at -0.485 0 90) (size 0.59 0.64) (layers "F.Cu" "F.Paste" "F.Mask") (roundrect_rratio 0.25)
      (net 3 "GNDA") (pintype "passive"))
    (pad "2" smd roundrect (at 0.485 0 90) (size 0.59 0.64) (layers "F.Cu" "F.Paste" "F.Mask") (roundrect_rratio 0.25)
      (net 41 "/IOPROC_EN_~{DIS}") (pintype "passive"))
  )

  (footprint "sdi-mipi-bridge-footprints:R_0402_1005Metric" (layer "F.Cu")
    (at 143 129.75 90)
    (descr "Resistor SMD 0402")
    (tags "resistor SMD 0402")
    (property "Author" "Antmicro")
    (property "DNP" "DNP")
    (property "License" "Apache-2.0")
    (property "MPN" "CR0402-FX-1002GLF")
    (property "Manufacturer" "Bourns")
    (property "Sheetfile" "sdi-mipi-bridge.kicad_sch")
    (property "Sheetname" "")
    (property "Tolerance" "1%")
    (property "Val" "10k")
    (property "ki_description" "10k resistor in 0402 package with 1% tolerance")
    (attr exclude_from_pos_files)
    (fp_text reference "R80" (at -5.75 0.4 90) (layer "F.SilkS")
        (effects (font (size 0.65 0.65) (thickness 0.15)) (justify left bottom))
    )
    (fp_text value "R_10k_0402" (at 0 1.4 90) (layer "F.Fab") hide
        (effects (font (size 0.7 0.7) (thickness 0.15)) (justify left bottom))
    )
    (fp_text user "${REFERENCE}" (at -0.95 3.168 90) (layer "F.Fab") hide
        (effects (font (size 0.7 0.7) (thickness 0.15)) (justify left bottom))
    )
    (fp_text user "License: Apache-2.0" (at -0.95 5.169 90) (layer "F.Fab") hide
        (effects (font (size 0.7 0.7) (thickness 0.15)) (justify left bottom))
    )
    (fp_text user "Author: Antmicro" (at -0.95 4.169 90) (layer "F.Fab") hide
        (effects (font (size 0.7 0.7) (thickness 0.15)) (justify left bottom))
    )
    (fp_rect (start -0.93 -0.47) (end 0.93 0.47)
      (stroke (width 0.05) (type solid)) (fill none) (layer "F.CrtYd"))
    (fp_rect (start -0.5 -0.25) (end 0.5 0.25)
      (stroke (width 0.15) (type solid)) (fill none) (layer "F.Fab"))
    (pad "1" smd roundrect (at -0.485 0 90) (size 0.59 0.64) (layers "F.Cu" "F.Paste" "F.Mask") (roundrect_rratio 0.25)
      (net 16 "/20bit_~{10bit}") (pintype "passive"))
    (pad "2" smd roundrect (at 0.485 0 90) (size 0.59 0.64) (layers "F.Cu" "F.Paste" "F.Mask") (roundrect_rratio 0.25)
      (net 76 "IO_VDD") (pintype "passive"))
  )

  (footprint "sdi-mipi-bridge-footprints:R_0402_1005Metric" (layer "F.Cu")
    (at 143 131.75 90)
    (descr "Resistor SMD 0402")
    (tags "resistor SMD 0402")
    (property "Author" "Antmicro")
    (property "License" "Apache-2.0")
    (property "MPN" "CR0402-FX-1002GLF")
    (property "Manufacturer" "Bourns")
    (property "Sheetfile" "sdi-mipi-bridge.kicad_sch")
    (property "Sheetname" "")
    (property "Tolerance" "1%")
    (property "Val" "10k")
    (property "ki_description" "10k resistor in 0402 package with 1% tolerance")
    (attr smd)
    (fp_text reference "R81" (at -5.75 0.4 90) (layer "F.SilkS")
        (effects (font (size 0.65 0.65) (thickness 0.15)) (justify left bottom))
    )
    (fp_text value "R_10k_0402" (at 0 1.4 90) (layer "F.Fab") hide
        (effects (font (size 0.7 0.7) (thickness 0.15)) (justify left bottom))
    )
    (fp_text user "Author: Antmicro" (at -0.95 4.169 90) (layer "F.Fab") hide
        (effects (font (size 0.7 0.7) (thickness 0.15)) (justify left bottom))
    )
    (fp_text user "${REFERENCE}" (at -0.95 3.168 90) (layer "F.Fab") hide
        (effects (font (size 0.7 0.7) (thickness 0.15)) (justify left bottom))
    )
    (fp_text user "License: Apache-2.0" (at -0.95 5.169 90) (layer "F.Fab") hide
        (effects (font (size 0.7 0.7) (thickness 0.15)) (justify left bottom))
    )
    (fp_rect (start -0.93 -0.47) (end 0.93 0.47)
      (stroke (width 0.05) (type solid)) (fill none) (layer "F.CrtYd"))
    (fp_rect (start -0.5 -0.25) (end 0.5 0.25)
      (stroke (width 0.15) (type solid)) (fill none) (layer "F.Fab"))
    (pad "1" smd roundrect (at -0.485 0 90) (size 0.59 0.64) (layers "F.Cu" "F.Paste" "F.Mask") (roundrect_rratio 0.25)
      (net 3 "GNDA") (pintype "passive"))
    (pad "2" smd roundrect (at 0.485 0 90) (size 0.59 0.64) (layers "F.Cu" "F.Paste" "F.Mask") (roundrect_rratio 0.25)
      (net 16 "/20bit_~{10bit}") (pintype "passive"))
  )

  (footprint "sdi-mipi-bridge-footprints:R_0402_1005Metric" (layer "F.Cu")
    (at 144.25 129.75 90)
    (descr "Resistor SMD 0402")
    (tags "resistor SMD 0402")
    (property "Author" "Antmicro")
    (property "DNP" "")
    (property "License" "Apache-2.0")
    (property "MPN" "CR0402-FX-1002GLF")
    (property "Manufacturer" "Bourns")
    (property "Sheetfile" "sdi-mipi-bridge.kicad_sch")
    (property "Sheetname" "")
    (property "Tolerance" "1%")
    (property "Val" "10k")
    (property "ki_description" "10k resistor in 0402 package with 1% tolerance")
    (attr smd)
    (fp_text reference "R83" (at -5.75 0.4 90) (layer "F.SilkS")
        (effects (font (size 0.65 0.65) (thickness 0.15)) (justify left bottom))
    )
    (fp_text value "R_10k_0402" (at 0 1.4 90) (layer "F.Fab") hide
        (effects (font (size 0.7 0.7) (thickness 0.15)) (justify left bottom))
    )
    (fp_text user "Author: Antmicro" (at -0.95 4.169 90) (layer "F.Fab") hide
        (effects (font (size 0.7 0.7) (thickness 0.15)) (justify left bottom))
    )
    (fp_text user "License: Apache-2.0" (at -0.95 5.169 90) (layer "F.Fab") hide
        (effects (font (size 0.7 0.7) (thickness 0.15)) (justify left bottom))
    )
    (fp_text user "${REFERENCE}" (at -0.95 3.168 90) (layer "F.Fab") hide
        (effects (font (size 0.7 0.7) (thickness 0.15)) (justify left bottom))
    )
    (fp_rect (start -0.93 -0.47) (end 0.93 0.47)
      (stroke (width 0.05) (type solid)) (fill none) (layer "F.CrtYd"))
    (fp_rect (start -0.5 -0.25) (end 0.5 0.25)
      (stroke (width 0.15) (type solid)) (fill none) (layer "F.Fab"))
    (pad "1" smd roundrect (at -0.485 0 90) (size 0.59 0.64) (layers "F.Cu" "F.Paste" "F.Mask") (roundrect_rratio 0.25)
      (net 17 "/~{SMPTE_BYPASS}") (pintype "passive"))
    (pad "2" smd roundrect (at 0.485 0 90) (size 0.59 0.64) (layers "F.Cu" "F.Paste" "F.Mask") (roundrect_rratio 0.25)
      (net 76 "IO_VDD") (pintype "passive"))
  )

  (footprint "sdi-mipi-bridge-footprints:TSSOP-16_4.4x5mm_P0.65mm" (layer "F.Cu")
    (at 130.7 125.3)
    (property "Author" "Antmicro")
    (property "License" "Apache-2.0")
    (property "MPN" "SC18IS602BIPW")
    (property "Manufacturer" "NXP")
    (property "Sheetfile" "sdi-mipi-bridge.kicad_sch")
    (property "Sheetname" "")
    (attr smd)
    (fp_text reference "U5" (at -0.7 -3.1) (layer "F.SilkS")
        (effects (font (size 0.65 0.65) (thickness 0.15)) (justify left bottom))
    )
    (fp_text value "SC18IS602BIPW" (at 0 3.749) (layer "F.Fab") hide
        (effects (font (size 0.7 0.7) (thickness 0.15)) (justify left bottom))
    )
    (fp_text user "Author: Antmicro" (at -3.801 8.15) (layer "F.Fab") hide
        (effects (font (size 0.7 0.7) (thickness 0.15)) (justify left bottom))
    )
    (fp_text user "${REFERENCE}" (at -3.801 9.349) (layer "F.Fab") hide
        (effects (font (size 0.7 0.7) (thickness 0.15)) (justify left bottom))
    )
    (fp_text user "License: Apache-2.0" (at -3.801 5.749) (layer "F.Fab") hide
        (effects (font (size 0.7 0.7) (thickness 0.15)) (justify left bottom))
    )
    (fp_line (start -2.15 -2.735) (end 2.249 -2.735)
      (stroke (width 0.15) (type solid)) (layer "F.SilkS"))
    (fp_line (start 0.05 2.733) (end -2.15 2.733)
      (stroke (width 0.15) (type solid)) (layer "F.SilkS"))
    (fp_line (start 0.05 2.733) (end 2.249 2.733)
      (stroke (width 0.15) (type solid)) (layer "F.SilkS"))
    (fp_circle (center -2.45 -2.67071) (end -2.4 -2.62071)
      (stroke (width 0.15) (type solid)) (fill solid) (layer "F.SilkS"))
    (fp_line (start -3.81 -2.75) (end -3.81 2.74)
      (stroke (width 0.05) (type solid)) (layer "F.CrtYd"))
    (fp_line (start -3.81 2.74) (end 3.89 2.74)
      (stroke (width 0.05) (type solid)) (layer "F.CrtYd"))
    (fp_line (start 3.89 -2.75) (end -3.81 -2.75)
      (stroke (width 0.05) (type solid)) (layer "F.CrtYd"))
    (fp_line (start 3.89 2.74) (end 3.89 -2.75)
      (stroke (width 0.05) (type solid)) (layer "F.CrtYd"))
    (fp_line (start -2.15 -1.5) (end -1.151 -2.5)
      (stroke (width 0.15) (type solid)) (layer "F.Fab"))
    (fp_line (start -2.15 2.499) (end -2.15 -1.5)
      (stroke (width 0.15) (type solid)) (layer "F.Fab"))
    (fp_line (start -1.151 -2.5) (end 2.249 -2.5)
      (stroke (width 0.15) (type solid)) (layer "F.Fab"))
    (fp_line (start 2.249 -2.5) (end 2.249 2.499)
      (stroke (width 0.15) (type solid)) (layer "F.Fab"))
    (fp_line (start 2.249 2.499) (end -2.15 2.499)
      (stroke (width 0.15) (type solid)) (layer "F.Fab"))
    (pad "1" smd roundrect (at -2.814 -2.275) (size 1.475 0.4) (layers "F.Cu" "F.Paste" "F.Mask") (roundrect_rratio 0.25)
      (net 45 "/~{CS}_TMS") (pinfunction "GPIO0/~{SS0}") (pintype "bidirectional"))
    (pad "2" smd roundrect (at -2.814 -1.625) (size 1.475 0.4) (layers "F.Cu" "F.Paste" "F.Mask") (roundrect_rratio 0.25)
      (net 163 "unconnected-(U5-GPIO1{slash}~{SS1}-Pad2)") (pinfunction "GPIO1/~{SS1}") (pintype "bidirectional+no_connect"))
    (pad "3" smd roundrect (at -2.814 -0.975) (size 1.475 0.4) (layers "F.Cu" "F.Paste" "F.Mask") (roundrect_rratio 0.25)
      (net 72 "Net-(U5-~{RESET})") (pinfunction "~{RESET}") (pintype "input"))
    (pad "4" smd roundrect (at -2.814 -0.327) (size 1.475 0.4) (layers "F.Cu" "F.Paste" "F.Mask") (roundrect_rratio 0.25)
      (net 1 "GNDREF") (pinfunction "V_{SS}") (pintype "power_in"))
    (pad "5" smd roundrect (at -2.814 0.325) (size 1.475 0.4) (layers "F.Cu" "F.Paste" "F.Mask") (roundrect_rratio 0.25)
      (net 46 "/SDOUT_TDO") (pinfunction "MISO") (pintype "input"))
    (pad "6" smd roundrect (at -2.814 0.973) (size 1.475 0.4) (layers "F.Cu" "F.Paste" "F.Mask") (roundrect_rratio 0.25)
      (net 43 "/SDIN_TDI") (pinfunction "MOSI") (pintype "output"))
    (pad "7" smd roundrect (at -2.814 1.624) (size 1.475 0.4) (layers "F.Cu" "F.Paste" "F.Mask") (roundrect_rratio 0.25)
      (net 62 "/SDA_GS") (pinfunction "SDA") (pintype "bidirectional"))
    (pad "8" smd roundrect (at -2.814 2.273) (size 1.475 0.4) (layers "F.Cu" "F.Paste" "F.Mask") (roundrect_rratio 0.25)
      (net 61 "/SCL_GS") (pinfunction "SCL") (pintype "input"))
    (pad "9" smd roundrect (at 2.911 2.273) (size 1.475 0.4) (layers "F.Cu" "F.Paste" "F.Mask") (roundrect_rratio 0.25)
      (net 164 "unconnected-(U5-~{INT}-Pad9)") (pinfunction "~{INT}") (pintype "output+no_connect"))
    (pad "10" smd roundrect (at 2.911 1.624) (size 1.475 0.4) (layers "F.Cu" "F.Paste" "F.Mask") (roundrect_rratio 0.25)
      (net 100 "/CRESET_B") (pinfunction "GPIO2/~{SS2}") (pintype "bidirectional"))
    (pad "11" smd roundrect (at 2.911 0.973) (size 1.475 0.4) (layers "F.Cu" "F.Paste" "F.Mask") (roundrect_rratio 0.25)
      (net 42 "/SCLK_TCK") (pinfunction "SCLK") (pintype "output"))
    (pad "12" smd roundrect (at 2.911 0.325) (size 1.475 0.4) (layers "F.Cu" "F.Paste" "F.Mask") (roundrect_rratio 0.25)
      (net 6 "+3V3") (pinfunction "V_{DD}") (pintype "power_in"))
    (pad "13" smd roundrect (at 2.911 -0.327) (size 1.475 0.4) (layers "F.Cu" "F.Paste" "F.Mask") (roundrect_rratio 0.25)
      (net 165 "unconnected-(U5-GPIO3{slash}~{SS3}-Pad13)") (pinfunction "GPIO3/~{SS3}") (pintype "bidirectional+no_connect"))
    (pad "14" smd roundrect (at 2.911 -0.975) (size 1.475 0.4) (layers "F.Cu" "F.Paste" "F.Mask") (roundrect_rratio 0.25)
      (net 74 "Net-(U5-A0)") (pinfunction "A0") (pintype "input"))
    (pad "15" smd roundrect (at 2.911 -1.625) (size 1.475 0.4) (layers "F.Cu" "F.Paste" "F.Mask") (roundrect_rratio 0.25)
      (net 75 "Net-(U5-A1)") (pinfunction "A1") (pintype "input"))
    (pad "16" smd roundrect (at 2.911 -2.275) (size 1.475 0.4) (layers "F.Cu" "F.Paste" "F.Mask") (roundrect_rratio 0.25)
      (net 84 "Net-(U5-A2)") (pinfunction "A2") (pintype "input"))
  )

  (footprint "sdi-mipi-bridge-footprints:C_0402_1005Metric" (layer "F.Cu")
    (at 120.14 130.71 180)
    (descr "Capacitor SMD 0402")
    (tags "capacitor SMD 0402")
    (property "Author" "Antmicro")
    (property "Dielectric" "")
    (property "License" "Apache-2.0")
    (property "MPN" "0402N160J500CT")
    (property "Manufacturer" "Walsin")
    (property "Sheetfile" "sdi-mipi-bridge.kicad_sch")
    (property "Sheetname" "")
    (property "Val" "16p")
    (property "Voltage" "")
    (property "ki_description" " ")
    (attr smd)
    (fp_text reference "C59" (at 0.94 -0.39) (layer "F.SilkS")
        (effects (font (size 0.65 0.65) (thickness 0.15)) (justify right bottom))
    )
    (fp_text value "C_16p_0402" (at 0 1.4) (layer "F.Fab") hide
        (effects (font (size 0.7 0.7) (thickness 0.15)) (justify right bottom))
    )
    (fp_text user "${REFERENCE}" (at -0.932 3.168) (layer "F.Fab") hide
        (effects (font (size 0.7 0.7) (thickness 0.15)) (justify right bottom))
    )
    (fp_text user "Author: Antmicro" (at -0.932 4.17) (layer "F.Fab") hide
        (effects (font (size 0.7 0.7) (thickness 0.15)) (justify right bottom))
    )
    (fp_text user "License: Apache-2.0" (at -0.932 5.17) (layer "F.Fab") hide
        (effects (font (size 0.7 0.7) (thickness 0.15)) (justify right bottom))
    )
    (fp_rect (start -0.94 -0.47) (end 0.94 0.47)
      (stroke (width 0.05) (type solid)) (fill none) (layer "F.CrtYd"))
    (fp_rect (start -0.499 -0.249) (end 0.499 0.249)
      (stroke (width 0.15) (type solid)) (fill none) (layer "F.Fab"))
    (pad "1" smd roundrect (at -0.484 0 180) (size 0.59 0.64) (layers "F.Cu" "F.Paste" "F.Mask") (roundrect_rratio 0.25)
      (net 1 "GNDREF") (pintype "passive"))
    (pad "2" smd roundrect (at 0.484 0 180) (size 0.59 0.64) (layers "F.Cu" "F.Paste" "F.Mask") (roundrect_rratio 0.25)
      (net 7 "/XTAL2") (pintype "passive"))
  )

  (footprint "sdi-mipi-bridge-footprints:C_0402_1005Metric" (layer "F.Cu")
    (at 123.46 130.71)
    (descr "Capacitor SMD 0402")
    (tags "capacitor SMD 0402")
    (property "Author" "Antmicro")
    (property "Dielectric" "")
    (property "License" "Apache-2.0")
    (property "MPN" "0402N160J500CT")
    (property "Manufacturer" "Walsin")
    (property "Sheetfile" "sdi-mipi-bridge.kicad_sch")
    (property "Sheetname" "")
    (property "Val" "16p")
    (property "Voltage" "")
    (property "ki_description" " ")
    (attr smd)
    (fp_text reference "C60" (at -0.96 1.29) (layer "F.SilkS")
        (effects (font (size 0.65 0.65) (thickness 0.15)) (justify left bottom))
    )
    (fp_text value "C_16p_0402" (at 0 1.4) (layer "F.Fab") hide
        (effects (font (size 0.7 0.7) (thickness 0.15)) (justify left bottom))
    )
    (fp_text user "${REFERENCE}" (at -0.932 3.168) (layer "F.Fab") hide
        (effects (font (size 0.7 0.7) (thickness 0.15)) (justify left bottom))
    )
    (fp_text user "License: Apache-2.0" (at -0.932 5.17) (layer "F.Fab") hide
        (effects (font (size 0.7 0.7) (thickness 0.15)) (justify left bottom))
    )
    (fp_text user "Author: Antmicro" (at -0.932 4.17) (layer "F.Fab") hide
        (effects (font (size 0.7 0.7) (thickness 0.15)) (justify left bottom))
    )
    (fp_rect (start -0.94 -0.47) (end 0.94 0.47)
      (stroke (width 0.05) (type solid)) (fill none) (layer "F.CrtYd"))
    (fp_rect (start -0.499 -0.249) (end 0.499 0.249)
      (stroke (width 0.15) (type solid)) (fill none) (layer "F.Fab"))
    (pad "1" smd roundrect (at -0.484 0) (size 0.59 0.64) (layers "F.Cu" "F.Paste" "F.Mask") (roundrect_rratio 0.25)
      (net 1 "GNDREF") (pintype "passive"))
    (pad "2" smd roundrect (at 0.484 0) (size 0.59 0.64) (layers "F.Cu" "F.Paste" "F.Mask") (roundrect_rratio 0.25)
      (net 8 "/XTAL1") (pintype "passive"))
  )

  (footprint "sdi-mipi-bridge-footprints:Oscillator_SMD_Abracon_ABM7-2Pin_6x3.5mm" (layer "F.Cu")
    (at 121.8 128.15)
    (property "Author" "Antmicro")
    (property "License" "Apache-2.0")
    (property "MPN" "ABM7-27.000MHZ-D2Y-T")
    (property "Manufacturer" "Abracon")
    (property "Sheetfile" "sdi-mipi-bridge.kicad_sch")
    (property "Sheetname" "")
    (attr smd)
    (fp_text reference "Y1" (at -3.25 -2.25) (layer "F.SilkS")
        (effects (font (size 0.65 0.65) (thickness 0.15)) (justify left bottom))
    )
    (fp_text value "Oscillator_SMD_27MHz_ABM7" (at -3 3) (layer "F.Fab") hide
        (effects (font (size 0.7 0.7) (thickness 0.15)) (justify left bottom))
    )
    (fp_text user "License: Apache-2.0" (at -3 7) (layer "F.Fab") hide
        (effects (font (size 0.7 0.7) (thickness 0.15)) (justify left bottom))
    )
    (fp_text user "Author: Antmicro" (at -3.051 5.5) (layer "F.Fab") hide
        (effects (font (size 0.7 0.7) (thickness 0.15)) (justify left bottom))
    )
    (fp_text user "${REFERENCE}" (at -3.051 4.25) (layer "F.Fab") hide
        (effects (font (size 0.7 0.7) (thickness 0.15)) (justify left bottom))
    )
    (fp_line (start -3.102 -1.4745) (end -2.803 -1.7755)
      (stroke (width 0.15) (type solid)) (layer "F.SilkS"))
    (fp_line (start -3.102 1.499) (end -2.801 1.8)
      (stroke (width 0.15) (type solid)) (layer "F.SilkS"))
    (fp_line (start -2.803 -1.7755) (end 2.798 -1.7755)
      (stroke (width 0.15) (type solid)) (layer "F.SilkS"))
    (fp_line (start 2.8 1.8) (end -2.801 1.8)
      (stroke (width 0.15) (type solid)) (layer "F.SilkS"))
    (fp_line (start 3.099 -1.4745) (end 2.798 -1.7755)
      (stroke (width 0.15) (type solid)) (layer "F.SilkS"))
    (fp_line (start 3.099 1.499) (end 2.8 1.8)
      (stroke (width 0.15) (type solid)) (layer "F.SilkS"))
    (fp_rect (start -3.251 -1.95) (end 3.248 1.949)
      (stroke (width 0.05) (type solid)) (fill none) (layer "F.CrtYd"))
    (pad "1" smd rect (at -2.15 0) (size 1.9 2.6) (layers "F.Cu" "F.Paste" "F.Mask")
      (net 7 "/XTAL2") (pintype "passive"))
    (pad "2" smd rect (at 2.148 0) (size 1.9 2.6) (layers "F.Cu" "F.Paste" "F.Mask")
      (net 8 "/XTAL1") (pintype "passive"))
  )

  (footprint "sdi-mipi-bridge-footprints:PinHeader_2x5_P1.27mm_Drill0.65mm" (layer "F.Cu")
    (at 121.889 133.95 180)
    (descr "Through hole straight pin header, 2x5, 1.27mm pitch, double rows")
    (tags "Through hole pin header THT 2x5 1.27mm double row")
    (property "Author" "Antmicro")
    (property "License" "Apache-2.0")
    (property "MPN" "2199SB-10G-301523")
    (property "Manufacturer" "Multicomp Pro")
    (property "Sheetfile" "sdi-mipi-bridge.kicad_sch")
    (property "Sheetname" "")
    (property "ki_description" "Pin Header, Board-to-Board, 1.27 mm, 2 Rows, 10 Contacts, Through Hole Straight, 2199SB")
    (property "ki_keywords" "PINSTRIP, HEADER, THT")
    (attr through_hole)
    (fp_text reference "J4" (at 0 -2.9 180) (layer "F.SilkS")
        (effects (font (size 0.7 0.7) (thickness 0.15)) (justify left bottom))
    )
    (fp_text value "PinHeader_2x5_P1.27mm_Vertical" (at 0 2.3 180) (layer "F.Fab")
        (effects (font (size 0.7 0.7) (thickness 0.15)) (justify left bottom))
    )
    (fp_text user "${REFERENCE}" (at -1.135 9.999 180) (layer "F.Fab") hide
        (effects (font (size 0.7 0.7) (thickness 0.15)) (justify left bottom))
    )
    (fp_text user "Author: Antmicro" (at -1.135 12.399 180) (layer "F.Fab") hide
        (effects (font (size 0.7 0.7) (thickness 0.15)) (justify left bottom))
    )
    (fp_text user "License: Apache-2.0" (at -1.135 11.198 180) (layer "F.Fab") hide
        (effects (font (size 0.7 0.7) (thickness 0.15)) (justify left bottom))
    )
    (fp_line (start -0.702 -2.403) (end -0.702 -1.901)
      (stroke (width 0.15) (type solid)) (layer "F.SilkS"))
    (fp_line (start -0.702 -2.403) (end -0.202 -2.403)
      (stroke (width 0.15) (type solid)) (layer "F.SilkS"))
    (fp_line (start 5.797 -2.4) (end 5.297 -2.4)
      (stroke (width 0.15) (type solid)) (layer "F.SilkS"))
    (fp_line (start 5.797 -2.4) (end 5.797 -1.899)
      (stroke (width 0.15) (type solid)) (layer "F.SilkS"))
    (fp_line (start 5.797 1.1) (end 5.297 1.1)
      (stroke (width 0.15) (type solid)) (layer "F.SilkS"))
    (fp_line (start 5.797 1.1) (end 5.797 0.598)
      (stroke (width 0.15) (type solid)) (layer "F.SilkS"))
    (fp_poly
      (pts
        (xy -0.702 0.598)
        (xy -0.702 1.1)
        (xy -0.202 1.1)
      )

      (stroke (width 0.15) (type solid)) (fill solid) (layer "F.SilkS"))
    (fp_rect (start -0.9 -2.6) (end 6 1.3)
      (stroke (width 0.05) (type solid)) (fill none) (layer "F.CrtYd"))
    (fp_line (start -0.635 -2.339) (end 5.712 -2.339)
      (stroke (width 0.15) (type solid)) (layer "F.Fab"))
    (fp_line (start -0.635 0.216) (end -0.635 -2.339)
      (stroke (width 0.15) (type solid)) (layer "F.Fab"))
    (fp_line (start 0.214 1.07) (end -0.635 0.216)
      (stroke (width 0.15) (type solid)) (layer "F.Fab"))
    (fp_line (start 5.712 -2.339) (end 5.712 1.07)
      (stroke (width 0.15) (type solid)) (layer "F.Fab"))
    (fp_line (start 5.712 1.07) (end 0.214 1.07)
      (stroke (width 0.15) (type solid)) (layer "F.Fab"))
    (pad "1" thru_hole rect (at 0 0 270) (size 1 1) (drill 0.65) (layers "*.Cu" "*.Mask")
      (net 28 "/AUDIO_SERIAL_BIT_CLK") (pintype "passive"))
    (pad "2" thru_hole oval (at 0 -1.27 270) (size 1 1) (drill 0.65) (layers "*.Cu" "*.Mask")
      (net 28 "/AUDIO_SERIAL_BIT_CLK") (pintype "passive"))
    (pad "3" thru_hole oval (at 1.269 0 270) (size 1 1) (drill 0.65) (layers "*.Cu" "*.Mask")
      (net 60 "/AUDIO_WORD_CLK") (pintype "passive"))
    (pad "4" thru_hole oval (at 1.269 -1.27 270) (size 1 1) (drill 0.65) (layers "*.Cu" "*.Mask")
      (net 60 "/AUDIO_WORD_CLK") (pintype "passive"))
    (pad "5" thru_hole oval (at 2.539 0 270) (size 1 1) (drill 0.65) (layers "*.Cu" "*.Mask")
      (net 52 "/AUDIO_OUTPUT_CH1_2") (pintype "passive"))
    (pad "6" thru_hole oval (at 2.539 -1.27 270) (size 1 1) (drill 0.65) (layers "*.Cu" "*.Mask")
      (net 50 "/AUDIO_OUTPUT_CH5_6") (pintype "passive"))
    (pad "7" thru_hole oval (at 3.809 0 270) (size 1 1) (drill 0.65) (layers "*.Cu" "*.Mask")
      (net 51 "/AUDIO_OUTPUT_CH3_4") (pintype "passive"))
    (pad "8" thru_hole oval (at 3.809 -1.27 270) (size 1 1) (drill 0.65) (layers "*.Cu" "*.Mask")
      (net 49 "/AUDIO_OUTPUT_CH7_8") (pintype "passive"))
    (pad "9" thru_hole oval (at 5.076 0 270) (size 1 1) (drill 0.65) (layers "*.Cu" "*.Mask")
      (net 3 "GNDA") (pintype "passive"))
    (pad "10" thru_hole oval (at 5.076 -1.27 270) (size 1 1) (drill 0.65) (layers "*.Cu" "*.Mask")
      (net 26 "/AUDIO_MASTER_CLK") (pintype "passive"))
  )

  (footprint "sdi-mipi-bridge-footprints:R_0402_1005Metric" (layer "F.Cu")
    (at 153.4 133 -90)
    (descr "Resistor SMD 0402")
    (tags "resistor SMD 0402")
    (property "Author" "Antmicro")
    (property "Current" "1A")
    (property "License" "Apache-2.0")
    (property "MPN" "ERJ2GE0R00X")
    (property "Manufacturer" "Panasonic")
    (property "Sheetfile" "sdi-mipi-bridge.kicad_sch")
    (property "Sheetname" "")
    (property "Tolerance" "")
    (property "Val" "0R")
    (property "ki_description" "0R resistor in 0402 package with unspecified tolerance")
    (attr smd)
    (fp_text reference "R82" (at 1.05 -0.35 90) (layer "F.SilkS")
        (effects (font (size 0.65 0.65) (thickness 0.15)) (justify right bottom))
    )
    (fp_text value "R_0R_0402" (at 0 1.4 90) (layer "F.Fab") hide
        (effects (font (size 0.7 0.7) (thickness 0.15)) (justify right bottom))
    )
    (fp_text user "License: Apache-2.0" (at -0.95 5.169 90) (layer "F.Fab") hide
        (effects (font (size 0.7 0.7) (thickness 0.15)) (justify right bottom))
    )
    (fp_text user "${REFERENCE}" (at -0.95 3.168 90) (layer "F.Fab") hide
        (effects (font (size 0.7 0.7) (thickness 0.15)) (justify right bottom))
    )
    (fp_text user "Author: Antmicro" (at -0.95 4.169 90) (layer "F.Fab") hide
        (effects (font (size 0.7 0.7) (thickness 0.15)) (justify right bottom))
    )
    (fp_rect (start -0.93 -0.47) (end 0.93 0.47)
      (stroke (width 0.05) (type solid)) (fill none) (layer "F.CrtYd"))
    (fp_rect (start -0.5 -0.25) (end 0.5 0.25)
      (stroke (width 0.15) (type solid)) (fill none) (layer "F.Fab"))
    (pad "1" smd roundrect (at -0.485 0 270) (size 0.59 0.64) (layers "F.Cu" "F.Paste" "F.Mask") (roundrect_rratio 0.25)
      (net 105 "/USER_SW") (pintype "passive"))
    (pad "2" smd roundrect (at 0.485 0 270) (size 0.59 0.64) (layers "F.Cu" "F.Paste" "F.Mask") (roundrect_rratio 0.25)
      (net 125 "Net-(R82-Pad2)") (pintype "passive"))
  )

  (footprint "sdi-mipi-bridge-footprints:PinHeader_1x4_P1.27mm_Drill0.7mm" (layer "F.Cu")
    (at 117.35 102.25 90)
    (descr "http://cnctech.us/pdfs/3220-XX-0100-00.pdf")
    (property "Author" "Antmicro")
    (property "License" "Apache-2.0")
    (property "MPN" "MC-HVT1-S04-G")
    (property "Manufacturer" "Multicomp Pro")
    (property "Sheetfile" "sdi-mipi-bridge.kicad_sch")
    (property "Sheetname" "")
    (property "ki_description" "Pin Header, Board-to-Board, 1.27 mm, 1 Rows, 4 Contacts, Through Hole")
    (property "ki_keywords" "PINSTRIP, HEADER ")
    (attr through_hole)
    (fp_text reference "J5" (at 2.64 -4.08 90) (layer "F.SilkS")
        (effects (font (size 0.7 0.7) (thickness 0.15)) (justify left bottom))
    )
    (fp_text value "PinHeader_1x4_P1.27mm_Drill.7mm" (at 3.1 3.039 90) (layer "F.Fab") hide
        (effects (font (size 0.7 0.7) (thickness 0.15)) (justify left bottom))
    )
    (fp_text user "${REFERENCE}" (at -4.446 5.038 90) (layer "F.Fab") hide
        (effects (font (size 0.7 0.7) (thickness 0.15)) (justify left bottom))
    )
    (fp_text user "Author: Antmicro" (at -4.446 6.24 90) (layer "F.Fab") hide
        (effects (font (size 0.7 0.7) (thickness 0.15)) (justify left bottom))
    )
    (fp_text user "License: Apache-2.0" (at -4.446 7.44 90) (layer "F.Fab") hide
        (effects (font (size 0.7 0.7) (thickness 0.15)) (justify left bottom))
    )
    (fp_line (start -1.216 1.225) (end -1.216 0.723)
      (stroke (width 0.15) (type solid)) (layer "F.SilkS"))
    (fp_line (start -1.216 1.225) (end -0.715 1.225)
      (stroke (width 0.15) (type solid)) (layer "F.SilkS"))
    (fp_line (start 5.025 -1.226) (end 4.525 -1.226)
      (stroke (width 0.15) (type solid)) (layer "F.SilkS"))
    (fp_line (start 5.025 -1.226) (end 5.025 -0.725)
      (stroke (width 0.15) (type solid)) (layer "F.SilkS"))
    (fp_line (start 5.025 1.225) (end 4.525 1.225)
      (stroke (width 0.15) (type solid)) (layer "F.SilkS"))
    (fp_line (start 5.025 1.225) (end 5.025 0.723)
      (stroke (width 0.15) (type solid)) (layer "F.SilkS"))
    (fp_circle (center 0 -1.851) (end 0.05 -1.851)
      (stroke (width 0.15) (type solid)) (fill solid) (layer "F.SilkS"))
    (fp_poly
      (pts
        (xy -1.216 -0.725)
        (xy -1.216 -1.226)
        (xy -0.715 -1.226)
      )

      (stroke (width 0.15) (type solid)) (fill solid) (layer "F.SilkS"))
    (fp_rect (start 4.929 1.55) (end -1.15 -1.551)
      (stroke (width 0.05) (type solid)) (fill none) (layer "F.CrtYd"))
    (fp_line (start -1.101 1.1) (end 4.9 1.1)
      (stroke (width 0.15) (type solid)) (layer "F.Fab"))
    (fp_line (start -1.1 -0.5) (end -1.101 1.1)
      (stroke (width 0.15) (type solid)) (layer "F.Fab"))
    (fp_line (start -1.1 -0.5) (end -0.5 -1.1)
      (stroke (width 0.15) (type solid)) (layer "F.Fab"))
    (fp_line (start -0.5 -1.1) (end 4.9 -1.101)
      (stroke (width 0.15) (type solid)) (layer "F.Fab"))
    (fp_line (start 4.9 -1.101) (end 4.9 1.1)
      (stroke (width 0.15) (type solid)) (layer "F.Fab"))
    (pad "1" thru_hole circle (at 0 0 90) (size 1.1 1.1) (drill 0.7) (layers "*.Cu" "*.Mask")
      (net 6 "+3V3") (pintype "passive"))
    (pad "2" thru_hole circle (at 1.269 0 90) (size 1.1 1.1) (drill 0.7) (layers "*.Cu" "*.Mask")
      (net 62 "/SDA_GS") (pintype "passive"))
    (pad "3" thru_hole circle (at 2.539 0 90) (size 1.1 1.1) (drill 0.7) (layers "*.Cu" "*.Mask")
      (net 61 "/SCL_GS") (pintype "passive"))
    (pad "4" thru_hole circle (at 3.809 0 90) (size 1.1 1.1) (drill 0.7) (layers "*.Cu" "*.Mask")
      (net 1 "GNDREF") (pintype "passive"))
  )

  (footprint "sdi-mipi-bridge-footprints:R_0402_1005Metric" (layer "F.Cu")
    (at 140.5 129.75 90)
    (descr "Resistor SMD 0402")
    (tags "resistor SMD 0402")
    (property "Author" "Antmicro")
    (property "License" "Apache-2.0")
    (property "MPN" "CR0402-FX-1002GLF")
    (property "Manufacturer" "Bourns")
    (property "Sheetfile" "sdi-mipi-bridge.kicad_sch")
    (property "Sheetname" "")
    (property "Tolerance" "1%")
    (property "Val" "10k")
    (property "ki_description" "10k resistor in 0402 package with 1% tolerance")
    (attr smd)
    (fp_text reference "R76" (at -5.75 0.4 90) (layer "F.SilkS")
        (effects (font (size 0.65 0.65) (thickness 0.15)) (justify left bottom))
    )
    (fp_text value "R_10k_0402" (at 0 1.4 90) (layer "F.Fab") hide
        (effects (font (size 0.7 0.7) (thickness 0.15)) (justify left bottom))
    )
    (fp_text user "License: Apache-2.0" (at -0.95 5.169 90) (layer "F.Fab") hide
        (effects (font (size 0.7 0.7) (thickness 0.15)) (justify left bottom))
    )
    (fp_text user "Author: Antmicro" (at -0.95 4.169 90) (layer "F.Fab") hide
        (effects (font (size 0.7 0.7) (thickness 0.15)) (justify left bottom))
    )
    (fp_text user "${REFERENCE}" (at -0.95 3.168 90) (layer "F.Fab") hide
        (effects (font (size 0.7 0.7) (thickness 0.15)) (justify left bottom))
    )
    (fp_rect (start -0.93 -0.47) (end 0.93 0.47)
      (stroke (width 0.05) (type solid)) (fill none) (layer "F.CrtYd"))
    (fp_rect (start -0.5 -0.25) (end 0.5 0.25)
      (stroke (width 0.15) (type solid)) (fill none) (layer "F.Fab"))
    (pad "1" smd roundrect (at -0.485 0 90) (size 0.59 0.64) (layers "F.Cu" "F.Paste" "F.Mask") (roundrect_rratio 0.25)
      (net 53 "/Audio_EN_~{DIS}") (pintype "passive"))
    (pad "2" smd roundrect (at 0.485 0 90) (size 0.59 0.64) (layers "F.Cu" "F.Paste" "F.Mask") (roundrect_rratio 0.25)
      (net 76 "IO_VDD") (pintype "passive"))
  )

  (footprint "sdi-mipi-bridge-footprints:R_0402_1005Metric" (layer "F.Cu")
    (at 140.5 131.75 90)
    (descr "Resistor SMD 0402")
    (tags "resistor SMD 0402")
    (property "Author" "Antmicro")
    (property "DNP" "DNP")
    (property "License" "Apache-2.0")
    (property "MPN" "CR0402-FX-1002GLF")
    (property "Manufacturer" "Bourns")
    (property "Sheetfile" "sdi-mipi-bridge.kicad_sch")
    (property "Sheetname" "")
    (property "Tolerance" "1%")
    (property "Val" "10k")
    (property "ki_description" "10k resistor in 0402 package with 1% tolerance")
    (attr exclude_from_pos_files)
    (fp_text reference "R77" (at -5.75 0.4 90) (layer "F.SilkS")
        (effects (font (size 0.65 0.65) (thickness 0.15)) (justify left bottom))
    )
    (fp_text value "R_10k_0402" (at 0 1.4 90) (layer "F.Fab") hide
        (effects (font (size 0.7 0.7) (thickness 0.15)) (justify left bottom))
    )
    (fp_text user "License: Apache-2.0" (at -0.95 5.169 90) (layer "F.Fab") hide
        (effects (font (size 0.7 0.7) (thickness 0.15)) (justify left bottom))
    )
    (fp_text user "${REFERENCE}" (at -0.95 3.168 90) (layer "F.Fab") hide
        (effects (font (size 0.7 0.7) (thickness 0.15)) (justify left bottom))
    )
    (fp_text user "Author: Antmicro" (at -0.95 4.169 90) (layer "F.Fab") hide
        (effects (font (size 0.7 0.7) (thickness 0.15)) (justify left bottom))
    )
    (fp_rect (start -0.93 -0.47) (end 0.93 0.47)
      (stroke (width 0.05) (type solid)) (fill none) (layer "F.CrtYd"))
    (fp_rect (start -0.5 -0.25) (end 0.5 0.25)
      (stroke (width 0.15) (type solid)) (fill none) (layer "F.Fab"))
    (pad "1" smd roundrect (at -0.485 0 90) (size 0.59 0.64) (layers "F.Cu" "F.Paste" "F.Mask") (roundrect_rratio 0.25)
      (net 3 "GNDA") (pintype "passive"))
    (pad "2" smd roundrect (at 0.485 0 90) (size 0.59 0.64) (layers "F.Cu" "F.Paste" "F.Mask") (roundrect_rratio 0.25)
      (net 53 "/Audio_EN_~{DIS}") (pintype "passive"))
  )

  (footprint "sdi-mipi-bridge-footprints:PinHeader_2x5_P1.27mm_Drill0.65mm" (layer "F.Cu")
    (at 158.514 102.755499 90)
    (descr "Through hole straight pin header, 2x5, 1.27mm pitch, double rows")
    (tags "Through hole pin header THT 2x5 1.27mm double row")
    (property "Author" "Antmicro")
    (property "License" "Apache-2.0")
    (property "MPN" "2199SB-10G-301523")
    (property "Manufacturer" "Multicomp Pro")
    (property "Sheetfile" "sdi-mipi-bridge.kicad_sch")
    (property "Sheetname" "")
    (property "ki_description" "Pin Header, Board-to-Board, 1.27 mm, 2 Rows, 10 Contacts, Through Hole Straight, 2199SB")
    (property "ki_keywords" "PINSTRIP, HEADER, THT")
    (attr through_hole)
    (fp_text reference "J6" (at 0 -2.9 90) (layer "F.SilkS")
        (effects (font (size 0.7 0.7) (thickness 0.15)) (justify left bottom))
    )
    (fp_text value "PinHeader_2x5_P1.27mm_Vertical" (at 0 2.3 90) (layer "F.Fab") hide
        (effects (font (size 0.7 0.7) (thickness 0.15)) (justify left bottom))
    )
    (fp_text user "${REFERENCE}" (at -1.135 9.999 90) (layer "F.Fab") hide
        (effects (font (size 0.7 0.7) (thickness 0.15)) (justify left bottom))
    )
    (fp_text user "License: Apache-2.0" (at -1.135 11.198 90) (layer "F.Fab") hide
        (effects (font (size 0.7 0.7) (thickness 0.15)) (justify left bottom))
    )
    (fp_text user "Author: Antmicro" (at -1.135 12.399 90) (layer "F.Fab") hide
        (effects (font (size 0.7 0.7) (thickness 0.15)) (justify left bottom))
    )
    (fp_line (start -0.702 -2.403) (end -0.702 -1.901)
      (stroke (width 0.15) (type solid)) (layer "F.SilkS"))
    (fp_line (start -0.702 -2.403) (end -0.202 -2.403)
      (stroke (width 0.15) (type solid)) (layer "F.SilkS"))
    (fp_line (start 5.797 -2.4) (end 5.297 -2.4)
      (stroke (width 0.15) (type solid)) (layer "F.SilkS"))
    (fp_line (start 5.797 -2.4) (end 5.797 -1.899)
      (stroke (width 0.15) (type solid)) (layer "F.SilkS"))
    (fp_line (start 5.797 1.1) (end 5.297 1.1)
      (stroke (width 0.15) (type solid)) (layer "F.SilkS"))
    (fp_line (start 5.797 1.1) (end 5.797 0.598)
      (stroke (width 0.15) (type solid)) (layer "F.SilkS"))
    (fp_poly
      (pts
        (xy -0.702 0.598)
        (xy -0.702 1.1)
        (xy -0.202 1.1)
      )

      (stroke (width 0.15) (type solid)) (fill solid) (layer "F.SilkS"))
    (fp_rect (start -0.9 -2.6) (end 6 1.3)
      (stroke (width 0.05) (type solid)) (fill none) (layer "F.CrtYd"))
    (fp_line (start -0.635 -2.339) (end 5.712 -2.339)
      (stroke (width 0.15) (type solid)) (layer "F.Fab"))
    (fp_line (start -0.635 0.216) (end -0.635 -2.339)
      (stroke (width 0.15) (type solid)) (layer "F.Fab"))
    (fp_line (start 0.214 1.07) (end -0.635 0.216)
      (stroke (width 0.15) (type solid)) (layer "F.Fab"))
    (fp_line (start 5.712 -2.339) (end 5.712 1.07)
      (stroke (width 0.15) (type solid)) (layer "F.Fab"))
    (fp_line (start 5.712 1.07) (end 0.214 1.07)
      (stroke (width 0.15) (type solid)) (layer "F.Fab"))
    (pad "1" thru_hole rect (at 0 0 180) (size 1 1) (drill 0.65) (layers "*.Cu" "*.Mask")
      (net 6 "+3V3") (pintype "passive"))
    (pad "2" thru_hole oval (at 0 -1.27 180) (size 1 1) (drill 0.65) (layers "*.Cu" "*.Mask")
      (net 103 "/USER_SDA") (pintype "passive"))
    (pad "3" thru_hole oval (at 1.269 0 180) (size 1 1) (drill 0.65) (layers "*.Cu" "*.Mask")
      (net 102 "/SPI_SCK(SDA)") (pintype "passive"))
    (pad "4" thru_hole oval (at 1.269 -1.27 180) (size 1 1) (drill 0.65) (layers "*.Cu" "*.Mask")
      (net 101 "/USER_SCL") (pintype "passive"))
    (pad "5" thru_hole oval (at 2.539 0 180) (size 1 1) (drill 0.65) (layers "*.Cu" "*.Mask")
      (net 97 "/MOSI") (pintype "passive"))
    (pad "6" thru_hole oval (at 2.539 -1.27 180) (size 1 1) (drill 0.65) (layers "*.Cu" "*.Mask")
      (net 124 "unconnected-(J6-Pad6)") (pintype "passive+no_connect"))
    (pad "7" thru_hole oval (at 3.809 0 180) (size 1 1) (drill 0.65) (layers "*.Cu" "*.Mask")
      (net 96 "/MISO") (pintype "passive"))
    (pad "8" thru_hole oval (at 3.809 -1.27 180) (size 1 1) (drill 0.65) (layers "*.Cu" "*.Mask")
      (net 100 "/CRESET_B") (pintype "passive"))
    (pad "9" thru_hole oval (at 5.076 0 180) (size 1 1) (drill 0.65) (layers "*.Cu" "*.Mask")
      (net 99 "/SPI_SS(SCL)") (pintype "passive"))
    (pad "10" thru_hole oval (at 5.076 -1.27 180) (size 1 1) (drill 0.65) (layers "*.Cu" "*.Mask")
      (net 1 "GNDREF") (pintype "passive"))
  )

  (footprint "sdi-mipi-bridge-footprints:R_0402_1005Metric" (layer "F.Cu")
    (at 142.1 110.925 -90)
    (descr "Resistor SMD 0402")
    (tags "resistor SMD 0402")
    (property "Author" "Antmicro")
    (property "License" "Apache-2.0")
    (property "MPN" "CR0402-FX-30R0GLF")
    (property "Manufacturer" "Bourns")
    (property "Sheetfile" "sdi-mipi-bridge.kicad_sch")
    (property "Sheetname" "")
    (property "Tolerance" "1%")
    (property "Val" "30R")
    (property "ki_description" "30R resistor in 0402 package with 1% tolerance")
    (attr smd)
    (fp_text reference "R96" (at -0.925 -0.35 -90) (layer "F.SilkS")
        (effects (font (size 0.65 0.65) (thickness 0.15)) (justify left bottom))
    )
    (fp_text value "R_30R_0402" (at 0 1.4 -90) (layer "F.Fab") hide
        (effects (font (size 0.7 0.7) (thickness 0.15)) (justify left bottom))
    )
    (fp_text user "${REFERENCE}" (at -0.95 3.168 -90) (layer "F.Fab") hide
        (effects (font (size 0.7 0.7) (thickness 0.15)) (justify left bottom))
    )
    (fp_text user "Author: Antmicro" (at -0.95 4.169 -90) (layer "F.Fab") hide
        (effects (font (size 0.7 0.7) (thickness 0.15)) (justify left bottom))
    )
    (fp_text user "License: Apache-2.0" (at -0.95 5.169 -90) (layer "F.Fab") hide
        (effects (font (size 0.7 0.7) (thickness 0.15)) (justify left bottom))
    )
    (fp_rect (start -0.93 -0.47) (end 0.93 0.47)
      (stroke (width 0.05) (type solid)) (fill none) (layer "F.CrtYd"))
    (fp_rect (start -0.5 -0.25) (end 0.5 0.25)
      (stroke (width 0.15) (type solid)) (fill none) (layer "F.Fab"))
    (pad "1" smd roundrect (at -0.485 0 270) (size 0.59 0.64) (layers "F.Cu" "F.Paste" "F.Mask") (roundrect_rratio 0.25)
      (net 102 "/SPI_SCK(SDA)") (pintype "passive"))
    (pad "2" smd roundrect (at 0.485 0 270) (size 0.59 0.64) (layers "F.Cu" "F.Paste" "F.Mask") (roundrect_rratio 0.25)
      (net 128 "Net-(U4-PB53{slash}SPI_SCK{slash}MCK{slash}SDA)") (pintype "passive"))
  )

  (footprint "sdi-mipi-bridge-footprints:oshw-logo" (layer "F.Cu")
    (at 109.7 99.9)
    (descr "OSHW Logo")
    (tags "OSHW Logo")
    (property "Author" "Antmicro")
    (property "License" "Apache-2.0")
    (property "MPN" "")
    (property "Manufacturer" "")
    (property "Sheetfile" "sdi-mipi-bridge.kicad_sch")
    (property "Sheetname" "")
    (attr smd)
    (fp_text reference "N2" (at 0 -4.4) (layer "F.SilkS") hide
        (effects (font (size 0.65 0.65) (thickness 0.15)) (justify left bottom))
    )
    (fp_text value "oshw_logo" (at 0 -3.4) (layer "F.Fab") hide
        (effects (font (size 0.7 0.7) (thickness 0.15)) (justify left bottom))
    )
    (fp_text user "Author: Antmicro" (at -3.081 6.404) (layer "F.Fab") hide
        (effects (font (size 0.7 0.7) (thickness 0.15)) (justify left bottom))
    )
    (fp_text user "License: Apache-2.0" (at -3.081 7.604) (layer "F.Fab") hide
        (effects (font (size 0.7 0.7) (thickness 0.15)) (justify left bottom))
    )
    (fp_text user "${REFERENCE}" (at -3.081 5.204) (layer "F.Fab") hide
        (effects (font (size 0.7 0.7) (thickness 0.15)) (justify left bottom))
    )
    (fp_poly
      (pts
        (xy -0.843 2.558)
        (xy -0.815 2.564)
        (xy -0.794 2.572)
        (xy -0.773 2.581)
        (xy -0.759 2.589)
        (xy -0.738 2.603)
        (xy -0.783 2.658)
        (xy -0.8 2.677)
        (xy -0.814 2.694)
        (xy -0.825 2.706)
        (xy -0.831 2.712)
        (xy -0.832 2.712)
        (xy -0.837 2.71)
        (xy -0.847 2.703)
        (xy -0.849 2.702)
        (xy -0.874 2.69)
        (xy -0.904 2.684)
        (xy -0.935 2.685)
        (xy -0.942 2.686)
        (xy -0.975 2.698)
        (xy -1.001 2.717)
        (xy -1.02 2.741)
        (xy -1.034 2.766)
        (xy -1.039 3.197)
        (xy -1.164 3.2)
        (xy -1.164 2.565)
        (xy -1.037 2.565)
        (xy -1.037 2.626)
        (xy -1.009 2.604)
        (xy -0.972 2.579)
        (xy -0.931 2.563)
        (xy -0.887 2.556)
        (xy -0.843 2.558)
      )

      (stroke (width 0.01) (type solid)) (fill solid) (layer "F.Cu"))
    (fp_poly
      (pts
        (xy 1.889 1.554)
        (xy 1.907 1.559)
        (xy 1.927 1.566)
        (xy 1.948 1.574)
        (xy 1.966 1.583)
        (xy 1.979 1.592)
        (xy 1.984 1.597)
        (xy 1.982 1.604)
        (xy 1.974 1.616)
        (xy 1.962 1.633)
        (xy 1.946 1.652)
        (xy 1.945 1.654)
        (xy 1.929 1.673)
        (xy 1.915 1.689)
        (xy 1.906 1.7)
        (xy 1.901 1.706)
        (xy 1.896 1.705)
        (xy 1.885 1.7)
        (xy 1.873 1.695)
        (xy 1.84 1.683)
        (xy 1.808 1.68)
        (xy 1.776 1.685)
        (xy 1.747 1.698)
        (xy 1.723 1.717)
        (xy 1.704 1.742)
        (xy 1.696 1.763)
        (xy 1.695 1.772)
        (xy 1.694 1.79)
        (xy 1.693 1.817)
        (xy 1.692 1.85)
        (xy 1.692 1.89)
        (xy 1.691 1.934)
        (xy 1.691 1.983)
        (xy 1.691 2.194)
        (xy 1.559 2.194)
        (xy 1.559 1.559)
        (xy 1.691 1.559)
        (xy 1.691 1.626)
        (xy 1.71 1.607)
        (xy 1.739 1.585)
        (xy 1.775 1.568)
        (xy 1.814 1.556)
        (xy 1.855 1.552)
        (xy 1.889 1.554)
      )

      (stroke (width 0.01) (type solid)) (fill solid) (layer "F.Cu"))
    (fp_poly
      (pts
        (xy -0.837 1.56)
        (xy -0.797 1.576)
        (xy -0.761 1.6)
        (xy -0.73 1.63)
        (xy -0.706 1.667)
        (xy -0.69 1.709)
        (xy -0.687 1.721)
        (xy -0.685 1.734)
        (xy -0.684 1.757)
        (xy -0.683 1.79)
        (xy -0.682 1.833)
        (xy -0.681 1.884)
        (xy -0.681 1.945)
        (xy -0.681 1.971)
        (xy -0.681 2.194)
        (xy -0.808 2.194)
        (xy -0.809 1.984)
        (xy -0.811 1.774)
        (xy -0.826 1.744)
        (xy -0.845 1.716)
        (xy -0.868 1.697)
        (xy -0.897 1.686)
        (xy -0.925 1.682)
        (xy -0.947 1.682)
        (xy -0.967 1.684)
        (xy -0.979 1.686)
        (xy -1.001 1.698)
        (xy -1.023 1.716)
        (xy -1.041 1.738)
        (xy -1.049 1.752)
        (xy -1.052 1.758)
        (xy -1.054 1.765)
        (xy -1.056 1.773)
        (xy -1.057 1.783)
        (xy -1.058 1.797)
        (xy -1.059 1.815)
        (xy -1.06 1.839)
        (xy -1.06 1.869)
        (xy -1.061 1.907)
        (xy -1.061 1.953)
        (xy -1.061 1.985)
        (xy -1.063 2.194)
        (xy -1.189 2.194)
        (xy -1.189 1.559)
        (xy -1.062 1.559)
        (xy -1.062 1.625)
        (xy -1.033 1.602)
        (xy -1.001 1.579)
        (xy -0.969 1.564)
        (xy -0.934 1.555)
        (xy -0.927 1.554)
        (xy -0.881 1.553)
        (xy -0.837 1.56)
      )

      (stroke (width 0.01) (type solid)) (fill solid) (layer "F.Cu"))
    (fp_poly
      (pts
        (xy 1.042 1.769)
        (xy 1.043 1.979)
        (xy 1.059 2.009)
        (xy 1.077 2.036)
        (xy 1.1 2.056)
        (xy 1.129 2.067)
        (xy 1.159 2.071)
        (xy 1.193 2.07)
        (xy 1.221 2.063)
        (xy 1.245 2.047)
        (xy 1.258 2.034)
        (xy 1.266 2.025)
        (xy 1.273 2.016)
        (xy 1.278 2.008)
        (xy 1.282 1.997)
        (xy 1.286 1.985)
        (xy 1.288 1.969)
        (xy 1.29 1.948)
        (xy 1.291 1.922)
        (xy 1.292 1.89)
        (xy 1.293 1.85)
        (xy 1.293 1.801)
        (xy 1.294 1.766)
        (xy 1.295 1.559)
        (xy 1.422 1.559)
        (xy 1.422 2.194)
        (xy 1.295 2.194)
        (xy 1.295 2.161)
        (xy 1.295 2.144)
        (xy 1.293 2.132)
        (xy 1.292 2.128)
        (xy 1.287 2.131)
        (xy 1.278 2.14)
        (xy 1.271 2.147)
        (xy 1.256 2.159)
        (xy 1.236 2.171)
        (xy 1.219 2.181)
        (xy 1.202 2.188)
        (xy 1.186 2.193)
        (xy 1.17 2.196)
        (xy 1.148 2.197)
        (xy 1.135 2.198)
        (xy 1.107 2.198)
        (xy 1.087 2.197)
        (xy 1.07 2.194)
        (xy 1.059 2.19)
        (xy 1.036 2.181)
        (xy 1.019 2.172)
        (xy 1.003 2.161)
        (xy 0.985 2.146)
        (xy 0.981 2.141)
        (xy 0.952 2.107)
        (xy 0.931 2.068)
        (xy 0.92 2.033)
        (xy 0.918 2.019)
        (xy 0.917 1.996)
        (xy 0.916 1.963)
        (xy 0.915 1.92)
        (xy 0.914 1.869)
        (xy 0.914 1.808)
        (xy 0.914 1.782)
        (xy 0.914 1.559)
        (xy 1.04 1.559)
        (xy 1.042 1.769)
      )

      (stroke (width 0.01) (type solid)) (fill solid) (layer "F.Cu"))
    (fp_poly
      (pts
        (xy 1.753 2.563)
        (xy 1.768 2.568)
        (xy 1.787 2.577)
        (xy 1.804 2.586)
        (xy 1.818 2.595)
        (xy 1.826 2.602)
        (xy 1.827 2.606)
        (xy 1.824 2.611)
        (xy 1.815 2.621)
        (xy 1.803 2.636)
        (xy 1.789 2.654)
        (xy 1.775 2.671)
        (xy 1.761 2.688)
        (xy 1.749 2.701)
        (xy 1.742 2.71)
        (xy 1.739 2.712)
        (xy 1.735 2.71)
        (xy 1.724 2.704)
        (xy 1.713 2.698)
        (xy 1.697 2.69)
        (xy 1.682 2.686)
        (xy 1.664 2.685)
        (xy 1.653 2.685)
        (xy 1.618 2.688)
        (xy 1.59 2.699)
        (xy 1.566 2.718)
        (xy 1.561 2.723)
        (xy 1.554 2.732)
        (xy 1.548 2.74)
        (xy 1.544 2.748)
        (xy 1.54 2.758)
        (xy 1.537 2.769)
        (xy 1.534 2.785)
        (xy 1.533 2.804)
        (xy 1.532 2.829)
        (xy 1.531 2.861)
        (xy 1.53 2.899)
        (xy 1.53 2.947)
        (xy 1.53 2.988)
        (xy 1.528 3.2)
        (xy 1.468 3.2)
        (xy 1.444 3.2)
        (xy 1.425 3.199)
        (xy 1.411 3.198)
        (xy 1.405 3.197)
        (xy 1.404 3.191)
        (xy 1.404 3.176)
        (xy 1.403 3.153)
        (xy 1.403 3.122)
        (xy 1.402 3.085)
        (xy 1.402 3.042)
        (xy 1.402 2.993)
        (xy 1.402 2.941)
        (xy 1.402 2.886)
        (xy 1.402 2.565)
        (xy 1.529 2.565)
        (xy 1.529 2.595)
        (xy 1.529 2.611)
        (xy 1.53 2.623)
        (xy 1.532 2.626)
        (xy 1.537 2.623)
        (xy 1.547 2.615)
        (xy 1.554 2.608)
        (xy 1.588 2.584)
        (xy 1.627 2.567)
        (xy 1.669 2.558)
        (xy 1.712 2.556)
        (xy 1.753 2.563)
      )

      (stroke (width 0.01) (type solid)) (fill solid) (layer "F.Cu"))
    (fp_poly
      (pts
        (xy 2.316 1.557)
        (xy 2.365 1.57)
        (xy 2.41 1.593)
        (xy 2.453 1.625)
        (xy 2.46 1.631)
        (xy 2.491 1.661)
        (xy 2.466 1.684)
        (xy 2.448 1.699)
        (xy 2.43 1.715)
        (xy 2.419 1.725)
        (xy 2.397 1.743)
        (xy 2.376 1.724)
        (xy 2.345 1.701)
        (xy 2.312 1.687)
        (xy 2.274 1.681)
        (xy 2.265 1.681)
        (xy 2.226 1.684)
        (xy 2.195 1.693)
        (xy 2.167 1.708)
        (xy 2.159 1.715)
        (xy 2.136 1.741)
        (xy 2.118 1.776)
        (xy 2.107 1.817)
        (xy 2.103 1.866)
        (xy 2.103 1.876)
        (xy 2.106 1.926)
        (xy 2.116 1.97)
        (xy 2.132 2.006)
        (xy 2.155 2.034)
        (xy 2.184 2.055)
        (xy 2.219 2.067)
        (xy 2.259 2.072)
        (xy 2.274 2.071)
        (xy 2.309 2.066)
        (xy 2.339 2.056)
        (xy 2.366 2.038)
        (xy 2.377 2.028)
        (xy 2.386 2.02)
        (xy 2.393 2.016)
        (xy 2.4 2.015)
        (xy 2.409 2.018)
        (xy 2.42 2.027)
        (xy 2.436 2.041)
        (xy 2.456 2.059)
        (xy 2.491 2.092)
        (xy 2.476 2.108)
        (xy 2.449 2.132)
        (xy 2.416 2.155)
        (xy 2.38 2.174)
        (xy 2.35 2.186)
        (xy 2.327 2.193)
        (xy 2.306 2.197)
        (xy 2.283 2.199)
        (xy 2.259 2.199)
        (xy 2.233 2.198)
        (xy 2.209 2.196)
        (xy 2.189 2.193)
        (xy 2.182 2.191)
        (xy 2.133 2.173)
        (xy 2.089 2.146)
        (xy 2.053 2.112)
        (xy 2.023 2.071)
        (xy 2.012 2.051)
        (xy 2 2.023)
        (xy 1.991 1.999)
        (xy 1.984 1.975)
        (xy 1.981 1.948)
        (xy 1.979 1.917)
        (xy 1.978 1.879)
        (xy 1.978 1.877)
        (xy 1.979 1.838)
        (xy 1.98 1.806)
        (xy 1.984 1.78)
        (xy 1.99 1.756)
        (xy 1.999 1.731)
        (xy 2.011 1.704)
        (xy 2.012 1.701)
        (xy 2.039 1.657)
        (xy 2.072 1.62)
        (xy 2.111 1.591)
        (xy 2.156 1.57)
        (xy 2.207 1.557)
        (xy 2.263 1.552)
        (xy 2.316 1.557)
      )

      (stroke (width 0.01) (type solid)) (fill solid) (layer "F.Cu"))
    (fp_poly
      (pts
        (xy -1.494 1.56)
        (xy -1.447 1.576)
        (xy -1.405 1.6)
        (xy -1.368 1.633)
        (xy -1.341 1.668)
        (xy -1.326 1.692)
        (xy -1.316 1.716)
        (xy -1.308 1.743)
        (xy -1.302 1.774)
        (xy -1.299 1.811)
        (xy -1.297 1.845)
        (xy -1.294 1.925)
        (xy -1.692 1.925)
        (xy -1.692 1.942)
        (xy -1.687 1.977)
        (xy -1.673 2.011)
        (xy -1.65 2.039)
        (xy -1.626 2.059)
        (xy -1.601 2.071)
        (xy -1.572 2.078)
        (xy -1.537 2.079)
        (xy -1.497 2.074)
        (xy -1.458 2.06)
        (xy -1.422 2.036)
        (xy -1.421 2.036)
        (xy -1.402 2.021)
        (xy -1.359 2.057)
        (xy -1.342 2.072)
        (xy -1.327 2.085)
        (xy -1.317 2.094)
        (xy -1.314 2.098)
        (xy -1.316 2.103)
        (xy -1.324 2.113)
        (xy -1.338 2.126)
        (xy -1.354 2.139)
        (xy -1.372 2.152)
        (xy -1.389 2.163)
        (xy -1.399 2.168)
        (xy -1.421 2.178)
        (xy -1.445 2.187)
        (xy -1.461 2.191)
        (xy -1.488 2.196)
        (xy -1.522 2.199)
        (xy -1.557 2.199)
        (xy -1.591 2.196)
        (xy -1.62 2.192)
        (xy -1.629 2.19)
        (xy -1.677 2.171)
        (xy -1.718 2.146)
        (xy -1.752 2.114)
        (xy -1.779 2.074)
        (xy -1.8 2.026)
        (xy -1.802 2.02)
        (xy -1.81 1.989)
        (xy -1.815 1.951)
        (xy -1.818 1.908)
        (xy -1.819 1.865)
        (xy -1.818 1.823)
        (xy -1.816 1.804)
        (xy -1.692 1.804)
        (xy -1.692 1.818)
        (xy -1.428 1.818)
        (xy -1.428 1.801)
        (xy -1.432 1.775)
        (xy -1.442 1.748)
        (xy -1.457 1.722)
        (xy -1.469 1.707)
        (xy -1.495 1.688)
        (xy -1.526 1.676)
        (xy -1.56 1.672)
        (xy -1.593 1.676)
        (xy -1.619 1.685)
        (xy -1.646 1.704)
        (xy -1.668 1.73)
        (xy -1.683 1.76)
        (xy -1.691 1.792)
        (xy -1.692 1.804)
        (xy -1.816 1.804)
        (xy -1.814 1.786)
        (xy -1.812 1.777)
        (xy -1.797 1.724)
        (xy -1.775 1.676)
        (xy -1.747 1.636)
        (xy -1.713 1.603)
        (xy -1.673 1.578)
        (xy -1.629 1.561)
        (xy -1.597 1.554)
        (xy -1.544 1.552)
        (xy -1.494 1.56)
      )

      (stroke (width 0.01) (type solid)) (fill solid) (layer "F.Cu"))
    (fp_poly
      (pts
        (xy 2.835 1.557)
        (xy 2.883 1.57)
        (xy 2.926 1.592)
        (xy 2.964 1.621)
        (xy 2.996 1.657)
        (xy 3.021 1.699)
        (xy 3.038 1.747)
        (xy 3.04 1.757)
        (xy 3.043 1.776)
        (xy 3.045 1.802)
        (xy 3.047 1.832)
        (xy 3.047 1.858)
        (xy 3.047 1.925)
        (xy 2.65 1.925)
        (xy 2.653 1.951)
        (xy 2.663 1.991)
        (xy 2.68 2.024)
        (xy 2.703 2.049)
        (xy 2.733 2.067)
        (xy 2.77 2.077)
        (xy 2.801 2.079)
        (xy 2.845 2.075)
        (xy 2.883 2.063)
        (xy 2.916 2.042)
        (xy 2.92 2.039)
        (xy 2.929 2.031)
        (xy 2.935 2.026)
        (xy 2.941 2.025)
        (xy 2.949 2.027)
        (xy 2.959 2.034)
        (xy 2.974 2.047)
        (xy 2.994 2.064)
        (xy 3.01 2.078)
        (xy 3.023 2.088)
        (xy 3.03 2.095)
        (xy 3.032 2.096)
        (xy 3.03 2.1)
        (xy 3.022 2.11)
        (xy 3.01 2.122)
        (xy 3.009 2.123)
        (xy 2.98 2.147)
        (xy 2.945 2.169)
        (xy 2.906 2.185)
        (xy 2.887 2.191)
        (xy 2.861 2.196)
        (xy 2.828 2.198)
        (xy 2.793 2.198)
        (xy 2.759 2.197)
        (xy 2.729 2.193)
        (xy 2.721 2.191)
        (xy 2.675 2.175)
        (xy 2.634 2.15)
        (xy 2.599 2.118)
        (xy 2.569 2.077)
        (xy 2.547 2.029)
        (xy 2.536 1.996)
        (xy 2.532 1.973)
        (xy 2.529 1.942)
        (xy 2.527 1.906)
        (xy 2.527 1.869)
        (xy 2.528 1.832)
        (xy 2.529 1.818)
        (xy 2.65 1.818)
        (xy 2.922 1.818)
        (xy 2.918 1.799)
        (xy 2.908 1.758)
        (xy 2.891 1.725)
        (xy 2.869 1.7)
        (xy 2.84 1.683)
        (xy 2.826 1.678)
        (xy 2.788 1.672)
        (xy 2.753 1.675)
        (xy 2.722 1.687)
        (xy 2.695 1.706)
        (xy 2.674 1.734)
        (xy 2.659 1.768)
        (xy 2.654 1.794)
        (xy 2.65 1.818)
        (xy 2.529 1.818)
        (xy 2.53 1.798)
        (xy 2.534 1.769)
        (xy 2.536 1.76)
        (xy 2.554 1.707)
        (xy 2.578 1.662)
        (xy 2.609 1.624)
        (xy 2.645 1.593)
        (xy 2.687 1.571)
        (xy 2.734 1.557)
        (xy 2.783 1.553)
        (xy 2.835 1.557)
      )

      (stroke (width 0.01) (type solid)) (fill solid) (layer "F.Cu"))
    (fp_poly
      (pts
        (xy -2.733 1.557)
        (xy -2.685 1.57)
        (xy -2.642 1.592)
        (xy -2.604 1.622)
        (xy -2.581 1.649)
        (xy -2.562 1.676)
        (xy -2.548 1.706)
        (xy -2.537 1.739)
        (xy -2.53 1.777)
        (xy -2.527 1.821)
        (xy -2.526 1.873)
        (xy -2.527 1.907)
        (xy -2.529 1.956)
        (xy -2.534 1.997)
        (xy -2.542 2.031)
        (xy -2.553 2.06)
        (xy -2.567 2.086)
        (xy -2.587 2.111)
        (xy -2.603 2.129)
        (xy -2.637 2.158)
        (xy -2.673 2.178)
        (xy -2.714 2.192)
        (xy -2.76 2.198)
        (xy -2.789 2.199)
        (xy -2.813 2.198)
        (xy -2.835 2.196)
        (xy -2.852 2.194)
        (xy -2.857 2.194)
        (xy -2.898 2.179)
        (xy -2.937 2.155)
        (xy -2.97 2.126)
        (xy -2.993 2.101)
        (xy -3.011 2.077)
        (xy -3.024 2.051)
        (xy -3.034 2.022)
        (xy -3.041 1.988)
        (xy -3.045 1.947)
        (xy -3.047 1.91)
        (xy -3.047 1.882)
        (xy -2.919 1.882)
        (xy -2.919 1.968)
        (xy -2.903 2.001)
        (xy -2.885 2.031)
        (xy -2.863 2.051)
        (xy -2.837 2.064)
        (xy -2.804 2.07)
        (xy -2.779 2.07)
        (xy -2.755 2.069)
        (xy -2.737 2.065)
        (xy -2.722 2.058)
        (xy -2.717 2.055)
        (xy -2.697 2.041)
        (xy -2.681 2.025)
        (xy -2.67 2.004)
        (xy -2.662 1.978)
        (xy -2.657 1.945)
        (xy -2.654 1.903)
        (xy -2.654 1.899)
        (xy -2.653 1.848)
        (xy -2.656 1.806)
        (xy -2.662 1.772)
        (xy -2.673 1.744)
        (xy -2.687 1.722)
        (xy -2.707 1.705)
        (xy -2.723 1.695)
        (xy -2.755 1.684)
        (xy -2.788 1.68)
        (xy -2.821 1.684)
        (xy -2.851 1.695)
        (xy -2.877 1.713)
        (xy -2.892 1.729)
        (xy -2.901 1.745)
        (xy -2.908 1.76)
        (xy -2.913 1.778)
        (xy -2.916 1.8)
        (xy -2.918 1.828)
        (xy -2.919 1.864)
        (xy -2.919 1.882)
        (xy -3.047 1.882)
        (xy -3.048 1.844)
        (xy -3.043 1.786)
        (xy -3.034 1.736)
        (xy -3.021 1.695)
        (xy -3.004 1.664)
        (xy -2.972 1.624)
        (xy -2.935 1.594)
        (xy -2.893 1.571)
        (xy -2.846 1.558)
        (xy -2.794 1.553)
        (xy -2.787 1.553)
        (xy -2.733 1.557)
      )

      (stroke (width 0.01) (type solid)) (fill solid) (layer "F.Cu"))
    (fp_poly
      (pts
        (xy 2.148 2.561)
        (xy 2.193 2.574)
        (xy 2.235 2.595)
        (xy 2.273 2.623)
        (xy 2.304 2.657)
        (xy 2.326 2.691)
        (xy 2.338 2.718)
        (xy 2.346 2.745)
        (xy 2.352 2.774)
        (xy 2.355 2.808)
        (xy 2.357 2.85)
        (xy 2.357 2.858)
        (xy 2.357 2.931)
        (xy 1.96 2.931)
        (xy 1.963 2.955)
        (xy 1.973 2.993)
        (xy 1.991 3.026)
        (xy 2.015 3.053)
        (xy 2.039 3.069)
        (xy 2.057 3.076)
        (xy 2.08 3.08)
        (xy 2.103 3.082)
        (xy 2.144 3.081)
        (xy 2.18 3.071)
        (xy 2.214 3.054)
        (xy 2.227 3.045)
        (xy 2.24 3.035)
        (xy 2.25 3.029)
        (xy 2.253 3.027)
        (xy 2.258 3.03)
        (xy 2.269 3.039)
        (xy 2.284 3.05)
        (xy 2.3 3.064)
        (xy 2.315 3.078)
        (xy 2.329 3.09)
        (xy 2.338 3.099)
        (xy 2.341 3.103)
        (xy 2.337 3.11)
        (xy 2.327 3.121)
        (xy 2.312 3.134)
        (xy 2.294 3.148)
        (xy 2.276 3.161)
        (xy 2.259 3.171)
        (xy 2.252 3.175)
        (xy 2.204 3.192)
        (xy 2.152 3.202)
        (xy 2.098 3.204)
        (xy 2.046 3.198)
        (xy 2.032 3.195)
        (xy 1.984 3.178)
        (xy 1.943 3.154)
        (xy 1.909 3.123)
        (xy 1.881 3.084)
        (xy 1.859 3.037)
        (xy 1.847 3.003)
        (xy 1.841 2.972)
        (xy 1.838 2.934)
        (xy 1.836 2.893)
        (xy 1.837 2.851)
        (xy 1.839 2.824)
        (xy 1.96 2.824)
        (xy 2.23 2.824)
        (xy 2.23 2.813)
        (xy 2.225 2.783)
        (xy 2.214 2.753)
        (xy 2.196 2.725)
        (xy 2.175 2.702)
        (xy 2.151 2.686)
        (xy 2.128 2.68)
        (xy 2.101 2.677)
        (xy 2.072 2.678)
        (xy 2.051 2.683)
        (xy 2.023 2.696)
        (xy 2 2.717)
        (xy 1.981 2.746)
        (xy 1.968 2.779)
        (xy 1.963 2.8)
        (xy 1.96 2.824)
        (xy 1.839 2.824)
        (xy 1.839 2.811)
        (xy 1.844 2.776)
        (xy 1.848 2.76)
        (xy 1.866 2.708)
        (xy 1.889 2.663)
        (xy 1.919 2.627)
        (xy 1.954 2.598)
        (xy 1.996 2.575)
        (xy 2.007 2.571)
        (xy 2.054 2.559)
        (xy 2.101 2.556)
        (xy 2.148 2.561)
      )

      (stroke (width 0.01) (type solid)) (fill solid) (layer "F.Cu"))
    (fp_poly
      (pts
        (xy -0.229 3.2)
        (xy -0.354 3.197)
        (xy -0.355 3.165)
        (xy -0.357 3.133)
        (xy -0.374 3.148)
        (xy -0.411 3.175)
        (xy -0.453 3.193)
        (xy -0.497 3.203)
        (xy -0.542 3.204)
        (xy -0.585 3.195)
        (xy -0.586 3.195)
        (xy -0.621 3.181)
        (xy -0.651 3.16)
        (xy -0.673 3.141)
        (xy -0.689 3.123)
        (xy -0.702 3.106)
        (xy -0.712 3.086)
        (xy -0.72 3.064)
        (xy -0.726 3.038)
        (xy -0.73 3.007)
        (xy -0.732 2.968)
        (xy -0.733 2.922)
        (xy -0.733 2.88)
        (xy -0.602 2.88)
        (xy -0.602 2.915)
        (xy -0.602 2.942)
        (xy -0.601 2.962)
        (xy -0.6 2.977)
        (xy -0.598 2.988)
        (xy -0.596 2.998)
        (xy -0.592 3.007)
        (xy -0.591 3.01)
        (xy -0.574 3.039)
        (xy -0.552 3.059)
        (xy -0.525 3.071)
        (xy -0.492 3.076)
        (xy -0.472 3.076)
        (xy -0.442 3.072)
        (xy -0.418 3.063)
        (xy -0.398 3.048)
        (xy -0.382 3.029)
        (xy -0.371 3.004)
        (xy -0.363 2.972)
        (xy -0.358 2.933)
        (xy -0.356 2.885)
        (xy -0.356 2.88)
        (xy -0.358 2.828)
        (xy -0.363 2.785)
        (xy -0.373 2.75)
        (xy -0.387 2.724)
        (xy -0.406 2.704)
        (xy -0.43 2.692)
        (xy -0.46 2.686)
        (xy -0.483 2.685)
        (xy -0.517 2.687)
        (xy -0.544 2.696)
        (xy -0.565 2.711)
        (xy -0.583 2.734)
        (xy -0.591 2.751)
        (xy -0.595 2.76)
        (xy -0.598 2.769)
        (xy -0.6 2.779)
        (xy -0.601 2.793)
        (xy -0.602 2.811)
        (xy -0.602 2.836)
        (xy -0.602 2.869)
        (xy -0.602 2.88)
        (xy -0.733 2.88)
        (xy -0.733 2.827)
        (xy -0.732 2.783)
        (xy -0.729 2.746)
        (xy -0.725 2.716)
        (xy -0.719 2.691)
        (xy -0.71 2.67)
        (xy -0.699 2.651)
        (xy -0.685 2.633)
        (xy -0.668 2.616)
        (xy -0.668 2.615)
        (xy -0.632 2.587)
        (xy -0.592 2.567)
        (xy -0.55 2.557)
        (xy -0.506 2.556)
        (xy -0.463 2.564)
        (xy -0.421 2.582)
        (xy -0.411 2.587)
        (xy -0.394 2.598)
        (xy -0.377 2.61)
        (xy -0.373 2.614)
        (xy -0.356 2.627)
        (xy -0.356 2.306)
        (xy -0.229 2.306)
        (xy -0.229 3.2)
      )

      (stroke (width 0.01) (type solid)) (fill solid) (layer "F.Cu"))
    (fp_poly
      (pts
        (xy 0.605 1.558)
        (xy 0.651 1.574)
        (xy 0.694 1.598)
        (xy 0.728 1.627)
        (xy 0.75 1.652)
        (xy 0.768 1.678)
        (xy 0.781 1.707)
        (xy 0.791 1.739)
        (xy 0.797 1.777)
        (xy 0.801 1.822)
        (xy 0.802 1.876)
        (xy 0.802 1.877)
        (xy 0.801 1.929)
        (xy 0.798 1.973)
        (xy 0.792 2.009)
        (xy 0.784 2.04)
        (xy 0.774 2.062)
        (xy 0.748 2.103)
        (xy 0.715 2.139)
        (xy 0.675 2.167)
        (xy 0.632 2.187)
        (xy 0.626 2.189)
        (xy 0.599 2.195)
        (xy 0.567 2.198)
        (xy 0.532 2.199)
        (xy 0.499 2.197)
        (xy 0.471 2.193)
        (xy 0.466 2.192)
        (xy 0.428 2.177)
        (xy 0.391 2.155)
        (xy 0.359 2.129)
        (xy 0.354 2.123)
        (xy 0.332 2.098)
        (xy 0.316 2.073)
        (xy 0.303 2.047)
        (xy 0.294 2.017)
        (xy 0.287 1.983)
        (xy 0.284 1.943)
        (xy 0.282 1.894)
        (xy 0.282 1.877)
        (xy 0.409 1.877)
        (xy 0.41 1.918)
        (xy 0.412 1.95)
        (xy 0.416 1.976)
        (xy 0.423 1.997)
        (xy 0.432 2.015)
        (xy 0.445 2.03)
        (xy 0.451 2.037)
        (xy 0.471 2.054)
        (xy 0.491 2.064)
        (xy 0.514 2.07)
        (xy 0.543 2.072)
        (xy 0.569 2.07)
        (xy 0.59 2.065)
        (xy 0.601 2.06)
        (xy 0.625 2.047)
        (xy 0.642 2.031)
        (xy 0.656 2.009)
        (xy 0.661 1.998)
        (xy 0.665 1.989)
        (xy 0.668 1.98)
        (xy 0.67 1.969)
        (xy 0.671 1.954)
        (xy 0.672 1.935)
        (xy 0.673 1.909)
        (xy 0.673 1.877)
        (xy 0.673 1.842)
        (xy 0.672 1.817)
        (xy 0.671 1.798)
        (xy 0.67 1.784)
        (xy 0.668 1.773)
        (xy 0.665 1.764)
        (xy 0.661 1.755)
        (xy 0.647 1.73)
        (xy 0.632 1.712)
        (xy 0.612 1.698)
        (xy 0.601 1.693)
        (xy 0.569 1.683)
        (xy 0.535 1.681)
        (xy 0.501 1.686)
        (xy 0.471 1.7)
        (xy 0.447 1.719)
        (xy 0.434 1.736)
        (xy 0.424 1.753)
        (xy 0.417 1.774)
        (xy 0.412 1.8)
        (xy 0.41 1.833)
        (xy 0.409 1.873)
        (xy 0.409 1.877)
        (xy 0.282 1.877)
        (xy 0.283 1.824)
        (xy 0.286 1.78)
        (xy 0.292 1.742)
        (xy 0.301 1.711)
        (xy 0.313 1.683)
        (xy 0.33 1.657)
        (xy 0.35 1.633)
        (xy 0.351 1.632)
        (xy 0.385 1.601)
        (xy 0.42 1.578)
        (xy 0.46 1.563)
        (xy 0.505 1.554)
        (xy 0.555 1.551)
        (xy 0.605 1.558)
      )

      (stroke (width 0.01) (type solid)) (fill solid) (layer "F.Cu"))
    (fp_poly
      (pts
        (xy 0.004 1.556)
        (xy 0.054 1.566)
        (xy 0.102 1.582)
        (xy 0.146 1.605)
        (xy 0.154 1.61)
        (xy 0.193 1.636)
        (xy 0.178 1.655)
        (xy 0.166 1.668)
        (xy 0.152 1.686)
        (xy 0.138 1.7)
        (xy 0.114 1.727)
        (xy 0.07 1.705)
        (xy 0.032 1.688)
        (xy -0.007 1.677)
        (xy -0.044 1.672)
        (xy -0.079 1.672)
        (xy -0.11 1.678)
        (xy -0.136 1.69)
        (xy -0.154 1.707)
        (xy -0.162 1.724)
        (xy -0.164 1.745)
        (xy -0.164 1.761)
        (xy -0.159 1.772)
        (xy -0.15 1.782)
        (xy -0.149 1.783)
        (xy -0.139 1.791)
        (xy -0.128 1.797)
        (xy -0.114 1.802)
        (xy -0.095 1.805)
        (xy -0.07 1.808)
        (xy -0.037 1.811)
        (xy -0.02 1.813)
        (xy 0.027 1.817)
        (xy 0.065 1.823)
        (xy 0.096 1.832)
        (xy 0.122 1.842)
        (xy 0.14 1.854)
        (xy 0.166 1.879)
        (xy 0.186 1.91)
        (xy 0.2 1.947)
        (xy 0.206 1.987)
        (xy 0.206 2.018)
        (xy 0.198 2.06)
        (xy 0.181 2.097)
        (xy 0.155 2.129)
        (xy 0.122 2.156)
        (xy 0.08 2.177)
        (xy 0.042 2.189)
        (xy 0.005 2.196)
        (xy -0.038 2.199)
        (xy -0.083 2.198)
        (xy -0.125 2.194)
        (xy -0.153 2.189)
        (xy -0.177 2.181)
        (xy -0.204 2.171)
        (xy -0.229 2.16)
        (xy -0.232 2.159)
        (xy -0.251 2.148)
        (xy -0.272 2.136)
        (xy -0.292 2.122)
        (xy -0.309 2.109)
        (xy -0.323 2.098)
        (xy -0.33 2.09)
        (xy -0.331 2.088)
        (xy -0.327 2.084)
        (xy -0.318 2.073)
        (xy -0.304 2.059)
        (xy -0.288 2.043)
        (xy -0.246 2)
        (xy -0.221 2.021)
        (xy -0.184 2.047)
        (xy -0.145 2.065)
        (xy -0.102 2.075)
        (xy -0.053 2.079)
        (xy -0.049 2.079)
        (xy -0.023 2.079)
        (xy -0.004 2.078)
        (xy 0.011 2.074)
        (xy 0.025 2.069)
        (xy 0.029 2.068)
        (xy 0.054 2.052)
        (xy 0.071 2.033)
        (xy 0.079 2.01)
        (xy 0.078 1.986)
        (xy 0.074 1.975)
        (xy 0.068 1.964)
        (xy 0.06 1.956)
        (xy 0.048 1.949)
        (xy 0.031 1.944)
        (xy 0.007 1.939)
        (xy -0.024 1.935)
        (xy -0.052 1.932)
        (xy -0.089 1.929)
        (xy -0.119 1.925)
        (xy -0.142 1.921)
        (xy -0.16 1.917)
        (xy -0.176 1.912)
        (xy -0.192 1.906)
        (xy -0.201 1.901)
        (xy -0.235 1.879)
        (xy -0.262 1.85)
        (xy -0.28 1.816)
        (xy -0.29 1.776)
        (xy -0.292 1.75)
        (xy -0.291 1.727)
        (xy -0.289 1.705)
        (xy -0.286 1.689)
        (xy -0.286 1.688)
        (xy -0.273 1.659)
        (xy -0.253 1.63)
        (xy -0.229 1.604)
        (xy -0.221 1.599)
        (xy -0.185 1.577)
        (xy -0.143 1.562)
        (xy -0.096 1.554)
        (xy -0.047 1.552)
        (xy 0.004 1.556)
      )

      (stroke (width 0.01) (type solid)) (fill solid) (layer "F.Cu"))
    (fp_poly
      (pts
        (xy 1.038 2.556)
        (xy 1.091 2.563)
        (xy 1.137 2.576)
        (xy 1.177 2.595)
        (xy 1.209 2.62)
        (xy 1.234 2.65)
        (xy 1.242 2.665)
        (xy 1.247 2.677)
        (xy 1.251 2.691)
        (xy 1.255 2.708)
        (xy 1.258 2.727)
        (xy 1.26 2.751)
        (xy 1.262 2.78)
        (xy 1.263 2.815)
        (xy 1.263 2.858)
        (xy 1.264 2.908)
        (xy 1.263 2.967)
        (xy 1.263 2.989)
        (xy 1.262 3.197)
        (xy 1.135 3.197)
        (xy 1.133 3.171)
        (xy 1.132 3.144)
        (xy 1.119 3.159)
        (xy 1.096 3.179)
        (xy 1.065 3.193)
        (xy 1.026 3.202)
        (xy 0.98 3.204)
        (xy 0.976 3.204)
        (xy 0.955 3.204)
        (xy 0.937 3.203)
        (xy 0.925 3.202)
        (xy 0.924 3.201)
        (xy 0.879 3.189)
        (xy 0.839 3.17)
        (xy 0.806 3.144)
        (xy 0.781 3.113)
        (xy 0.763 3.077)
        (xy 0.753 3.037)
        (xy 0.753 3.005)
        (xy 0.873 3.005)
        (xy 0.874 3.023)
        (xy 0.878 3.035)
        (xy 0.887 3.047)
        (xy 0.89 3.05)
        (xy 0.903 3.063)
        (xy 0.917 3.072)
        (xy 0.935 3.078)
        (xy 0.957 3.081)
        (xy 0.986 3.082)
        (xy 1.013 3.082)
        (xy 1.043 3.081)
        (xy 1.065 3.079)
        (xy 1.08 3.077)
        (xy 1.091 3.073)
        (xy 1.096 3.071)
        (xy 1.112 3.058)
        (xy 1.123 3.039)
        (xy 1.13 3.012)
        (xy 1.132 2.977)
        (xy 1.132 2.975)
        (xy 1.132 2.931)
        (xy 1.035 2.931)
        (xy 0.999 2.931)
        (xy 0.973 2.931)
        (xy 0.953 2.932)
        (xy 0.939 2.934)
        (xy 0.928 2.936)
        (xy 0.919 2.939)
        (xy 0.916 2.94)
        (xy 0.893 2.954)
        (xy 0.88 2.971)
        (xy 0.874 2.994)
        (xy 0.873 3.005)
        (xy 0.753 3.005)
        (xy 0.753 2.994)
        (xy 0.761 2.951)
        (xy 0.768 2.931)
        (xy 0.776 2.915)
        (xy 0.786 2.901)
        (xy 0.802 2.884)
        (xy 0.804 2.882)
        (xy 0.82 2.867)
        (xy 0.835 2.854)
        (xy 0.85 2.845)
        (xy 0.867 2.838)
        (xy 0.887 2.833)
        (xy 0.912 2.829)
        (xy 0.943 2.827)
        (xy 0.982 2.826)
        (xy 1.015 2.825)
        (xy 1.133 2.823)
        (xy 1.132 2.771)
        (xy 1.131 2.746)
        (xy 1.129 2.73)
        (xy 1.127 2.719)
        (xy 1.123 2.711)
        (xy 1.117 2.705)
        (xy 1.098 2.691)
        (xy 1.07 2.682)
        (xy 1.032 2.677)
        (xy 1.006 2.677)
        (xy 0.972 2.678)
        (xy 0.945 2.682)
        (xy 0.924 2.688)
        (xy 0.907 2.699)
        (xy 0.9 2.706)
        (xy 0.882 2.723)
        (xy 0.834 2.686)
        (xy 0.816 2.672)
        (xy 0.801 2.66)
        (xy 0.79 2.652)
        (xy 0.787 2.648)
        (xy 0.791 2.639)
        (xy 0.801 2.626)
        (xy 0.816 2.612)
        (xy 0.832 2.6)
        (xy 0.864 2.581)
        (xy 0.902 2.568)
        (xy 0.946 2.559)
        (xy 0.98 2.556)
        (xy 1.038 2.556)
      )

      (stroke (width 0.01) (type solid)) (fill solid) (layer "F.Cu"))
    (fp_poly
      (pts
        (xy -1.521 2.559)
        (xy -1.485 2.562)
        (xy -1.454 2.568)
        (xy -1.427 2.577)
        (xy -1.401 2.589)
        (xy -1.371 2.61)
        (xy -1.345 2.639)
        (xy -1.325 2.67)
        (xy -1.321 2.679)
        (xy -1.309 2.71)
        (xy -1.309 3.197)
        (xy -1.433 3.2)
        (xy -1.433 3.172)
        (xy -1.434 3.157)
        (xy -1.435 3.147)
        (xy -1.436 3.144)
        (xy -1.44 3.147)
        (xy -1.449 3.156)
        (xy -1.453 3.161)
        (xy -1.472 3.178)
        (xy -1.496 3.19)
        (xy -1.526 3.198)
        (xy -1.563 3.202)
        (xy -1.578 3.203)
        (xy -1.603 3.203)
        (xy -1.627 3.203)
        (xy -1.647 3.201)
        (xy -1.656 3.2)
        (xy -1.686 3.191)
        (xy -1.717 3.176)
        (xy -1.746 3.159)
        (xy -1.765 3.143)
        (xy -1.79 3.111)
        (xy -1.807 3.075)
        (xy -1.816 3.037)
        (xy -1.817 2.998)
        (xy -1.817 2.997)
        (xy -1.697 2.997)
        (xy -1.696 3.02)
        (xy -1.687 3.042)
        (xy -1.67 3.06)
        (xy -1.668 3.062)
        (xy -1.654 3.07)
        (xy -1.64 3.076)
        (xy -1.624 3.08)
        (xy -1.602 3.081)
        (xy -1.574 3.082)
        (xy -1.558 3.082)
        (xy -1.529 3.081)
        (xy -1.508 3.08)
        (xy -1.494 3.078)
        (xy -1.483 3.075)
        (xy -1.474 3.07)
        (xy -1.458 3.058)
        (xy -1.447 3.041)
        (xy -1.44 3.017)
        (xy -1.435 2.985)
        (xy -1.435 2.977)
        (xy -1.432 2.931)
        (xy -1.533 2.931)
        (xy -1.568 2.931)
        (xy -1.595 2.931)
        (xy -1.615 2.932)
        (xy -1.63 2.934)
        (xy -1.641 2.936)
        (xy -1.65 2.938)
        (xy -1.655 2.941)
        (xy -1.676 2.955)
        (xy -1.69 2.974)
        (xy -1.697 2.997)
        (xy -1.817 2.997)
        (xy -1.811 2.96)
        (xy -1.797 2.924)
        (xy -1.775 2.892)
        (xy -1.747 2.864)
        (xy -1.715 2.845)
        (xy -1.7 2.838)
        (xy -1.685 2.833)
        (xy -1.668 2.83)
        (xy -1.648 2.827)
        (xy -1.623 2.825)
        (xy -1.591 2.824)
        (xy -1.551 2.824)
        (xy -1.54 2.824)
        (xy -1.432 2.824)
        (xy -1.434 2.776)
        (xy -1.436 2.747)
        (xy -1.441 2.726)
        (xy -1.448 2.711)
        (xy -1.46 2.699)
        (xy -1.474 2.689)
        (xy -1.483 2.685)
        (xy -1.492 2.682)
        (xy -1.505 2.68)
        (xy -1.524 2.68)
        (xy -1.55 2.679)
        (xy -1.56 2.679)
        (xy -1.594 2.68)
        (xy -1.62 2.682)
        (xy -1.639 2.686)
        (xy -1.654 2.692)
        (xy -1.666 2.701)
        (xy -1.675 2.711)
        (xy -1.686 2.724)
        (xy -1.735 2.686)
        (xy -1.754 2.672)
        (xy -1.769 2.659)
        (xy -1.78 2.65)
        (xy -1.784 2.646)
        (xy -1.78 2.64)
        (xy -1.77 2.629)
        (xy -1.756 2.616)
        (xy -1.74 2.604)
        (xy -1.724 2.592)
        (xy -1.711 2.584)
        (xy -1.71 2.583)
        (xy -1.688 2.574)
        (xy -1.668 2.566)
        (xy -1.647 2.562)
        (xy -1.623 2.559)
        (xy -1.593 2.558)
        (xy -1.565 2.558)
        (xy -1.521 2.559)
      )

      (stroke (width 0.01) (type solid)) (fill solid) (layer "F.Cu"))
    (fp_poly
      (pts
        (xy 0.035 2.777)
        (xy 0.047 2.822)
        (xy 0.059 2.864)
        (xy 0.069 2.903)
        (xy 0.078 2.936)
        (xy 0.086 2.963)
        (xy 0.092 2.984)
        (xy 0.095 2.996)
        (xy 0.096 2.999)
        (xy 0.098 2.999)
        (xy 0.103 2.991)
        (xy 0.109 2.975)
        (xy 0.118 2.95)
        (xy 0.129 2.917)
        (xy 0.143 2.874)
        (xy 0.152 2.849)
        (xy 0.165 2.807)
        (xy 0.179 2.766)
        (xy 0.192 2.726)
        (xy 0.204 2.689)
        (xy 0.214 2.658)
        (xy 0.221 2.634)
        (xy 0.224 2.627)
        (xy 0.244 2.565)
        (xy 0.338 2.565)
        (xy 0.406 2.774)
        (xy 0.42 2.819)
        (xy 0.434 2.861)
        (xy 0.446 2.899)
        (xy 0.457 2.932)
        (xy 0.466 2.96)
        (xy 0.473 2.981)
        (xy 0.477 2.993)
        (xy 0.478 2.997)
        (xy 0.48 2.998)
        (xy 0.482 2.996)
        (xy 0.485 2.99)
        (xy 0.49 2.978)
        (xy 0.495 2.96)
        (xy 0.502 2.936)
        (xy 0.511 2.905)
        (xy 0.523 2.865)
        (xy 0.536 2.817)
        (xy 0.543 2.789)
        (xy 0.556 2.744)
        (xy 0.568 2.701)
        (xy 0.578 2.663)
        (xy 0.587 2.629)
        (xy 0.595 2.602)
        (xy 0.601 2.582)
        (xy 0.605 2.57)
        (xy 0.606 2.567)
        (xy 0.611 2.566)
        (xy 0.625 2.566)
        (xy 0.645 2.566)
        (xy 0.669 2.566)
        (xy 0.673 2.566)
        (xy 0.739 2.567)
        (xy 0.656 2.827)
        (xy 0.64 2.878)
        (xy 0.624 2.928)
        (xy 0.609 2.976)
        (xy 0.595 3.02)
        (xy 0.582 3.06)
        (xy 0.571 3.094)
        (xy 0.563 3.121)
        (xy 0.557 3.139)
        (xy 0.556 3.143)
        (xy 0.538 3.2)
        (xy 0.425 3.197)
        (xy 0.358 2.975)
        (xy 0.341 2.917)
        (xy 0.327 2.87)
        (xy 0.315 2.831)
        (xy 0.305 2.801)
        (xy 0.297 2.78)
        (xy 0.292 2.766)
        (xy 0.289 2.761)
        (xy 0.288 2.761)
        (xy 0.286 2.768)
        (xy 0.281 2.783)
        (xy 0.274 2.806)
        (xy 0.265 2.836)
        (xy 0.254 2.871)
        (xy 0.242 2.911)
        (xy 0.23 2.953)
        (xy 0.223 2.976)
        (xy 0.21 3.02)
        (xy 0.197 3.062)
        (xy 0.186 3.099)
        (xy 0.177 3.132)
        (xy 0.169 3.158)
        (xy 0.163 3.177)
        (xy 0.16 3.189)
        (xy 0.159 3.191)
        (xy 0.157 3.195)
        (xy 0.151 3.198)
        (xy 0.141 3.199)
        (xy 0.124 3.2)
        (xy 0.101 3.2)
        (xy 0.073 3.199)
        (xy 0.055 3.198)
        (xy 0.045 3.196)
        (xy 0.043 3.194)
        (xy 0.041 3.188)
        (xy 0.036 3.173)
        (xy 0.029 3.15)
        (xy 0.019 3.121)
        (xy 0.008 3.084)
        (xy -0.006 3.043)
        (xy -0.02 2.996)
        (xy -0.036 2.946)
        (xy -0.053 2.893)
        (xy -0.057 2.883)
        (xy -0.074 2.83)
        (xy -0.09 2.779)
        (xy -0.105 2.732)
        (xy -0.119 2.689)
        (xy -0.131 2.652)
        (xy -0.141 2.621)
        (xy -0.148 2.596)
        (xy -0.154 2.58)
        (xy -0.156 2.572)
        (xy -0.156 2.569)
        (xy -0.151 2.567)
        (xy -0.14 2.566)
        (xy -0.123 2.565)
        (xy -0.096 2.565)
        (xy -0.091 2.565)
        (xy -0.023 2.565)
        (xy 0.035 2.777)
      )

      (stroke (width 0.01) (type solid)) (fill solid) (layer "F.Cu"))
    (fp_poly
      (pts
        (xy -2.065 1.559)
        (xy -2.024 1.576)
        (xy -1.986 1.601)
        (xy -1.973 1.612)
        (xy -1.957 1.63)
        (xy -1.943 1.649)
        (xy -1.932 1.668)
        (xy -1.924 1.69)
        (xy -1.918 1.716)
        (xy -1.914 1.747)
        (xy -1.911 1.785)
        (xy -1.91 1.831)
        (xy -1.91 1.877)
        (xy -1.91 1.93)
        (xy -1.912 1.974)
        (xy -1.914 2.011)
        (xy -1.919 2.041)
        (xy -1.925 2.067)
        (xy -1.934 2.088)
        (xy -1.945 2.107)
        (xy -1.959 2.125)
        (xy -1.972 2.139)
        (xy -1.993 2.157)
        (xy -2.018 2.173)
        (xy -2.031 2.18)
        (xy -2.047 2.188)
        (xy -2.06 2.192)
        (xy -2.074 2.195)
        (xy -2.091 2.196)
        (xy -2.114 2.197)
        (xy -2.122 2.197)
        (xy -2.147 2.196)
        (xy -2.165 2.195)
        (xy -2.179 2.193)
        (xy -2.191 2.189)
        (xy -2.205 2.183)
        (xy -2.21 2.18)
        (xy -2.231 2.169)
        (xy -2.251 2.156)
        (xy -2.265 2.146)
        (xy -2.286 2.127)
        (xy -2.286 2.627)
        (xy -2.266 2.608)
        (xy -2.248 2.595)
        (xy -2.227 2.582)
        (xy -2.217 2.577)
        (xy -2.173 2.562)
        (xy -2.129 2.556)
        (xy -2.086 2.559)
        (xy -2.045 2.57)
        (xy -2.007 2.589)
        (xy -1.974 2.616)
        (xy -1.946 2.648)
        (xy -1.926 2.687)
        (xy -1.919 2.707)
        (xy -1.917 2.715)
        (xy -1.915 2.724)
        (xy -1.914 2.737)
        (xy -1.913 2.753)
        (xy -1.912 2.774)
        (xy -1.911 2.8)
        (xy -1.911 2.833)
        (xy -1.911 2.874)
        (xy -1.911 2.923)
        (xy -1.911 2.967)
        (xy -1.911 3.2)
        (xy -2.035 3.197)
        (xy -2.038 2.984)
        (xy -2.038 2.932)
        (xy -2.039 2.889)
        (xy -2.039 2.854)
        (xy -2.04 2.826)
        (xy -2.041 2.805)
        (xy -2.042 2.788)
        (xy -2.043 2.776)
        (xy -2.045 2.767)
        (xy -2.046 2.76)
        (xy -2.049 2.755)
        (xy -2.051 2.75)
        (xy -2.072 2.721)
        (xy -2.098 2.701)
        (xy -2.128 2.688)
        (xy -2.161 2.683)
        (xy -2.195 2.687)
        (xy -2.22 2.697)
        (xy -2.24 2.71)
        (xy -2.259 2.729)
        (xy -2.274 2.75)
        (xy -2.278 2.757)
        (xy -2.28 2.765)
        (xy -2.281 2.781)
        (xy -2.283 2.806)
        (xy -2.284 2.839)
        (xy -2.285 2.881)
        (xy -2.286 2.933)
        (xy -2.286 2.984)
        (xy -2.289 3.197)
        (xy -2.413 3.2)
        (xy -2.413 1.877)
        (xy -2.286 1.877)
        (xy -2.285 1.926)
        (xy -2.281 1.966)
        (xy -2.274 1.998)
        (xy -2.262 2.024)
        (xy -2.247 2.043)
        (xy -2.228 2.058)
        (xy -2.215 2.064)
        (xy -2.194 2.07)
        (xy -2.168 2.072)
        (xy -2.141 2.071)
        (xy -2.117 2.066)
        (xy -2.106 2.063)
        (xy -2.079 2.044)
        (xy -2.058 2.019)
        (xy -2.05 2.001)
        (xy -2.045 1.984)
        (xy -2.042 1.959)
        (xy -2.04 1.929)
        (xy -2.038 1.895)
        (xy -2.038 1.861)
        (xy -2.039 1.829)
        (xy -2.041 1.8)
        (xy -2.044 1.777)
        (xy -2.045 1.772)
        (xy -2.057 1.738)
        (xy -2.073 1.712)
        (xy -2.094 1.695)
        (xy -2.122 1.684)
        (xy -2.156 1.681)
        (xy -2.159 1.681)
        (xy -2.192 1.683)
        (xy -2.22 1.691)
        (xy -2.243 1.705)
        (xy -2.26 1.725)
        (xy -2.273 1.753)
        (xy -2.281 1.788)
        (xy -2.285 1.832)
        (xy -2.286 1.877)
        (xy -2.413 1.877)
        (xy -2.413 1.559)
        (xy -2.286 1.559)
        (xy -2.286 1.62)
        (xy -2.26 1.6)
        (xy -2.225 1.577)
        (xy -2.19 1.563)
        (xy -2.154 1.554)
        (xy -2.109 1.552)
        (xy -2.065 1.559)
      )

      (stroke (width 0.01) (type solid)) (fill solid) (layer "F.Cu"))
    (fp_poly
      (pts
        (xy 0.063 -3.201)
        (xy 0.118 -3.201)
        (xy 0.164 -3.201)
        (xy 0.202 -3.2)
        (xy 0.233 -3.2)
        (xy 0.258 -3.2)
        (xy 0.277 -3.199)
        (xy 0.292 -3.198)
        (xy 0.302 -3.197)
        (xy 0.309 -3.196)
        (xy 0.314 -3.195)
        (xy 0.317 -3.193)
        (xy 0.319 -3.192)
        (xy 0.321 -3.189)
        (xy 0.324 -3.183)
        (xy 0.327 -3.174)
        (xy 0.33 -3.161)
        (xy 0.334 -3.144)
        (xy 0.339 -3.12)
        (xy 0.345 -3.091)
        (xy 0.352 -3.054)
        (xy 0.361 -3.01)
        (xy 0.371 -2.958)
        (xy 0.382 -2.897)
        (xy 0.385 -2.878)
        (xy 0.395 -2.824)
        (xy 0.405 -2.772)
        (xy 0.414 -2.724)
        (xy 0.423 -2.68)
        (xy 0.43 -2.642)
        (xy 0.437 -2.61)
        (xy 0.442 -2.586)
        (xy 0.446 -2.569)
        (xy 0.448 -2.562)
        (xy 0.456 -2.55)
        (xy 0.464 -2.544)
        (xy 0.476 -2.539)
        (xy 0.495 -2.53)
        (xy 0.521 -2.519)
        (xy 0.552 -2.506)
        (xy 0.587 -2.492)
        (xy 0.624 -2.477)
        (xy 0.664 -2.461)
        (xy 0.704 -2.445)
        (xy 0.743 -2.43)
        (xy 0.78 -2.415)
        (xy 0.814 -2.402)
        (xy 0.843 -2.391)
        (xy 0.868 -2.382)
        (xy 0.885 -2.376)
        (xy 0.895 -2.373)
        (xy 0.896 -2.373)
        (xy 0.911 -2.376)
        (xy 0.931 -2.386)
        (xy 0.948 -2.397)
        (xy 0.962 -2.406)
        (xy 0.983 -2.421)
        (xy 1.011 -2.44)
        (xy 1.043 -2.462)
        (xy 1.079 -2.487)
        (xy 1.118 -2.513)
        (xy 1.158 -2.541)
        (xy 1.198 -2.568)
        (xy 1.238 -2.595)
        (xy 1.275 -2.621)
        (xy 1.309 -2.644)
        (xy 1.338 -2.665)
        (xy 1.362 -2.681)
        (xy 1.377 -2.691)
        (xy 1.398 -2.705)
        (xy 1.418 -2.717)
        (xy 1.433 -2.725)
        (xy 1.442 -2.728)
        (xy 1.443 -2.728)
        (xy 1.448 -2.726)
        (xy 1.456 -2.72)
        (xy 1.468 -2.71)
        (xy 1.486 -2.694)
        (xy 1.508 -2.673)
        (xy 1.535 -2.647)
        (xy 1.568 -2.614)
        (xy 1.608 -2.575)
        (xy 1.654 -2.53)
        (xy 1.675 -2.509)
        (xy 1.721 -2.462)
        (xy 1.761 -2.422)
        (xy 1.794 -2.388)
        (xy 1.822 -2.36)
        (xy 1.844 -2.337)
        (xy 1.862 -2.318)
        (xy 1.875 -2.304)
        (xy 1.884 -2.293)
        (xy 1.89 -2.284)
        (xy 1.893 -2.279)
        (xy 1.894 -2.275)
        (xy 1.892 -2.269)
        (xy 1.886 -2.257)
        (xy 1.875 -2.239)
        (xy 1.86 -2.215)
        (xy 1.839 -2.183)
        (xy 1.814 -2.145)
        (xy 1.783 -2.1)
        (xy 1.747 -2.046)
        (xy 1.721 -2.009)
        (xy 1.69 -1.964)
        (xy 1.661 -1.921)
        (xy 1.634 -1.88)
        (xy 1.609 -1.844)
        (xy 1.588 -1.811)
        (xy 1.57 -1.785)
        (xy 1.557 -1.764)
        (xy 1.549 -1.75)
        (xy 1.546 -1.743)
        (xy 1.547 -1.735)
        (xy 1.552 -1.719)
        (xy 1.56 -1.696)
        (xy 1.571 -1.667)
        (xy 1.585 -1.634)
        (xy 1.6 -1.597)
        (xy 1.616 -1.557)
        (xy 1.633 -1.516)
        (xy 1.651 -1.476)
        (xy 1.668 -1.436)
        (xy 1.685 -1.398)
        (xy 1.701 -1.363)
        (xy 1.715 -1.333)
        (xy 1.727 -1.309)
        (xy 1.736 -1.291)
        (xy 1.742 -1.281)
        (xy 1.744 -1.279)
        (xy 1.751 -1.277)
        (xy 1.767 -1.273)
        (xy 1.791 -1.268)
        (xy 1.822 -1.261)
        (xy 1.86 -1.254)
        (xy 1.903 -1.245)
        (xy 1.951 -1.236)
        (xy 2.002 -1.226)
        (xy 2.049 -1.217)
        (xy 2.103 -1.207)
        (xy 2.154 -1.198)
        (xy 2.201 -1.188)
        (xy 2.244 -1.18)
        (xy 2.281 -1.173)
        (xy 2.311 -1.166)
        (xy 2.335 -1.161)
        (xy 2.35 -1.157)
        (xy 2.355 -1.156)
        (xy 2.367 -1.148)
        (xy 2.367 -0.834)
        (xy 2.367 -0.768)
        (xy 2.367 -0.712)
        (xy 2.367 -0.664)
        (xy 2.366 -0.625)
        (xy 2.366 -0.592)
        (xy 2.365 -0.566)
        (xy 2.364 -0.546)
        (xy 2.363 -0.531)
        (xy 2.361 -0.52)
        (xy 2.358 -0.512)
        (xy 2.355 -0.507)
        (xy 2.352 -0.504)
        (xy 2.348 -0.503)
        (xy 2.343 -0.501)
        (xy 2.34 -0.501)
        (xy 2.333 -0.499)
        (xy 2.317 -0.496)
        (xy 2.293 -0.492)
        (xy 2.261 -0.486)
        (xy 2.224 -0.479)
        (xy 2.181 -0.471)
        (xy 2.134 -0.462)
        (xy 2.084 -0.453)
        (xy 2.054 -0.448)
        (xy 2.002 -0.438)
        (xy 1.953 -0.429)
        (xy 1.907 -0.42)
        (xy 1.866 -0.412)
        (xy 1.831 -0.404)
        (xy 1.802 -0.398)
        (xy 1.78 -0.394)
        (xy 1.767 -0.391)
        (xy 1.764 -0.39)
        (xy 1.76 -0.387)
        (xy 1.757 -0.384)
        (xy 1.753 -0.379)
        (xy 1.748 -0.371)
        (xy 1.742 -0.36)
        (xy 1.735 -0.344)
        (xy 1.726 -0.324)
        (xy 1.715 -0.297)
        (xy 1.701 -0.264)
        (xy 1.685 -0.223)
        (xy 1.665 -0.174)
        (xy 1.653 -0.145)
        (xy 1.63 -0.086)
        (xy 1.61 -0.037)
        (xy 1.594 0.005)
        (xy 1.582 0.038)
        (xy 1.572 0.064)
        (xy 1.566 0.084)
        (xy 1.562 0.097)
        (xy 1.561 0.104)
        (xy 1.562 0.105)
        (xy 1.565 0.111)
        (xy 1.574 0.125)
        (xy 1.587 0.146)
        (xy 1.604 0.173)
        (xy 1.626 0.205)
        (xy 1.65 0.241)
        (xy 1.677 0.281)
        (xy 1.706 0.324)
        (xy 1.729 0.358)
        (xy 1.768 0.413)
        (xy 1.8 0.461)
        (xy 1.827 0.502)
        (xy 1.85 0.535)
        (xy 1.867 0.562)
        (xy 1.88 0.583)
        (xy 1.889 0.598)
        (xy 1.893 0.608)
        (xy 1.894 0.612)
        (xy 1.893 0.616)
        (xy 1.89 0.622)
        (xy 1.885 0.63)
        (xy 1.876 0.64)
        (xy 1.863 0.655)
        (xy 1.846 0.673)
        (xy 1.825 0.695)
        (xy 1.798 0.723)
        (xy 1.765 0.756)
        (xy 1.727 0.795)
        (xy 1.682 0.839)
        (xy 1.635 0.886)
        (xy 1.595 0.926)
        (xy 1.561 0.96)
        (xy 1.532 0.989)
        (xy 1.508 1.012)
        (xy 1.488 1.03)
        (xy 1.473 1.044)
        (xy 1.461 1.054)
        (xy 1.452 1.061)
        (xy 1.445 1.065)
        (xy 1.44 1.066)
        (xy 1.438 1.066)
        (xy 1.433 1.064)
        (xy 1.421 1.055)
        (xy 1.401 1.043)
        (xy 1.376 1.026)
        (xy 1.345 1.005)
        (xy 1.31 0.981)
        (xy 1.27 0.954)
        (xy 1.228 0.925)
        (xy 1.193 0.901)
        (xy 1.138 0.864)
        (xy 1.089 0.83)
        (xy 1.046 0.802)
        (xy 1.01 0.778)
        (xy 0.981 0.759)
        (xy 0.96 0.746)
        (xy 0.946 0.738)
        (xy 0.94 0.736)
        (xy 0.932 0.738)
        (xy 0.917 0.745)
        (xy 0.895 0.755)
        (xy 0.869 0.768)
        (xy 0.84 0.783)
        (xy 0.816 0.795)
        (xy 0.781 0.814)
        (xy 0.753 0.828)
        (xy 0.732 0.838)
        (xy 0.717 0.845)
        (xy 0.707 0.849)
        (xy 0.699 0.85)
        (xy 0.694 0.849)
        (xy 0.691 0.847)
        (xy 0.687 0.84)
        (xy 0.682 0.829)
        (xy 0.674 0.814)
        (xy 0.665 0.793)
        (xy 0.653 0.767)
        (xy 0.639 0.735)
        (xy 0.623 0.696)
        (xy 0.604 0.651)
        (xy 0.582 0.598)
        (xy 0.556 0.538)
        (xy 0.528 0.469)
        (xy 0.496 0.391)
        (xy 0.47 0.329)
        (xy 0.436 0.247)
        (xy 0.406 0.173)
        (xy 0.379 0.108)
        (xy 0.355 0.05)
        (xy 0.335 0)
        (xy 0.317 -0.043)
        (xy 0.303 -0.079)
        (xy 0.291 -0.11)
        (xy 0.281 -0.135)
        (xy 0.273 -0.155)
        (xy 0.268 -0.171)
        (xy 0.264 -0.183)
        (xy 0.262 -0.191)
        (xy 0.262 -0.196)
        (xy 0.262 -0.198)
        (xy 0.269 -0.207)
        (xy 0.283 -0.219)
        (xy 0.302 -0.233)
        (xy 0.303 -0.234)
        (xy 0.354 -0.268)
        (xy 0.398 -0.3)
        (xy 0.435 -0.331)
        (xy 0.469 -0.363)
        (xy 0.5 -0.397)
        (xy 0.507 -0.405)
        (xy 0.556 -0.472)
        (xy 0.596 -0.543)
        (xy 0.627 -0.619)
        (xy 0.643 -0.672)
        (xy 0.651 -0.718)
        (xy 0.657 -0.77)
        (xy 0.66 -0.824)
        (xy 0.659 -0.878)
        (xy 0.654 -0.927)
        (xy 0.652 -0.936)
        (xy 0.634 -1.015)
        (xy 0.607 -1.09)
        (xy 0.571 -1.161)
        (xy 0.528 -1.227)
        (xy 0.477 -1.287)
        (xy 0.419 -1.341)
        (xy 0.355 -1.387)
        (xy 0.285 -1.426)
        (xy 0.21 -1.456)
        (xy 0.205 -1.458)
        (xy 0.131 -1.477)
        (xy 0.054 -1.487)
        (xy -0.025 -1.489)
        (xy -0.103 -1.482)
        (xy -0.178 -1.466)
        (xy -0.206 -1.458)
        (xy -0.281 -1.428)
        (xy -0.351 -1.39)
        (xy -0.416 -1.344)
        (xy -0.474 -1.29)
        (xy -0.526 -1.23)
        (xy -0.571 -1.164)
        (xy -0.607 -1.093)
        (xy -0.63 -1.034)
        (xy -0.649 -0.96)
        (xy -0.659 -0.883)
        (xy -0.661 -0.804)
        (xy -0.654 -0.726)
        (xy -0.638 -0.651)
        (xy -0.63 -0.623)
        (xy -0.618 -0.591)
        (xy -0.602 -0.554)
        (xy -0.584 -0.518)
        (xy -0.566 -0.485)
        (xy -0.553 -0.463)
        (xy -0.509 -0.407)
        (xy -0.457 -0.352)
        (xy -0.397 -0.299)
        (xy -0.33 -0.25)
        (xy -0.289 -0.224)
        (xy -0.273 -0.212)
        (xy -0.263 -0.2)
        (xy -0.262 -0.197)
        (xy -0.263 -0.19)
        (xy -0.268 -0.175)
        (xy -0.277 -0.151)
        (xy -0.288 -0.121)
        (xy -0.302 -0.084)
        (xy -0.319 -0.042)
        (xy -0.338 0.005)
        (xy -0.358 0.056)
        (xy -0.381 0.111)
        (xy -0.404 0.168)
        (xy -0.428 0.228)
        (xy -0.453 0.288)
        (xy -0.478 0.349)
        (xy -0.504 0.41)
        (xy -0.529 0.47)
        (xy -0.553 0.527)
        (xy -0.576 0.583)
        (xy -0.598 0.635)
        (xy -0.619 0.683)
        (xy -0.638 0.727)
        (xy -0.655 0.765)
        (xy -0.669 0.797)
        (xy -0.68 0.822)
        (xy -0.689 0.839)
        (xy -0.694 0.848)
        (xy -0.695 0.849)
        (xy -0.699 0.85)
        (xy -0.706 0.849)
        (xy -0.717 0.845)
        (xy -0.732 0.839)
        (xy -0.752 0.829)
        (xy -0.779 0.815)
        (xy -0.814 0.797)
        (xy -0.817 0.795)
        (xy -0.848 0.779)
        (xy -0.877 0.764)
        (xy -0.902 0.752)
        (xy -0.922 0.743)
        (xy -0.936 0.737)
        (xy -0.941 0.736)
        (xy -0.949 0.739)
        (xy -0.964 0.748)
        (xy -0.987 0.761)
        (xy -1.015 0.78)
        (xy -1.05 0.803)
        (xy -1.072 0.818)
        (xy -1.138 0.863)
        (xy -1.195 0.903)
        (xy -1.245 0.937)
        (xy -1.289 0.966)
        (xy -1.325 0.991)
        (xy -1.356 1.012)
        (xy -1.381 1.029)
        (xy -1.401 1.042)
        (xy -1.416 1.052)
        (xy -1.427 1.059)
        (xy -1.435 1.064)
        (xy -1.439 1.066)
        (xy -1.44 1.066)
        (xy -1.449 1.064)
        (xy -1.453 1.061)
        (xy -1.458 1.057)
        (xy -1.47 1.046)
        (xy -1.487 1.029)
        (xy -1.509 1.007)
        (xy -1.537 0.98)
        (xy -1.568 0.95)
        (xy -1.602 0.915)
        (xy -1.639 0.879)
        (xy -1.678 0.84)
        (xy -1.678 0.839)
        (xy -1.726 0.792)
        (xy -1.767 0.751)
        (xy -1.801 0.716)
        (xy -1.829 0.687)
        (xy -1.852 0.663)
        (xy -1.869 0.644)
        (xy -1.882 0.63)
        (xy -1.89 0.62)
        (xy -1.894 0.613)
        (xy -1.895 0.61)
        (xy -1.892 0.603)
        (xy -1.884 0.588)
        (xy -1.87 0.565)
        (xy -1.85 0.536)
        (xy -1.826 0.499)
        (xy -1.797 0.455)
        (xy -1.763 0.405)
        (xy -1.73 0.358)
        (xy -1.7 0.313)
        (xy -1.671 0.271)
        (xy -1.645 0.232)
        (xy -1.621 0.197)
        (xy -1.601 0.166)
        (xy -1.584 0.141)
        (xy -1.572 0.121)
        (xy -1.565 0.109)
        (xy -1.563 0.105)
        (xy -1.563 0.099)
        (xy -1.566 0.087)
        (xy -1.572 0.07)
        (xy -1.58 0.045)
        (xy -1.592 0.013)
        (xy -1.607 -0.026)
        (xy -1.626 -0.074)
        (xy -1.648 -0.13)
        (xy -1.654 -0.145)
        (xy -1.676 -0.199)
        (xy -1.695 -0.245)
        (xy -1.71 -0.282)
        (xy -1.723 -0.313)
        (xy -1.733 -0.337)
        (xy -1.741 -0.356)
        (xy -1.748 -0.369)
        (xy -1.753 -0.379)
        (xy -1.758 -0.385)
        (xy -1.761 -0.388)
        (xy -1.763 -0.389)
        (xy -1.767 -0.39)
        (xy -1.774 -0.392)
        (xy -1.784 -0.395)
        (xy -1.799 -0.398)
        (xy -1.818 -0.402)
        (xy -1.843 -0.407)
        (xy -1.873 -0.413)
        (xy -1.91 -0.42)
        (xy -1.954 -0.429)
        (xy -2.005 -0.438)
        (xy -2.065 -0.449)
        (xy -2.133 -0.462)
        (xy -2.211 -0.477)
        (xy -2.22 -0.478)
        (xy -2.26 -0.486)
        (xy -2.29 -0.491)
        (xy -2.313 -0.496)
        (xy -2.33 -0.499)
        (xy -2.341 -0.502)
        (xy -2.349 -0.504)
        (xy -2.353 -0.506)
        (xy -2.356 -0.508)
        (xy -2.359 -0.51)
        (xy -2.36 -0.511)
        (xy -2.361 -0.514)
        (xy -2.363 -0.518)
        (xy -2.364 -0.526)
        (xy -2.365 -0.536)
        (xy -2.366 -0.551)
        (xy -2.366 -0.571)
        (xy -2.367 -0.597)
        (xy -2.367 -0.629)
        (xy -2.368 -0.668)
        (xy -2.368 -0.715)
        (xy -2.368 -0.771)
        (xy -2.368 -0.834)
        (xy -2.368 -1.148)
        (xy -2.356 -1.155)
        (xy -2.349 -1.158)
        (xy -2.333 -1.162)
        (xy -2.309 -1.167)
        (xy -2.278 -1.173)
        (xy -2.24 -1.181)
        (xy -2.197 -1.189)
        (xy -2.149 -1.198)
        (xy -2.098 -1.208)
        (xy -2.051 -1.217)
        (xy -1.996 -1.227)
        (xy -1.945 -1.237)
        (xy -1.897 -1.246)
        (xy -1.854 -1.254)
        (xy -1.817 -1.262)
        (xy -1.787 -1.268)
        (xy -1.764 -1.273)
        (xy -1.75 -1.277)
        (xy -1.745 -1.279)
        (xy -1.741 -1.285)
        (xy -1.733 -1.3)
        (xy -1.722 -1.322)
        (xy -1.709 -1.35)
        (xy -1.694 -1.382)
        (xy -1.677 -1.419)
        (xy -1.66 -1.458)
        (xy -1.642 -1.498)
        (xy -1.625 -1.539)
        (xy -1.608 -1.58)
        (xy -1.592 -1.618)
        (xy -1.578 -1.653)
        (xy -1.565 -1.684)
        (xy -1.556 -1.709)
        (xy -1.549 -1.729)
        (xy -1.546 -1.74)
        (xy -1.546 -1.742)
        (xy -1.549 -1.749)
        (xy -1.558 -1.763)
        (xy -1.571 -1.784)
        (xy -1.588 -1.811)
        (xy -1.61 -1.843)
        (xy -1.634 -1.88)
        (xy -1.661 -1.92)
        (xy -1.691 -1.963)
        (xy -1.722 -2.008)
        (xy -1.762 -2.067)
        (xy -1.796 -2.117)
        (xy -1.825 -2.16)
        (xy -1.848 -2.196)
        (xy -1.867 -2.225)
        (xy -1.881 -2.247)
        (xy -1.89 -2.262)
        (xy -1.895 -2.272)
        (xy -1.895 -2.275)
        (xy -1.894 -2.279)
        (xy -1.891 -2.285)
        (xy -1.884 -2.293)
        (xy -1.875 -2.305)
        (xy -1.861 -2.32)
        (xy -1.843 -2.339)
        (xy -1.82 -2.363)
        (xy -1.792 -2.392)
        (xy -1.758 -2.426)
        (xy -1.718 -2.466)
        (xy -1.676 -2.509)
        (xy -1.627 -2.557)
        (xy -1.585 -2.599)
        (xy -1.549 -2.634)
        (xy -1.52 -2.663)
        (xy -1.495 -2.686)
        (xy -1.476 -2.704)
        (xy -1.462 -2.716)
        (xy -1.452 -2.724)
        (xy -1.446 -2.728)
        (xy -1.444 -2.728)
        (xy -1.437 -2.726)
        (xy -1.423 -2.717)
        (xy -1.401 -2.703)
        (xy -1.372 -2.685)
        (xy -1.337 -2.661)
        (xy -1.295 -2.634)
        (xy -1.248 -2.602)
        (xy -1.196 -2.566)
        (xy -1.173 -2.551)
        (xy -1.118 -2.513)
        (xy -1.071 -2.481)
        (xy -1.031 -2.454)
        (xy -0.998 -2.432)
        (xy -0.97 -2.413)
        (xy -0.948 -2.399)
        (xy -0.931 -2.389)
        (xy -0.917 -2.381)
        (xy -0.907 -2.376)
        (xy -0.901 -2.373)
        (xy -0.897 -2.373)
        (xy -0.888 -2.375)
        (xy -0.87 -2.38)
        (xy -0.845 -2.39)
        (xy -0.813 -2.402)
        (xy -0.774 -2.417)
        (xy -0.73 -2.434)
        (xy -0.681 -2.454)
        (xy -0.629 -2.475)
        (xy -0.586 -2.493)
        (xy -0.55 -2.508)
        (xy -0.522 -2.52)
        (xy -0.499 -2.529)
        (xy -0.482 -2.537)
        (xy -0.47 -2.543)
        (xy -0.461 -2.548)
        (xy -0.455 -2.551)
        (xy -0.452 -2.554)
        (xy -0.449 -2.557)
        (xy -0.448 -2.56)
        (xy -0.447 -2.566)
        (xy -0.443 -2.582)
        (xy -0.438 -2.605)
        (xy -0.432 -2.637)
        (xy -0.425 -2.674)
        (xy -0.417 -2.717)
        (xy -0.407 -2.765)
        (xy -0.398 -2.817)
        (xy -0.388 -2.871)
        (xy -0.387 -2.876)
        (xy -0.375 -2.94)
        (xy -0.364 -2.995)
        (xy -0.356 -3.042)
        (xy -0.348 -3.081)
        (xy -0.342 -3.112)
        (xy -0.337 -3.137)
        (xy -0.332 -3.157)
        (xy -0.328 -3.171)
        (xy -0.325 -3.181)
        (xy -0.323 -3.188)
        (xy -0.32 -3.191)
        (xy -0.32 -3.192)
        (xy -0.317 -3.194)
        (xy -0.313 -3.195)
        (xy -0.307 -3.197)
        (xy -0.298 -3.198)
        (xy -0.286 -3.199)
        (xy -0.269 -3.199)
        (xy -0.247 -3.2)
        (xy -0.219 -3.2)
        (xy -0.184 -3.201)
        (xy -0.142 -3.201)
        (xy -0.092 -3.201)
        (xy -0.033 -3.201)
        (xy -0.001 -3.201)
        (xy 0.063 -3.201)
      )

      (stroke (width 0.01) (type solid)) (fill solid) (layer "F.Cu"))
    (fp_poly
      (pts
        (xy -0.843 2.558)
        (xy -0.815 2.564)
        (xy -0.794 2.572)
        (xy -0.773 2.581)
        (xy -0.759 2.589)
        (xy -0.738 2.603)
        (xy -0.783 2.658)
        (xy -0.8 2.677)
        (xy -0.814 2.694)
        (xy -0.825 2.706)
        (xy -0.831 2.712)
        (xy -0.832 2.712)
        (xy -0.837 2.71)
        (xy -0.847 2.703)
        (xy -0.849 2.702)
        (xy -0.874 2.69)
        (xy -0.904 2.684)
        (xy -0.935 2.685)
        (xy -0.942 2.686)
        (xy -0.975 2.698)
        (xy -1.001 2.717)
        (xy -1.02 2.741)
        (xy -1.034 2.766)
        (xy -1.039 3.197)
        (xy -1.164 3.2)
        (xy -1.164 2.565)
        (xy -1.037 2.565)
        (xy -1.037 2.626)
        (xy -1.009 2.604)
        (xy -0.972 2.579)
        (xy -0.931 2.563)
        (xy -0.887 2.556)
        (xy -0.843 2.558)
      )

      (stroke (width 0.01) (type solid)) (fill solid) (layer "F.Mask"))
    (fp_poly
      (pts
        (xy 1.889 1.554)
        (xy 1.907 1.559)
        (xy 1.927 1.566)
        (xy 1.948 1.574)
        (xy 1.966 1.583)
        (xy 1.979 1.592)
        (xy 1.984 1.597)
        (xy 1.982 1.604)
        (xy 1.974 1.616)
        (xy 1.962 1.633)
        (xy 1.946 1.652)
        (xy 1.945 1.654)
        (xy 1.929 1.673)
        (xy 1.915 1.689)
        (xy 1.906 1.7)
        (xy 1.901 1.706)
        (xy 1.896 1.705)
        (xy 1.885 1.7)
        (xy 1.873 1.695)
        (xy 1.84 1.683)
        (xy 1.808 1.68)
        (xy 1.776 1.685)
        (xy 1.747 1.698)
        (xy 1.723 1.717)
        (xy 1.704 1.742)
        (xy 1.696 1.763)
        (xy 1.695 1.772)
        (xy 1.694 1.79)
        (xy 1.693 1.817)
        (xy 1.692 1.85)
        (xy 1.692 1.89)
        (xy 1.691 1.934)
        (xy 1.691 1.983)
        (xy 1.691 2.194)
        (xy 1.559 2.194)
        (xy 1.559 1.559)
        (xy 1.691 1.559)
        (xy 1.691 1.626)
        (xy 1.71 1.607)
        (xy 1.739 1.585)
        (xy 1.775 1.568)
        (xy 1.814 1.556)
        (xy 1.855 1.552)
        (xy 1.889 1.554)
      )

      (stroke (width 0.01) (type solid)) (fill solid) (layer "F.Mask"))
    (fp_poly
      (pts
        (xy -0.837 1.56)
        (xy -0.797 1.576)
        (xy -0.761 1.6)
        (xy -0.73 1.63)
        (xy -0.706 1.667)
        (xy -0.69 1.709)
        (xy -0.687 1.721)
        (xy -0.685 1.734)
        (xy -0.684 1.757)
        (xy -0.683 1.79)
        (xy -0.682 1.833)
        (xy -0.681 1.884)
        (xy -0.681 1.945)
        (xy -0.681 1.971)
        (xy -0.681 2.194)
        (xy -0.808 2.194)
        (xy -0.809 1.984)
        (xy -0.811 1.774)
        (xy -0.826 1.744)
        (xy -0.845 1.716)
        (xy -0.868 1.697)
        (xy -0.897 1.686)
        (xy -0.925 1.682)
        (xy -0.947 1.682)
        (xy -0.967 1.684)
        (xy -0.979 1.686)
        (xy -1.001 1.698)
        (xy -1.023 1.716)
        (xy -1.041 1.738)
        (xy -1.049 1.752)
        (xy -1.052 1.758)
        (xy -1.054 1.765)
        (xy -1.056 1.773)
        (xy -1.057 1.783)
        (xy -1.058 1.797)
        (xy -1.059 1.815)
        (xy -1.06 1.839)
        (xy -1.06 1.869)
        (xy -1.061 1.907)
        (xy -1.061 1.953)
        (xy -1.061 1.985)
        (xy -1.063 2.194)
        (xy -1.189 2.194)
        (xy -1.189 1.559)
        (xy -1.062 1.559)
        (xy -1.062 1.625)
        (xy -1.033 1.602)
        (xy -1.001 1.579)
        (xy -0.969 1.564)
        (xy -0.934 1.555)
        (xy -0.927 1.554)
        (xy -0.881 1.553)
        (xy -0.837 1.56)
      )

      (stroke (width 0.01) (type solid)) (fill solid) (layer "F.Mask"))
    (fp_poly
      (pts
        (xy 1.042 1.769)
        (xy 1.043 1.979)
        (xy 1.059 2.009)
        (xy 1.077 2.036)
        (xy 1.1 2.056)
        (xy 1.129 2.067)
        (xy 1.159 2.071)
        (xy 1.193 2.07)
        (xy 1.221 2.063)
        (xy 1.245 2.047)
        (xy 1.258 2.034)
        (xy 1.266 2.025)
        (xy 1.273 2.016)
        (xy 1.278 2.008)
        (xy 1.282 1.997)
        (xy 1.286 1.985)
        (xy 1.288 1.969)
        (xy 1.29 1.948)
        (xy 1.291 1.922)
        (xy 1.292 1.89)
        (xy 1.293 1.85)
        (xy 1.293 1.801)
        (xy 1.294 1.766)
        (xy 1.295 1.559)
        (xy 1.422 1.559)
        (xy 1.422 2.194)
        (xy 1.295 2.194)
        (xy 1.295 2.161)
        (xy 1.295 2.144)
        (xy 1.293 2.132)
        (xy 1.292 2.128)
        (xy 1.287 2.131)
        (xy 1.278 2.14)
        (xy 1.271 2.147)
        (xy 1.256 2.159)
        (xy 1.236 2.171)
        (xy 1.219 2.181)
        (xy 1.202 2.188)
        (xy 1.186 2.193)
        (xy 1.17 2.196)
        (xy 1.148 2.197)
        (xy 1.135 2.198)
        (xy 1.107 2.198)
        (xy 1.087 2.197)
        (xy 1.07 2.194)
        (xy 1.059 2.19)
        (xy 1.036 2.181)
        (xy 1.019 2.172)
        (xy 1.003 2.161)
        (xy 0.985 2.146)
        (xy 0.981 2.141)
        (xy 0.952 2.107)
        (xy 0.931 2.068)
        (xy 0.92 2.033)
        (xy 0.918 2.019)
        (xy 0.917 1.996)
        (xy 0.916 1.963)
        (xy 0.915 1.92)
        (xy 0.914 1.869)
        (xy 0.914 1.808)
        (xy 0.914 1.782)
        (xy 0.914 1.559)
        (xy 1.04 1.559)
        (xy 1.042 1.769)
      )

      (stroke (width 0.01) (type solid)) (fill solid) (layer "F.Mask"))
    (fp_poly
      (pts
        (xy 1.753 2.563)
        (xy 1.768 2.568)
        (xy 1.787 2.577)
        (xy 1.804 2.586)
        (xy 1.818 2.595)
        (xy 1.826 2.602)
        (xy 1.827 2.606)
        (xy 1.824 2.611)
        (xy 1.815 2.621)
        (xy 1.803 2.636)
        (xy 1.789 2.654)
        (xy 1.775 2.671)
        (xy 1.761 2.688)
        (xy 1.749 2.701)
        (xy 1.742 2.71)
        (xy 1.739 2.712)
        (xy 1.735 2.71)
        (xy 1.724 2.704)
        (xy 1.713 2.698)
        (xy 1.697 2.69)
        (xy 1.682 2.686)
        (xy 1.664 2.685)
        (xy 1.653 2.685)
        (xy 1.618 2.688)
        (xy 1.59 2.699)
        (xy 1.566 2.718)
        (xy 1.561 2.723)
        (xy 1.554 2.732)
        (xy 1.548 2.74)
        (xy 1.544 2.748)
        (xy 1.54 2.758)
        (xy 1.537 2.769)
        (xy 1.534 2.785)
        (xy 1.533 2.804)
        (xy 1.532 2.829)
        (xy 1.531 2.861)
        (xy 1.53 2.899)
        (xy 1.53 2.947)
        (xy 1.53 2.988)
        (xy 1.528 3.2)
        (xy 1.468 3.2)
        (xy 1.444 3.2)
        (xy 1.425 3.199)
        (xy 1.411 3.198)
        (xy 1.405 3.197)
        (xy 1.404 3.191)
        (xy 1.404 3.176)
        (xy 1.403 3.153)
        (xy 1.403 3.122)
        (xy 1.402 3.085)
        (xy 1.402 3.042)
        (xy 1.402 2.993)
        (xy 1.402 2.941)
        (xy 1.402 2.886)
        (xy 1.402 2.565)
        (xy 1.529 2.565)
        (xy 1.529 2.595)
        (xy 1.529 2.611)
        (xy 1.53 2.623)
        (xy 1.532 2.626)
        (xy 1.537 2.623)
        (xy 1.547 2.615)
        (xy 1.554 2.608)
        (xy 1.588 2.584)
        (xy 1.627 2.567)
        (xy 1.669 2.558)
        (xy 1.712 2.556)
        (xy 1.753 2.563)
      )

      (stroke (width 0.01) (type solid)) (fill solid) (layer "F.Mask"))
    (fp_poly
      (pts
        (xy 2.316 1.557)
        (xy 2.365 1.57)
        (xy 2.41 1.593)
        (xy 2.453 1.625)
        (xy 2.46 1.631)
        (xy 2.491 1.661)
        (xy 2.466 1.684)
        (xy 2.448 1.699)
        (xy 2.43 1.715)
        (xy 2.419 1.725)
        (xy 2.397 1.743)
        (xy 2.376 1.724)
        (xy 2.345 1.701)
        (xy 2.312 1.687)
        (xy 2.274 1.681)
        (xy 2.265 1.681)
        (xy 2.226 1.684)
        (xy 2.195 1.693)
        (xy 2.167 1.708)
        (xy 2.159 1.715)
        (xy 2.136 1.741)
        (xy 2.118 1.776)
        (xy 2.107 1.817)
        (xy 2.103 1.866)
        (xy 2.103 1.876)
        (xy 2.106 1.926)
        (xy 2.116 1.97)
        (xy 2.132 2.006)
        (xy 2.155 2.034)
        (xy 2.184 2.055)
        (xy 2.219 2.067)
        (xy 2.259 2.072)
        (xy 2.274 2.071)
        (xy 2.309 2.066)
        (xy 2.339 2.056)
        (xy 2.366 2.038)
        (xy 2.377 2.028)
        (xy 2.386 2.02)
        (xy 2.393 2.016)
        (xy 2.4 2.015)
        (xy 2.409 2.018)
        (xy 2.42 2.027)
        (xy 2.436 2.041)
        (xy 2.456 2.059)
        (xy 2.491 2.092)
        (xy 2.476 2.108)
        (xy 2.449 2.132)
        (xy 2.416 2.155)
        (xy 2.38 2.174)
        (xy 2.35 2.186)
        (xy 2.327 2.193)
        (xy 2.306 2.197)
        (xy 2.283 2.199)
        (xy 2.259 2.199)
        (xy 2.233 2.198)
        (xy 2.209 2.196)
        (xy 2.189 2.193)
        (xy 2.182 2.191)
        (xy 2.133 2.173)
        (xy 2.089 2.146)
        (xy 2.053 2.112)
        (xy 2.023 2.071)
        (xy 2.012 2.051)
        (xy 2 2.023)
        (xy 1.991 1.999)
        (xy 1.984 1.975)
        (xy 1.981 1.948)
        (xy 1.979 1.917)
        (xy 1.978 1.879)
        (xy 1.978 1.877)
        (xy 1.979 1.838)
        (xy 1.98 1.806)
        (xy 1.984 1.78)
        (xy 1.99 1.756)
        (xy 1.999 1.731)
        (xy 2.011 1.704)
        (xy 2.012 1.701)
        (xy 2.039 1.657)
        (xy 2.072 1.62)
        (xy 2.111 1.591)
        (xy 2.156 1.57)
        (xy 2.207 1.557)
        (xy 2.263 1.552)
        (xy 2.316 1.557)
      )

      (stroke (width 0.01) (type solid)) (fill solid) (layer "F.Mask"))
    (fp_poly
      (pts
        (xy -1.494 1.56)
        (xy -1.447 1.576)
        (xy -1.405 1.6)
        (xy -1.368 1.633)
        (xy -1.341 1.668)
        (xy -1.326 1.692)
        (xy -1.316 1.716)
        (xy -1.308 1.743)
        (xy -1.302 1.774)
        (xy -1.299 1.811)
        (xy -1.297 1.845)
        (xy -1.294 1.925)
        (xy -1.692 1.925)
        (xy -1.692 1.942)
        (xy -1.687 1.977)
        (xy -1.673 2.011)
        (xy -1.65 2.039)
        (xy -1.626 2.059)
        (xy -1.601 2.071)
        (xy -1.572 2.078)
        (xy -1.537 2.079)
        (xy -1.497 2.074)
        (xy -1.458 2.06)
        (xy -1.422 2.036)
        (xy -1.421 2.036)
        (xy -1.402 2.021)
        (xy -1.359 2.057)
        (xy -1.342 2.072)
        (xy -1.327 2.085)
        (xy -1.317 2.094)
        (xy -1.314 2.098)
        (xy -1.316 2.103)
        (xy -1.324 2.113)
        (xy -1.338 2.126)
        (xy -1.354 2.139)
        (xy -1.372 2.152)
        (xy -1.389 2.163)
        (xy -1.399 2.168)
        (xy -1.421 2.178)
        (xy -1.445 2.187)
        (xy -1.461 2.191)
        (xy -1.488 2.196)
        (xy -1.522 2.199)
        (xy -1.557 2.199)
        (xy -1.591 2.196)
        (xy -1.62 2.192)
        (xy -1.629 2.19)
        (xy -1.677 2.171)
        (xy -1.718 2.146)
        (xy -1.752 2.114)
        (xy -1.779 2.074)
        (xy -1.8 2.026)
        (xy -1.802 2.02)
        (xy -1.81 1.989)
        (xy -1.815 1.951)
        (xy -1.818 1.908)
        (xy -1.819 1.865)
        (xy -1.818 1.823)
        (xy -1.816 1.804)
        (xy -1.692 1.804)
        (xy -1.692 1.818)
        (xy -1.428 1.818)
        (xy -1.428 1.801)
        (xy -1.432 1.775)
        (xy -1.442 1.748)
        (xy -1.457 1.722)
        (xy -1.469 1.707)
        (xy -1.495 1.688)
        (xy -1.526 1.676)
        (xy -1.56 1.672)
        (xy -1.593 1.676)
        (xy -1.619 1.685)
        (xy -1.646 1.704)
        (xy -1.668 1.73)
        (xy -1.683 1.76)
        (xy -1.691 1.792)
        (xy -1.692 1.804)
        (xy -1.816 1.804)
        (xy -1.814 1.786)
        (xy -1.812 1.777)
        (xy -1.797 1.724)
        (xy -1.775 1.676)
        (xy -1.747 1.636)
        (xy -1.713 1.603)
        (xy -1.673 1.578)
        (xy -1.629 1.561)
        (xy -1.597 1.554)
        (xy -1.544 1.552)
        (xy -1.494 1.56)
      )

      (stroke (width 0.01) (type solid)) (fill solid) (layer "F.Mask"))
    (fp_poly
      (pts
        (xy 2.835 1.557)
        (xy 2.883 1.57)
        (xy 2.926 1.592)
        (xy 2.964 1.621)
        (xy 2.996 1.657)
        (xy 3.021 1.699)
        (xy 3.038 1.747)
        (xy 3.04 1.757)
        (xy 3.043 1.776)
        (xy 3.045 1.802)
        (xy 3.047 1.832)
        (xy 3.047 1.858)
        (xy 3.047 1.925)
        (xy 2.65 1.925)
        (xy 2.653 1.951)
        (xy 2.663 1.991)
        (xy 2.68 2.024)
        (xy 2.703 2.049)
        (xy 2.733 2.067)
        (xy 2.77 2.077)
        (xy 2.801 2.079)
        (xy 2.845 2.075)
        (xy 2.883 2.063)
        (xy 2.916 2.042)
        (xy 2.92 2.039)
        (xy 2.929 2.031)
        (xy 2.935 2.026)
        (xy 2.941 2.025)
        (xy 2.949 2.027)
        (xy 2.959 2.034)
        (xy 2.974 2.047)
        (xy 2.994 2.064)
        (xy 3.01 2.078)
        (xy 3.023 2.088)
        (xy 3.03 2.095)
        (xy 3.032 2.096)
        (xy 3.03 2.1)
        (xy 3.022 2.11)
        (xy 3.01 2.122)
        (xy 3.009 2.123)
        (xy 2.98 2.147)
        (xy 2.945 2.169)
        (xy 2.906 2.185)
        (xy 2.887 2.191)
        (xy 2.861 2.196)
        (xy 2.828 2.198)
        (xy 2.793 2.198)
        (xy 2.759 2.197)
        (xy 2.729 2.193)
        (xy 2.721 2.191)
        (xy 2.675 2.175)
        (xy 2.634 2.15)
        (xy 2.599 2.118)
        (xy 2.569 2.077)
        (xy 2.547 2.029)
        (xy 2.536 1.996)
        (xy 2.532 1.973)
        (xy 2.529 1.942)
        (xy 2.527 1.906)
        (xy 2.527 1.869)
        (xy 2.528 1.832)
        (xy 2.529 1.818)
        (xy 2.65 1.818)
        (xy 2.922 1.818)
        (xy 2.918 1.799)
        (xy 2.908 1.758)
        (xy 2.891 1.725)
        (xy 2.869 1.7)
        (xy 2.84 1.683)
        (xy 2.826 1.678)
        (xy 2.788 1.672)
        (xy 2.753 1.675)
        (xy 2.722 1.687)
        (xy 2.695 1.706)
        (xy 2.674 1.734)
        (xy 2.659 1.768)
        (xy 2.654 1.794)
        (xy 2.65 1.818)
        (xy 2.529 1.818)
        (xy 2.53 1.798)
        (xy 2.534 1.769)
        (xy 2.536 1.76)
        (xy 2.554 1.707)
        (xy 2.578 1.662)
        (xy 2.609 1.624)
        (xy 2.645 1.593)
        (xy 2.687 1.571)
        (xy 2.734 1.557)
        (xy 2.783 1.553)
        (xy 2.835 1.557)
      )

      (stroke (width 0.01) (type solid)) (fill solid) (layer "F.Mask"))
    (fp_poly
      (pts
        (xy -2.733 1.557)
        (xy -2.685 1.57)
        (xy -2.642 1.592)
        (xy -2.604 1.622)
        (xy -2.581 1.649)
        (xy -2.562 1.676)
        (xy -2.548 1.706)
        (xy -2.537 1.739)
        (xy -2.53 1.777)
        (xy -2.527 1.821)
        (xy -2.526 1.873)
        (xy -2.527 1.907)
        (xy -2.529 1.956)
        (xy -2.534 1.997)
        (xy -2.542 2.031)
        (xy -2.553 2.06)
        (xy -2.567 2.086)
        (xy -2.587 2.111)
        (xy -2.603 2.129)
        (xy -2.637 2.158)
        (xy -2.673 2.178)
        (xy -2.714 2.192)
        (xy -2.76 2.198)
        (xy -2.789 2.199)
        (xy -2.813 2.198)
        (xy -2.835 2.196)
        (xy -2.852 2.194)
        (xy -2.857 2.194)
        (xy -2.898 2.179)
        (xy -2.937 2.155)
        (xy -2.97 2.126)
        (xy -2.993 2.101)
        (xy -3.011 2.077)
        (xy -3.024 2.051)
        (xy -3.034 2.022)
        (xy -3.041 1.988)
        (xy -3.045 1.947)
        (xy -3.047 1.91)
        (xy -3.047 1.882)
        (xy -2.919 1.882)
        (xy -2.919 1.968)
        (xy -2.903 2.001)
        (xy -2.885 2.031)
        (xy -2.863 2.051)
        (xy -2.837 2.064)
        (xy -2.804 2.07)
        (xy -2.779 2.07)
        (xy -2.755 2.069)
        (xy -2.737 2.065)
        (xy -2.722 2.058)
        (xy -2.717 2.055)
        (xy -2.697 2.041)
        (xy -2.681 2.025)
        (xy -2.67 2.004)
        (xy -2.662 1.978)
        (xy -2.657 1.945)
        (xy -2.654 1.903)
        (xy -2.654 1.899)
        (xy -2.653 1.848)
        (xy -2.656 1.806)
        (xy -2.662 1.772)
        (xy -2.673 1.744)
        (xy -2.687 1.722)
        (xy -2.707 1.705)
        (xy -2.723 1.695)
        (xy -2.755 1.684)
        (xy -2.788 1.68)
        (xy -2.821 1.684)
        (xy -2.851 1.695)
        (xy -2.877 1.713)
        (xy -2.892 1.729)
        (xy -2.901 1.745)
        (xy -2.908 1.76)
        (xy -2.913 1.778)
        (xy -2.916 1.8)
        (xy -2.918 1.828)
        (xy -2.919 1.864)
        (xy -2.919 1.882)
        (xy -3.047 1.882)
        (xy -3.048 1.844)
        (xy -3.043 1.786)
        (xy -3.034 1.736)
        (xy -3.021 1.695)
        (xy -3.004 1.664)
        (xy -2.972 1.624)
        (xy -2.935 1.594)
        (xy -2.893 1.571)
        (xy -2.846 1.558)
        (xy -2.794 1.553)
        (xy -2.787 1.553)
        (xy -2.733 1.557)
      )

      (stroke (width 0.01) (type solid)) (fill solid) (layer "F.Mask"))
    (fp_poly
      (pts
        (xy 2.148 2.561)
        (xy 2.193 2.574)
        (xy 2.235 2.595)
        (xy 2.273 2.623)
        (xy 2.304 2.657)
        (xy 2.326 2.691)
        (xy 2.338 2.718)
        (xy 2.346 2.745)
        (xy 2.352 2.774)
        (xy 2.355 2.808)
        (xy 2.357 2.85)
        (xy 2.357 2.858)
        (xy 2.357 2.931)
        (xy 1.96 2.931)
        (xy 1.963 2.955)
        (xy 1.973 2.993)
        (xy 1.991 3.026)
        (xy 2.015 3.053)
        (xy 2.039 3.069)
        (xy 2.057 3.076)
        (xy 2.08 3.08)
        (xy 2.103 3.082)
        (xy 2.144 3.081)
        (xy 2.18 3.071)
        (xy 2.214 3.054)
        (xy 2.227 3.045)
        (xy 2.24 3.035)
        (xy 2.25 3.029)
        (xy 2.253 3.027)
        (xy 2.258 3.03)
        (xy 2.269 3.039)
        (xy 2.284 3.05)
        (xy 2.3 3.064)
        (xy 2.315 3.078)
        (xy 2.329 3.09)
        (xy 2.338 3.099)
        (xy 2.341 3.103)
        (xy 2.337 3.11)
        (xy 2.327 3.121)
        (xy 2.312 3.134)
        (xy 2.294 3.148)
        (xy 2.276 3.161)
        (xy 2.259 3.171)
        (xy 2.252 3.175)
        (xy 2.204 3.192)
        (xy 2.152 3.202)
        (xy 2.098 3.204)
        (xy 2.046 3.198)
        (xy 2.032 3.195)
        (xy 1.984 3.178)
        (xy 1.943 3.154)
        (xy 1.909 3.123)
        (xy 1.881 3.084)
        (xy 1.859 3.037)
        (xy 1.847 3.003)
        (xy 1.841 2.972)
        (xy 1.838 2.934)
        (xy 1.836 2.893)
        (xy 1.837 2.851)
        (xy 1.839 2.824)
        (xy 1.96 2.824)
        (xy 2.23 2.824)
        (xy 2.23 2.813)
        (xy 2.225 2.783)
        (xy 2.214 2.753)
        (xy 2.196 2.725)
        (xy 2.175 2.702)
        (xy 2.151 2.686)
        (xy 2.128 2.68)
        (xy 2.101 2.677)
        (xy 2.072 2.678)
        (xy 2.051 2.683)
        (xy 2.023 2.696)
        (xy 2 2.717)
        (xy 1.981 2.746)
        (xy 1.968 2.779)
        (xy 1.963 2.8)
        (xy 1.96 2.824)
        (xy 1.839 2.824)
        (xy 1.839 2.811)
        (xy 1.844 2.776)
        (xy 1.848 2.76)
        (xy 1.866 2.708)
        (xy 1.889 2.663)
        (xy 1.919 2.627)
        (xy 1.954 2.598)
        (xy 1.996 2.575)
        (xy 2.007 2.571)
        (xy 2.054 2.559)
        (xy 2.101 2.556)
        (xy 2.148 2.561)
      )

      (stroke (width 0.01) (type solid)) (fill solid) (layer "F.Mask"))
    (fp_poly
      (pts
        (xy -0.229 3.2)
        (xy -0.354 3.197)
        (xy -0.355 3.165)
        (xy -0.357 3.133)
        (xy -0.374 3.148)
        (xy -0.411 3.175)
        (xy -0.453 3.193)
        (xy -0.497 3.203)
        (xy -0.542 3.204)
        (xy -0.585 3.195)
        (xy -0.586 3.195)
        (xy -0.621 3.181)
        (xy -0.651 3.16)
        (xy -0.673 3.141)
        (xy -0.689 3.123)
        (xy -0.702 3.106)
        (xy -0.712 3.086)
        (xy -0.72 3.064)
        (xy -0.726 3.038)
        (xy -0.73 3.007)
        (xy -0.732 2.968)
        (xy -0.733 2.922)
        (xy -0.733 2.88)
        (xy -0.602 2.88)
        (xy -0.602 2.915)
        (xy -0.602 2.942)
        (xy -0.601 2.962)
        (xy -0.6 2.977)
        (xy -0.598 2.988)
        (xy -0.596 2.998)
        (xy -0.592 3.007)
        (xy -0.591 3.01)
        (xy -0.574 3.039)
        (xy -0.552 3.059)
        (xy -0.525 3.071)
        (xy -0.492 3.076)
        (xy -0.472 3.076)
        (xy -0.442 3.072)
        (xy -0.418 3.063)
        (xy -0.398 3.048)
        (xy -0.382 3.029)
        (xy -0.371 3.004)
        (xy -0.363 2.972)
        (xy -0.358 2.933)
        (xy -0.356 2.885)
        (xy -0.356 2.88)
        (xy -0.358 2.828)
        (xy -0.363 2.785)
        (xy -0.373 2.75)
        (xy -0.387 2.724)
        (xy -0.406 2.704)
        (xy -0.43 2.692)
        (xy -0.46 2.686)
        (xy -0.483 2.685)
        (xy -0.517 2.687)
        (xy -0.544 2.696)
        (xy -0.565 2.711)
        (xy -0.583 2.734)
        (xy -0.591 2.751)
        (xy -0.595 2.76)
        (xy -0.598 2.769)
        (xy -0.6 2.779)
        (xy -0.601 2.793)
        (xy -0.602 2.811)
        (xy -0.602 2.836)
        (xy -0.602 2.869)
        (xy -0.602 2.88)
        (xy -0.733 2.88)
        (xy -0.733 2.827)
        (xy -0.732 2.783)
        (xy -0.729 2.746)
        (xy -0.725 2.716)
        (xy -0.719 2.691)
        (xy -0.71 2.67)
        (xy -0.699 2.651)
        (xy -0.685 2.633)
        (xy -0.668 2.616)
        (xy -0.668 2.615)
        (xy -0.632 2.587)
        (xy -0.592 2.567)
        (xy -0.55 2.557)
        (xy -0.506 2.556)
        (xy -0.463 2.564)
        (xy -0.421 2.582)
        (xy -0.411 2.587)
        (xy -0.394 2.598)
        (xy -0.377 2.61)
        (xy -0.373 2.614)
        (xy -0.356 2.627)
        (xy -0.356 2.306)
        (xy -0.229 2.306)
        (xy -0.229 3.2)
      )

      (stroke (width 0.01) (type solid)) (fill solid) (layer "F.Mask"))
    (fp_poly
      (pts
        (xy 0.605 1.558)
        (xy 0.651 1.574)
        (xy 0.694 1.598)
        (xy 0.728 1.627)
        (xy 0.75 1.652)
        (xy 0.768 1.678)
        (xy 0.781 1.707)
        (xy 0.791 1.739)
        (xy 0.797 1.777)
        (xy 0.801 1.822)
        (xy 0.802 1.876)
        (xy 0.802 1.877)
        (xy 0.801 1.929)
        (xy 0.798 1.973)
        (xy 0.792 2.009)
        (xy 0.784 2.04)
        (xy 0.774 2.062)
        (xy 0.748 2.103)
        (xy 0.715 2.139)
        (xy 0.675 2.167)
        (xy 0.632 2.187)
        (xy 0.626 2.189)
        (xy 0.599 2.195)
        (xy 0.567 2.198)
        (xy 0.532 2.199)
        (xy 0.499 2.197)
        (xy 0.471 2.193)
        (xy 0.466 2.192)
        (xy 0.428 2.177)
        (xy 0.391 2.155)
        (xy 0.359 2.129)
        (xy 0.354 2.123)
        (xy 0.332 2.098)
        (xy 0.316 2.073)
        (xy 0.303 2.047)
        (xy 0.294 2.017)
        (xy 0.287 1.983)
        (xy 0.284 1.943)
        (xy 0.282 1.894)
        (xy 0.282 1.877)
        (xy 0.409 1.877)
        (xy 0.41 1.918)
        (xy 0.412 1.95)
        (xy 0.416 1.976)
        (xy 0.423 1.997)
        (xy 0.432 2.015)
        (xy 0.445 2.03)
        (xy 0.451 2.037)
        (xy 0.471 2.054)
        (xy 0.491 2.064)
        (xy 0.514 2.07)
        (xy 0.543 2.072)
        (xy 0.569 2.07)
        (xy 0.59 2.065)
        (xy 0.601 2.06)
        (xy 0.625 2.047)
        (xy 0.642 2.031)
        (xy 0.656 2.009)
        (xy 0.661 1.998)
        (xy 0.665 1.989)
        (xy 0.668 1.98)
        (xy 0.67 1.969)
        (xy 0.671 1.954)
        (xy 0.672 1.935)
        (xy 0.673 1.909)
        (xy 0.673 1.877)
        (xy 0.673 1.842)
        (xy 0.672 1.817)
        (xy 0.671 1.798)
        (xy 0.67 1.784)
        (xy 0.668 1.773)
        (xy 0.665 1.764)
        (xy 0.661 1.755)
        (xy 0.647 1.73)
        (xy 0.632 1.712)
        (xy 0.612 1.698)
        (xy 0.601 1.693)
        (xy 0.569 1.683)
        (xy 0.535 1.681)
        (xy 0.501 1.686)
        (xy 0.471 1.7)
        (xy 0.447 1.719)
        (xy 0.434 1.736)
        (xy 0.424 1.753)
        (xy 0.417 1.774)
        (xy 0.412 1.8)
        (xy 0.41 1.833)
        (xy 0.409 1.873)
        (xy 0.409 1.877)
        (xy 0.282 1.877)
        (xy 0.283 1.824)
        (xy 0.286 1.78)
        (xy 0.292 1.742)
        (xy 0.301 1.711)
        (xy 0.313 1.683)
        (xy 0.33 1.657)
        (xy 0.35 1.633)
        (xy 0.351 1.632)
        (xy 0.385 1.601)
        (xy 0.42 1.578)
        (xy 0.46 1.563)
        (xy 0.505 1.554)
        (xy 0.555 1.551)
        (xy 0.605 1.558)
      )

      (stroke (width 0.01) (type solid)) (fill solid) (layer "F.Mask"))
    (fp_poly
      (pts
        (xy 0.004 1.556)
        (xy 0.054 1.566)
        (xy 0.102 1.582)
        (xy 0.146 1.605)
        (xy 0.154 1.61)
        (xy 0.193 1.636)
        (xy 0.178 1.655)
        (xy 0.166 1.668)
        (xy 0.152 1.686)
        (xy 0.138 1.7)
        (xy 0.114 1.727)
        (xy 0.07 1.705)
        (xy 0.032 1.688)
        (xy -0.007 1.677)
        (xy -0.044 1.672)
        (xy -0.079 1.672)
        (xy -0.11 1.678)
        (xy -0.136 1.69)
        (xy -0.154 1.707)
        (xy -0.162 1.724)
        (xy -0.164 1.745)
        (xy -0.164 1.761)
        (xy -0.159 1.772)
        (xy -0.15 1.782)
        (xy -0.149 1.783)
        (xy -0.139 1.791)
        (xy -0.128 1.797)
        (xy -0.114 1.802)
        (xy -0.095 1.805)
        (xy -0.07 1.808)
        (xy -0.037 1.811)
        (xy -0.02 1.813)
        (xy 0.027 1.817)
        (xy 0.065 1.823)
        (xy 0.096 1.832)
        (xy 0.122 1.842)
        (xy 0.14 1.854)
        (xy 0.166 1.879)
        (xy 0.186 1.91)
        (xy 0.2 1.947)
        (xy 0.206 1.987)
        (xy 0.206 2.018)
        (xy 0.198 2.06)
        (xy 0.181 2.097)
        (xy 0.155 2.129)
        (xy 0.122 2.156)
        (xy 0.08 2.177)
        (xy 0.042 2.189)
        (xy 0.005 2.196)
        (xy -0.038 2.199)
        (xy -0.083 2.198)
        (xy -0.125 2.194)
        (xy -0.153 2.189)
        (xy -0.177 2.181)
        (xy -0.204 2.171)
        (xy -0.229 2.16)
        (xy -0.232 2.159)
        (xy -0.251 2.148)
        (xy -0.272 2.136)
        (xy -0.292 2.122)
        (xy -0.309 2.109)
        (xy -0.323 2.098)
        (xy -0.33 2.09)
        (xy -0.331 2.088)
        (xy -0.327 2.084)
        (xy -0.318 2.073)
        (xy -0.304 2.059)
        (xy -0.288 2.043)
        (xy -0.246 2)
        (xy -0.221 2.021)
        (xy -0.184 2.047)
        (xy -0.145 2.065)
        (xy -0.102 2.075)
        (xy -0.053 2.079)
        (xy -0.049 2.079)
        (xy -0.023 2.079)
        (xy -0.004 2.078)
        (xy 0.011 2.074)
        (xy 0.025 2.069)
        (xy 0.029 2.068)
        (xy 0.054 2.052)
        (xy 0.071 2.033)
        (xy 0.079 2.01)
        (xy 0.078 1.986)
        (xy 0.074 1.975)
        (xy 0.068 1.964)
        (xy 0.06 1.956)
        (xy 0.048 1.949)
        (xy 0.031 1.944)
        (xy 0.007 1.939)
        (xy -0.024 1.935)
        (xy -0.052 1.932)
        (xy -0.089 1.929)
        (xy -0.119 1.925)
        (xy -0.142 1.921)
        (xy -0.16 1.917)
        (xy -0.176 1.912)
        (xy -0.192 1.906)
        (xy -0.201 1.901)
        (xy -0.235 1.879)
        (xy -0.262 1.85)
        (xy -0.28 1.816)
        (xy -0.29 1.776)
        (xy -0.292 1.75)
        (xy -0.291 1.727)
        (xy -0.289 1.705)
        (xy -0.286 1.689)
        (xy -0.286 1.688)
        (xy -0.273 1.659)
        (xy -0.253 1.63)
        (xy -0.229 1.604)
        (xy -0.221 1.599)
        (xy -0.185 1.577)
        (xy -0.143 1.562)
        (xy -0.096 1.554)
        (xy -0.047 1.552)
        (xy 0.004 1.556)
      )

      (stroke (width 0.01) (type solid)) (fill solid) (layer "F.Mask"))
    (fp_poly
      (pts
        (xy 1.038 2.556)
        (xy 1.091 2.563)
        (xy 1.137 2.576)
        (xy 1.177 2.595)
        (xy 1.209 2.62)
        (xy 1.234 2.65)
        (xy 1.242 2.665)
        (xy 1.247 2.677)
        (xy 1.251 2.691)
        (xy 1.255 2.708)
        (xy 1.258 2.727)
        (xy 1.26 2.751)
        (xy 1.262 2.78)
        (xy 1.263 2.815)
        (xy 1.263 2.858)
        (xy 1.264 2.908)
        (xy 1.263 2.967)
        (xy 1.263 2.989)
        (xy 1.262 3.197)
        (xy 1.135 3.197)
        (xy 1.133 3.171)
        (xy 1.132 3.144)
        (xy 1.119 3.159)
        (xy 1.096 3.179)
        (xy 1.065 3.193)
        (xy 1.026 3.202)
        (xy 0.98 3.204)
        (xy 0.976 3.204)
        (xy 0.955 3.204)
        (xy 0.937 3.203)
        (xy 0.925 3.202)
        (xy 0.924 3.201)
        (xy 0.879 3.189)
        (xy 0.839 3.17)
        (xy 0.806 3.144)
        (xy 0.781 3.113)
        (xy 0.763 3.077)
        (xy 0.753 3.037)
        (xy 0.753 3.005)
        (xy 0.873 3.005)
        (xy 0.874 3.023)
        (xy 0.878 3.035)
        (xy 0.887 3.047)
        (xy 0.89 3.05)
        (xy 0.903 3.063)
        (xy 0.917 3.072)
        (xy 0.935 3.078)
        (xy 0.957 3.081)
        (xy 0.986 3.082)
        (xy 1.013 3.082)
        (xy 1.043 3.081)
        (xy 1.065 3.079)
        (xy 1.08 3.077)
        (xy 1.091 3.073)
        (xy 1.096 3.071)
        (xy 1.112 3.058)
        (xy 1.123 3.039)
        (xy 1.13 3.012)
        (xy 1.132 2.977)
        (xy 1.132 2.975)
        (xy 1.132 2.931)
        (xy 1.035 2.931)
        (xy 0.999 2.931)
        (xy 0.973 2.931)
        (xy 0.953 2.932)
        (xy 0.939 2.934)
        (xy 0.928 2.936)
        (xy 0.919 2.939)
        (xy 0.916 2.94)
        (xy 0.893 2.954)
        (xy 0.88 2.971)
        (xy 0.874 2.994)
        (xy 0.873 3.005)
        (xy 0.753 3.005)
        (xy 0.753 2.994)
        (xy 0.761 2.951)
        (xy 0.768 2.931)
        (xy 0.776 2.915)
        (xy 0.786 2.901)
        (xy 0.802 2.884)
        (xy 0.804 2.882)
        (xy 0.82 2.867)
        (xy 0.835 2.854)
        (xy 0.85 2.845)
        (xy 0.867 2.838)
        (xy 0.887 2.833)
        (xy 0.912 2.829)
        (xy 0.943 2.827)
        (xy 0.982 2.826)
        (xy 1.015 2.825)
        (xy 1.133 2.823)
        (xy 1.132 2.771)
        (xy 1.131 2.746)
        (xy 1.129 2.73)
        (xy 1.127 2.719)
        (xy 1.123 2.711)
        (xy 1.117 2.705)
        (xy 1.098 2.691)
        (xy 1.07 2.682)
        (xy 1.032 2.677)
        (xy 1.006 2.677)
        (xy 0.972 2.678)
        (xy 0.945 2.682)
        (xy 0.924 2.688)
        (xy 0.907 2.699)
        (xy 0.9 2.706)
        (xy 0.882 2.723)
        (xy 0.834 2.686)
        (xy 0.816 2.672)
        (xy 0.801 2.66)
        (xy 0.79 2.652)
        (xy 0.787 2.648)
        (xy 0.791 2.639)
        (xy 0.801 2.626)
        (xy 0.816 2.612)
        (xy 0.832 2.6)
        (xy 0.864 2.581)
        (xy 0.902 2.568)
        (xy 0.946 2.559)
        (xy 0.98 2.556)
        (xy 1.038 2.556)
      )

      (stroke (width 0.01) (type solid)) (fill solid) (layer "F.Mask"))
    (fp_poly
      (pts
        (xy -1.521 2.559)
        (xy -1.485 2.562)
        (xy -1.454 2.568)
        (xy -1.427 2.577)
        (xy -1.401 2.589)
        (xy -1.371 2.61)
        (xy -1.345 2.639)
        (xy -1.325 2.67)
        (xy -1.321 2.679)
        (xy -1.309 2.71)
        (xy -1.309 3.197)
        (xy -1.433 3.2)
        (xy -1.433 3.172)
        (xy -1.434 3.157)
        (xy -1.435 3.147)
        (xy -1.436 3.144)
        (xy -1.44 3.147)
        (xy -1.449 3.156)
        (xy -1.453 3.161)
        (xy -1.472 3.178)
        (xy -1.496 3.19)
        (xy -1.526 3.198)
        (xy -1.563 3.202)
        (xy -1.578 3.203)
        (xy -1.603 3.203)
        (xy -1.627 3.203)
        (xy -1.647 3.201)
        (xy -1.656 3.2)
        (xy -1.686 3.191)
        (xy -1.717 3.176)
        (xy -1.746 3.159)
        (xy -1.765 3.143)
        (xy -1.79 3.111)
        (xy -1.807 3.075)
        (xy -1.816 3.037)
        (xy -1.817 2.998)
        (xy -1.817 2.997)
        (xy -1.697 2.997)
        (xy -1.696 3.02)
        (xy -1.687 3.042)
        (xy -1.67 3.06)
        (xy -1.668 3.062)
        (xy -1.654 3.07)
        (xy -1.64 3.076)
        (xy -1.624 3.08)
        (xy -1.602 3.081)
        (xy -1.574 3.082)
        (xy -1.558 3.082)
        (xy -1.529 3.081)
        (xy -1.508 3.08)
        (xy -1.494 3.078)
        (xy -1.483 3.075)
        (xy -1.474 3.07)
        (xy -1.458 3.058)
        (xy -1.447 3.041)
        (xy -1.44 3.017)
        (xy -1.435 2.985)
        (xy -1.435 2.977)
        (xy -1.432 2.931)
        (xy -1.533 2.931)
        (xy -1.568 2.931)
        (xy -1.595 2.931)
        (xy -1.615 2.932)
        (xy -1.63 2.934)
        (xy -1.641 2.936)
        (xy -1.65 2.938)
        (xy -1.655 2.941)
        (xy -1.676 2.955)
        (xy -1.69 2.974)
        (xy -1.697 2.997)
        (xy -1.817 2.997)
        (xy -1.811 2.96)
        (xy -1.797 2.924)
        (xy -1.775 2.892)
        (xy -1.747 2.864)
        (xy -1.715 2.845)
        (xy -1.7 2.838)
        (xy -1.685 2.833)
        (xy -1.668 2.83)
        (xy -1.648 2.827)
        (xy -1.623 2.825)
        (xy -1.591 2.824)
        (xy -1.551 2.824)
        (xy -1.54 2.824)
        (xy -1.432 2.824)
        (xy -1.434 2.776)
        (xy -1.436 2.747)
        (xy -1.441 2.726)
        (xy -1.448 2.711)
        (xy -1.46 2.699)
        (xy -1.474 2.689)
        (xy -1.483 2.685)
        (xy -1.492 2.682)
        (xy -1.505 2.68)
        (xy -1.524 2.68)
        (xy -1.55 2.679)
        (xy -1.56 2.679)
        (xy -1.594 2.68)
        (xy -1.62 2.682)
        (xy -1.639 2.686)
        (xy -1.654 2.692)
        (xy -1.666 2.701)
        (xy -1.675 2.711)
        (xy -1.686 2.724)
        (xy -1.735 2.686)
        (xy -1.754 2.672)
        (xy -1.769 2.659)
        (xy -1.78 2.65)
        (xy -1.784 2.646)
        (xy -1.78 2.64)
        (xy -1.77 2.629)
        (xy -1.756 2.616)
        (xy -1.74 2.604)
        (xy -1.724 2.592)
        (xy -1.711 2.584)
        (xy -1.71 2.583)
        (xy -1.688 2.574)
        (xy -1.668 2.566)
        (xy -1.647 2.562)
        (xy -1.623 2.559)
        (xy -1.593 2.558)
        (xy -1.565 2.558)
        (xy -1.521 2.559)
      )

      (stroke (width 0.01) (type solid)) (fill solid) (layer "F.Mask"))
    (fp_poly
      (pts
        (xy 0.035 2.777)
        (xy 0.047 2.822)
        (xy 0.059 2.864)
        (xy 0.069 2.903)
        (xy 0.078 2.936)
        (xy 0.086 2.963)
        (xy 0.092 2.984)
        (xy 0.095 2.996)
        (xy 0.096 2.999)
        (xy 0.098 2.999)
        (xy 0.103 2.991)
        (xy 0.109 2.975)
        (xy 0.118 2.95)
        (xy 0.129 2.917)
        (xy 0.143 2.874)
        (xy 0.152 2.849)
        (xy 0.165 2.807)
        (xy 0.179 2.766)
        (xy 0.192 2.726)
        (xy 0.204 2.689)
        (xy 0.214 2.658)
        (xy 0.221 2.634)
        (xy 0.224 2.627)
        (xy 0.244 2.565)
        (xy 0.338 2.565)
        (xy 0.406 2.774)
        (xy 0.42 2.819)
        (xy 0.434 2.861)
        (xy 0.446 2.899)
        (xy 0.457 2.932)
        (xy 0.466 2.96)
        (xy 0.473 2.981)
        (xy 0.477 2.993)
        (xy 0.478 2.997)
        (xy 0.48 2.998)
        (xy 0.482 2.996)
        (xy 0.485 2.99)
        (xy 0.49 2.978)
        (xy 0.495 2.96)
        (xy 0.502 2.936)
        (xy 0.511 2.905)
        (xy 0.523 2.865)
        (xy 0.536 2.817)
        (xy 0.543 2.789)
        (xy 0.556 2.744)
        (xy 0.568 2.701)
        (xy 0.578 2.663)
        (xy 0.587 2.629)
        (xy 0.595 2.602)
        (xy 0.601 2.582)
        (xy 0.605 2.57)
        (xy 0.606 2.567)
        (xy 0.611 2.566)
        (xy 0.625 2.566)
        (xy 0.645 2.566)
        (xy 0.669 2.566)
        (xy 0.673 2.566)
        (xy 0.739 2.567)
        (xy 0.656 2.827)
        (xy 0.64 2.878)
        (xy 0.624 2.928)
        (xy 0.609 2.976)
        (xy 0.595 3.02)
        (xy 0.582 3.06)
        (xy 0.571 3.094)
        (xy 0.563 3.121)
        (xy 0.557 3.139)
        (xy 0.556 3.143)
        (xy 0.538 3.2)
        (xy 0.425 3.197)
        (xy 0.358 2.975)
        (xy 0.341 2.917)
        (xy 0.327 2.87)
        (xy 0.315 2.831)
        (xy 0.305 2.801)
        (xy 0.297 2.78)
        (xy 0.292 2.766)
        (xy 0.289 2.761)
        (xy 0.288 2.761)
        (xy 0.286 2.768)
        (xy 0.281 2.783)
        (xy 0.274 2.806)
        (xy 0.265 2.836)
        (xy 0.254 2.871)
        (xy 0.242 2.911)
        (xy 0.23 2.953)
        (xy 0.223 2.976)
        (xy 0.21 3.02)
        (xy 0.197 3.062)
        (xy 0.186 3.099)
        (xy 0.177 3.132)
        (xy 0.169 3.158)
        (xy 0.163 3.177)
        (xy 0.16 3.189)
        (xy 0.159 3.191)
        (xy 0.157 3.195)
        (xy 0.151 3.198)
        (xy 0.141 3.199)
        (xy 0.124 3.2)
        (xy 0.101 3.2)
        (xy 0.073 3.199)
        (xy 0.055 3.198)
        (xy 0.045 3.196)
        (xy 0.043 3.194)
        (xy 0.041 3.188)
        (xy 0.036 3.173)
        (xy 0.029 3.15)
        (xy 0.019 3.121)
        (xy 0.008 3.084)
        (xy -0.006 3.043)
        (xy -0.02 2.996)
        (xy -0.036 2.946)
        (xy -0.053 2.893)
        (xy -0.057 2.883)
        (xy -0.074 2.83)
        (xy -0.09 2.779)
        (xy -0.105 2.732)
        (xy -0.119 2.689)
        (xy -0.131 2.652)
        (xy -0.141 2.621)
        (xy -0.148 2.596)
        (xy -0.154 2.58)
        (xy -0.156 2.572)
        (xy -0.156 2.569)
        (xy -0.151 2.567)
        (xy -0.14 2.566)
        (xy -0.123 2.565)
        (xy -0.096 2.565)
        (xy -0.091 2.565)
        (xy -0.023 2.565)
        (xy 0.035 2.777)
      )

      (stroke (width 0.01) (type solid)) (fill solid) (layer "F.Mask"))
    (fp_poly
      (pts
        (xy -2.065 1.559)
        (xy -2.024 1.576)
        (xy -1.986 1.601)
        (xy -1.973 1.612)
        (xy -1.957 1.63)
        (xy -1.943 1.649)
        (xy -1.932 1.668)
        (xy -1.924 1.69)
        (xy -1.918 1.716)
        (xy -1.914 1.747)
        (xy -1.911 1.785)
        (xy -1.91 1.831)
        (xy -1.91 1.877)
        (xy -1.91 1.93)
        (xy -1.912 1.974)
        (xy -1.914 2.011)
        (xy -1.919 2.041)
        (xy -1.925 2.067)
        (xy -1.934 2.088)
        (xy -1.945 2.107)
        (xy -1.959 2.125)
        (xy -1.972 2.139)
        (xy -1.993 2.157)
        (xy -2.018 2.173)
        (xy -2.031 2.18)
        (xy -2.047 2.188)
        (xy -2.06 2.192)
        (xy -2.074 2.195)
        (xy -2.091 2.196)
        (xy -2.114 2.197)
        (xy -2.122 2.197)
        (xy -2.147 2.196)
        (xy -2.165 2.195)
        (xy -2.179 2.193)
        (xy -2.191 2.189)
        (xy -2.205 2.183)
        (xy -2.21 2.18)
        (xy -2.231 2.169)
        (xy -2.251 2.156)
        (xy -2.265 2.146)
        (xy -2.286 2.127)
        (xy -2.286 2.627)
        (xy -2.266 2.608)
        (xy -2.248 2.595)
        (xy -2.227 2.582)
        (xy -2.217 2.577)
        (xy -2.173 2.562)
        (xy -2.129 2.556)
        (xy -2.086 2.559)
        (xy -2.045 2.57)
        (xy -2.007 2.589)
        (xy -1.974 2.616)
        (xy -1.946 2.648)
        (xy -1.926 2.687)
        (xy -1.919 2.707)
        (xy -1.917 2.715)
        (xy -1.915 2.724)
        (xy -1.914 2.737)
        (xy -1.913 2.753)
        (xy -1.912 2.774)
        (xy -1.911 2.8)
        (xy -1.911 2.833)
        (xy -1.911 2.874)
        (xy -1.911 2.923)
        (xy -1.911 2.967)
        (xy -1.911 3.2)
        (xy -2.035 3.197)
        (xy -2.038 2.984)
        (xy -2.038 2.932)
        (xy -2.039 2.889)
        (xy -2.039 2.854)
        (xy -2.04 2.826)
        (xy -2.041 2.805)
        (xy -2.042 2.788)
        (xy -2.043 2.776)
        (xy -2.045 2.767)
        (xy -2.046 2.76)
        (xy -2.049 2.755)
        (xy -2.051 2.75)
        (xy -2.072 2.721)
        (xy -2.098 2.701)
        (xy -2.128 2.688)
        (xy -2.161 2.683)
        (xy -2.195 2.687)
        (xy -2.22 2.697)
        (xy -2.24 2.71)
        (xy -2.259 2.729)
        (xy -2.274 2.75)
        (xy -2.278 2.757)
        (xy -2.28 2.765)
        (xy -2.281 2.781)
        (xy -2.283 2.806)
        (xy -2.284 2.839)
        (xy -2.285 2.881)
        (xy -2.286 2.933)
        (xy -2.286 2.984)
        (xy -2.289 3.197)
        (xy -2.413 3.2)
        (xy -2.413 1.877)
        (xy -2.286 1.877)
        (xy -2.285 1.926)
        (xy -2.281 1.966)
        (xy -2.274 1.998)
        (xy -2.262 2.024)
        (xy -2.247 2.043)
        (xy -2.228 2.058)
        (xy -2.215 2.064)
        (xy -2.194 2.07)
        (xy -2.168 2.072)
        (xy -2.141 2.071)
        (xy -2.117 2.066)
        (xy -2.106 2.063)
        (xy -2.079 2.044)
        (xy -2.058 2.019)
        (xy -2.05 2.001)
        (xy -2.045 1.984)
        (xy -2.042 1.959)
        (xy -2.04 1.929)
        (xy -2.038 1.895)
        (xy -2.038 1.861)
        (xy -2.039 1.829)
        (xy -2.041 1.8)
        (xy -2.044 1.777)
        (xy -2.045 1.772)
        (xy -2.057 1.738)
        (xy -2.073 1.712)
        (xy -2.094 1.695)
        (xy -2.122 1.684)
        (xy -2.156 1.681)
        (xy -2.159 1.681)
        (xy -2.192 1.683)
        (xy -2.22 1.691)
        (xy -2.243 1.705)
        (xy -2.26 1.725)
        (xy -2.273 1.753)
        (xy -2.281 1.788)
        (xy -2.285 1.832)
        (xy -2.286 1.877)
        (xy -2.413 1.877)
        (xy -2.413 1.559)
        (xy -2.286 1.559)
        (xy -2.286 1.62)
        (xy -2.26 1.6)
        (xy -2.225 1.577)
        (xy -2.19 1.563)
        (xy -2.154 1.554)
        (xy -2.109 1.552)
        (xy -2.065 1.559)
      )

      (stroke (width 0.01) (type solid)) (fill solid) (layer "F.Mask"))
    (fp_poly
      (pts
        (xy 0.063 -3.201)
        (xy 0.118 -3.201)
        (xy 0.164 -3.201)
        (xy 0.202 -3.2)
        (xy 0.233 -3.2)
        (xy 0.258 -3.2)
        (xy 0.277 -3.199)
        (xy 0.292 -3.198)
        (xy 0.302 -3.197)
        (xy 0.309 -3.196)
        (xy 0.314 -3.195)
        (xy 0.317 -3.193)
        (xy 0.319 -3.192)
        (xy 0.321 -3.189)
        (xy 0.324 -3.183)
        (xy 0.327 -3.174)
        (xy 0.33 -3.161)
        (xy 0.334 -3.144)
        (xy 0.339 -3.12)
        (xy 0.345 -3.091)
        (xy 0.352 -3.054)
        (xy 0.361 -3.01)
        (xy 0.371 -2.958)
        (xy 0.382 -2.897)
        (xy 0.385 -2.878)
        (xy 0.395 -2.824)
        (xy 0.405 -2.772)
        (xy 0.414 -2.724)
        (xy 0.423 -2.68)
        (xy 0.43 -2.642)
        (xy 0.437 -2.61)
        (xy 0.442 -2.586)
        (xy 0.446 -2.569)
        (xy 0.448 -2.562)
        (xy 0.456 -2.55)
        (xy 0.464 -2.544)
        (xy 0.476 -2.539)
        (xy 0.495 -2.53)
        (xy 0.521 -2.519)
        (xy 0.552 -2.506)
        (xy 0.587 -2.492)
        (xy 0.624 -2.477)
        (xy 0.664 -2.461)
        (xy 0.704 -2.445)
        (xy 0.743 -2.43)
        (xy 0.78 -2.415)
        (xy 0.814 -2.402)
        (xy 0.843 -2.391)
        (xy 0.868 -2.382)
        (xy 0.885 -2.376)
        (xy 0.895 -2.373)
        (xy 0.896 -2.373)
        (xy 0.911 -2.376)
        (xy 0.931 -2.386)
        (xy 0.948 -2.397)
        (xy 0.962 -2.406)
        (xy 0.983 -2.421)
        (xy 1.011 -2.44)
        (xy 1.043 -2.462)
        (xy 1.079 -2.487)
        (xy 1.118 -2.513)
        (xy 1.158 -2.541)
        (xy 1.198 -2.568)
        (xy 1.238 -2.595)
        (xy 1.275 -2.621)
        (xy 1.309 -2.644)
        (xy 1.338 -2.665)
        (xy 1.362 -2.681)
        (xy 1.377 -2.691)
        (xy 1.398 -2.705)
        (xy 1.418 -2.717)
        (xy 1.433 -2.725)
        (xy 1.442 -2.728)
        (xy 1.443 -2.728)
        (xy 1.448 -2.726)
        (xy 1.456 -2.72)
        (xy 1.468 -2.71)
        (xy 1.486 -2.694)
        (xy 1.508 -2.673)
        (xy 1.535 -2.647)
        (xy 1.568 -2.614)
        (xy 1.608 -2.575)
        (xy 1.654 -2.53)
        (xy 1.675 -2.509)
        (xy 1.721 -2.462)
        (xy 1.761 -2.422)
        (xy 1.794 -2.388)
        (xy 1.822 -2.36)
        (xy 1.844 -2.337)
        (xy 1.862 -2.318)
        (xy 1.875 -2.304)
        (xy 1.884 -2.293)
        (xy 1.89 -2.284)
        (xy 1.893 -2.279)
        (xy 1.894 -2.275)
        (xy 1.892 -2.269)
        (xy 1.886 -2.257)
        (xy 1.875 -2.239)
        (xy 1.86 -2.215)
        (xy 1.839 -2.183)
        (xy 1.814 -2.145)
        (xy 1.783 -2.1)
        (xy 1.747 -2.046)
        (xy 1.721 -2.009)
        (xy 1.69 -1.964)
        (xy 1.661 -1.921)
        (xy 1.634 -1.88)
        (xy 1.609 -1.844)
        (xy 1.588 -1.811)
        (xy 1.57 -1.785)
        (xy 1.557 -1.764)
        (xy 1.549 -1.75)
        (xy 1.546 -1.743)
        (xy 1.547 -1.735)
        (xy 1.552 -1.719)
        (xy 1.56 -1.696)
        (xy 1.571 -1.667)
        (xy 1.585 -1.634)
        (xy 1.6 -1.597)
        (xy 1.616 -1.557)
        (xy 1.633 -1.516)
        (xy 1.651 -1.476)
        (xy 1.668 -1.436)
        (xy 1.685 -1.398)
        (xy 1.701 -1.363)
        (xy 1.715 -1.333)
        (xy 1.727 -1.309)
        (xy 1.736 -1.291)
        (xy 1.742 -1.281)
        (xy 1.744 -1.279)
        (xy 1.751 -1.277)
        (xy 1.767 -1.273)
        (xy 1.791 -1.268)
        (xy 1.822 -1.261)
        (xy 1.86 -1.254)
        (xy 1.903 -1.245)
        (xy 1.951 -1.236)
        (xy 2.002 -1.226)
        (xy 2.049 -1.217)
        (xy 2.103 -1.207)
        (xy 2.154 -1.198)
        (xy 2.201 -1.188)
        (xy 2.244 -1.18)
        (xy 2.281 -1.173)
        (xy 2.311 -1.166)
        (xy 2.335 -1.161)
        (xy 2.35 -1.157)
        (xy 2.355 -1.156)
        (xy 2.367 -1.148)
        (xy 2.367 -0.834)
        (xy 2.367 -0.768)
        (xy 2.367 -0.712)
        (xy 2.367 -0.664)
        (xy 2.366 -0.625)
        (xy 2.366 -0.592)
        (xy 2.365 -0.566)
        (xy 2.364 -0.546)
        (xy 2.363 -0.531)
        (xy 2.361 -0.52)
        (xy 2.358 -0.512)
        (xy 2.355 -0.507)
        (xy 2.352 -0.504)
        (xy 2.348 -0.503)
        (xy 2.343 -0.501)
        (xy 2.34 -0.501)
        (xy 2.333 -0.499)
        (xy 2.317 -0.496)
        (xy 2.293 -0.492)
        (xy 2.261 -0.486)
        (xy 2.224 -0.479)
        (xy 2.181 -0.471)
        (xy 2.134 -0.462)
        (xy 2.084 -0.453)
        (xy 2.054 -0.448)
        (xy 2.002 -0.438)
        (xy 1.953 -0.429)
        (xy 1.907 -0.42)
        (xy 1.866 -0.412)
        (xy 1.831 -0.404)
        (xy 1.802 -0.398)
        (xy 1.78 -0.394)
        (xy 1.767 -0.391)
        (xy 1.764 -0.39)
        (xy 1.76 -0.387)
        (xy 1.757 -0.384)
        (xy 1.753 -0.379)
        (xy 1.748 -0.371)
        (xy 1.742 -0.36)
        (xy 1.735 -0.344)
        (xy 1.726 -0.324)
        (xy 1.715 -0.297)
        (xy 1.701 -0.264)
        (xy 1.685 -0.223)
        (xy 1.665 -0.174)
        (xy 1.653 -0.145)
        (xy 1.63 -0.086)
        (xy 1.61 -0.037)
        (xy 1.594 0.005)
        (xy 1.582 0.038)
        (xy 1.572 0.064)
        (xy 1.566 0.084)
        (xy 1.562 0.097)
        (xy 1.561 0.104)
        (xy 1.562 0.105)
        (xy 1.565 0.111)
        (xy 1.574 0.125)
        (xy 1.587 0.146)
        (xy 1.604 0.173)
        (xy 1.626 0.205)
        (xy 1.65 0.241)
        (xy 1.677 0.281)
        (xy 1.706 0.324)
        (xy 1.729 0.358)
        (xy 1.768 0.413)
        (xy 1.8 0.461)
        (xy 1.827 0.502)
        (xy 1.85 0.535)
        (xy 1.867 0.562)
        (xy 1.88 0.583)
        (xy 1.889 0.598)
        (xy 1.893 0.608)
        (xy 1.894 0.612)
        (xy 1.893 0.616)
        (xy 1.89 0.622)
        (xy 1.885 0.63)
        (xy 1.876 0.64)
        (xy 1.863 0.655)
        (xy 1.846 0.673)
        (xy 1.825 0.695)
        (xy 1.798 0.723)
        (xy 1.765 0.756)
        (xy 1.727 0.795)
        (xy 1.682 0.839)
        (xy 1.635 0.886)
        (xy 1.595 0.926)
        (xy 1.561 0.96)
        (xy 1.532 0.989)
        (xy 1.508 1.012)
        (xy 1.488 1.03)
        (xy 1.473 1.044)
        (xy 1.461 1.054)
        (xy 1.452 1.061)
        (xy 1.445 1.065)
        (xy 1.44 1.066)
        (xy 1.438 1.066)
        (xy 1.433 1.064)
        (xy 1.421 1.055)
        (xy 1.401 1.043)
        (xy 1.376 1.026)
        (xy 1.345 1.005)
        (xy 1.31 0.981)
        (xy 1.27 0.954)
        (xy 1.228 0.925)
        (xy 1.193 0.901)
        (xy 1.138 0.864)
        (xy 1.089 0.83)
        (xy 1.046 0.802)
        (xy 1.01 0.778)
        (xy 0.981 0.759)
        (xy 0.96 0.746)
        (xy 0.946 0.738)
        (xy 0.94 0.736)
        (xy 0.932 0.738)
        (xy 0.917 0.745)
        (xy 0.895 0.755)
        (xy 0.869 0.768)
        (xy 0.84 0.783)
        (xy 0.816 0.795)
        (xy 0.781 0.814)
        (xy 0.753 0.828)
        (xy 0.732 0.838)
        (xy 0.717 0.845)
        (xy 0.707 0.849)
        (xy 0.699 0.85)
        (xy 0.694 0.849)
        (xy 0.691 0.847)
        (xy 0.687 0.84)
        (xy 0.682 0.829)
        (xy 0.674 0.814)
        (xy 0.665 0.793)
        (xy 0.653 0.767)
        (xy 0.639 0.735)
        (xy 0.623 0.696)
        (xy 0.604 0.651)
        (xy 0.582 0.598)
        (xy 0.556 0.538)
        (xy 0.528 0.469)
        (xy 0.496 0.391)
        (xy 0.47 0.329)
        (xy 0.436 0.247)
        (xy 0.406 0.173)
        (xy 0.379 0.108)
        (xy 0.355 0.05)
        (xy 0.335 0)
        (xy 0.317 -0.043)
        (xy 0.303 -0.079)
        (xy 0.291 -0.11)
        (xy 0.281 -0.135)
        (xy 0.273 -0.155)
        (xy 0.268 -0.171)
        (xy 0.264 -0.183)
        (xy 0.262 -0.191)
        (xy 0.262 -0.196)
        (xy 0.262 -0.198)
        (xy 0.269 -0.207)
        (xy 0.283 -0.219)
        (xy 0.302 -0.233)
        (xy 0.303 -0.234)
        (xy 0.354 -0.268)
        (xy 0.398 -0.3)
        (xy 0.435 -0.331)
        (xy 0.469 -0.363)
        (xy 0.5 -0.397)
        (xy 0.507 -0.405)
        (xy 0.556 -0.472)
        (xy 0.596 -0.543)
        (xy 0.627 -0.619)
        (xy 0.643 -0.672)
        (xy 0.651 -0.718)
        (xy 0.657 -0.77)
        (xy 0.66 -0.824)
        (xy 0.659 -0.878)
        (xy 0.654 -0.927)
        (xy 0.652 -0.936)
        (xy 0.634 -1.015)
        (xy 0.607 -1.09)
        (xy 0.571 -1.161)
        (xy 0.528 -1.227)
        (xy 0.477 -1.287)
        (xy 0.419 -1.341)
        (xy 0.355 -1.387)
        (xy 0.285 -1.426)
        (xy 0.21 -1.456)
        (xy 0.205 -1.458)
        (xy 0.131 -1.477)
        (xy 0.054 -1.487)
        (xy -0.025 -1.489)
        (xy -0.103 -1.482)
        (xy -0.178 -1.466)
        (xy -0.206 -1.458)
        (xy -0.281 -1.428)
        (xy -0.351 -1.39)
        (xy -0.416 -1.344)
        (xy -0.474 -1.29)
        (xy -0.526 -1.23)
        (xy -0.571 -1.164)
        (xy -0.607 -1.093)
        (xy -0.63 -1.034)
        (xy -0.649 -0.96)
        (xy -0.659 -0.883)
        (xy -0.661 -0.804)
        (xy -0.654 -0.726)
        (xy -0.638 -0.651)
        (xy -0.63 -0.623)
        (xy -0.618 -0.591)
        (xy -0.602 -0.554)
        (xy -0.584 -0.518)
        (xy -0.566 -0.485)
        (xy -0.553 -0.463)
        (xy -0.509 -0.407)
        (xy -0.457 -0.352)
        (xy -0.397 -0.299)
        (xy -0.33 -0.25)
        (xy -0.289 -0.224)
        (xy -0.273 -0.212)
        (xy -0.263 -0.2)
        (xy -0.262 -0.197)
        (xy -0.263 -0.19)
        (xy -0.268 -0.175)
        (xy -0.277 -0.151)
        (xy -0.288 -0.121)
        (xy -0.302 -0.084)
        (xy -0.319 -0.042)
        (xy -0.338 0.005)
        (xy -0.358 0.056)
        (xy -0.381 0.111)
        (xy -0.404 0.168)
        (xy -0.428 0.228)
        (xy -0.453 0.288)
        (xy -0.478 0.349)
        (xy -0.504 0.41)
        (xy -0.529 0.47)
        (xy -0.553 0.527)
        (xy -0.576 0.583)
        (xy -0.598 0.635)
        (xy -0.619 0.683)
        (xy -0.638 0.727)
        (xy -0.655 0.765)
        (xy -0.669 0.797)
        (xy -0.68 0.822)
        (xy -0.689 0.839)
        (xy -0.694 0.848)
        (xy -0.695 0.849)
        (xy -0.699 0.85)
        (xy -0.706 0.849)
        (xy -0.717 0.845)
        (xy -0.732 0.839)
        (xy -0.752 0.829)
        (xy -0.779 0.815)
        (xy -0.814 0.797)
        (xy -0.817 0.795)
        (xy -0.848 0.779)
        (xy -0.877 0.764)
        (xy -0.902 0.752)
        (xy -0.922 0.743)
        (xy -0.936 0.737)
        (xy -0.941 0.736)
        (xy -0.949 0.739)
        (xy -0.964 0.748)
        (xy -0.987 0.761)
        (xy -1.015 0.78)
        (xy -1.05 0.803)
        (xy -1.072 0.818)
        (xy -1.138 0.863)
        (xy -1.195 0.903)
        (xy -1.245 0.937)
        (xy -1.289 0.966)
        (xy -1.325 0.991)
        (xy -1.356 1.012)
        (xy -1.381 1.029)
        (xy -1.401 1.042)
        (xy -1.416 1.052)
        (xy -1.427 1.059)
        (xy -1.435 1.064)
        (xy -1.439 1.066)
        (xy -1.44 1.066)
        (xy -1.449 1.064)
        (xy -1.453 1.061)
        (xy -1.458 1.057)
        (xy -1.47 1.046)
        (xy -1.487 1.029)
        (xy -1.509 1.007)
        (xy -1.537 0.98)
        (xy -1.568 0.95)
        (xy -1.602 0.915)
        (xy -1.639 0.879)
        (xy -1.678 0.84)
        (xy -1.678 0.839)
        (xy -1.726 0.792)
        (xy -1.767 0.751)
        (xy -1.801 0.716)
        (xy -1.829 0.687)
        (xy -1.852 0.663)
        (xy -1.869 0.644)
        (xy -1.882 0.63)
        (xy -1.89 0.62)
        (xy -1.894 0.613)
        (xy -1.895 0.61)
        (xy -1.892 0.603)
        (xy -1.884 0.588)
        (xy -1.87 0.565)
        (xy -1.85 0.536)
        (xy -1.826 0.499)
        (xy -1.797 0.455)
        (xy -1.763 0.405)
        (xy -1.73 0.358)
        (xy -1.7 0.313)
        (xy -1.671 0.271)
        (xy -1.645 0.232)
        (xy -1.621 0.197)
        (xy -1.601 0.166)
        (xy -1.584 0.141)
        (xy -1.572 0.121)
        (xy -1.565 0.109)
        (xy -1.563 0.105)
        (xy -1.563 0.099)
        (xy -1.566 0.087)
        (xy -1.572 0.07)
        (xy -1.58 0.045)
        (xy -1.592 0.013)
        (xy -1.607 -0.026)
        (xy -1.626 -0.074)
        (xy -1.648 -0.13)
        (xy -1.654 -0.145)
        (xy -1.676 -0.199)
        (xy -1.695 -0.245)
        (xy -1.71 -0.282)
        (xy -1.723 -0.313)
        (xy -1.733 -0.337)
        (xy -1.741 -0.356)
        (xy -1.748 -0.369)
        (xy -1.753 -0.379)
        (xy -1.758 -0.385)
        (xy -1.761 -0.388)
        (xy -1.763 -0.389)
        (xy -1.767 -0.39)
        (xy -1.774 -0.392)
        (xy -1.784 -0.395)
        (xy -1.799 -0.398)
        (xy -1.818 -0.402)
        (xy -1.843 -0.407)
        (xy -1.873 -0.413)
        (xy -1.91 -0.42)
        (xy -1.954 -0.429)
        (xy -2.005 -0.438)
        (xy -2.065 -0.449)
        (xy -2.133 -0.462)
        (xy -2.211 -0.477)
        (xy -2.22 -0.478)
        (xy -2.26 -0.486)
        (xy -2.29 -0.491)
        (xy -2.313 -0.496)
        (xy -2.33 -0.499)
        (xy -2.341 -0.502)
        (xy -2.349 -0.504)
        (xy -2.353 -0.506)
        (xy -2.356 -0.508)
        (xy -2.359 -0.51)
        (xy -2.36 -0.511)
        (xy -2.361 -0.514)
        (xy -2.363 -0.518)
        (xy -2.364 -0.526)
        (xy -2.365 -0.536)
        (xy -2.366 -0.551)
        (xy -2.366 -0.571)
        (xy -2.367 -0.597)
        (xy -2.367 -0.629)
        (xy -2.368 -0.668)
        (xy -2.368 -0.715)
        (xy -2.368 -0.771)
        (xy -2.368 -0.834)
        (xy -2.368 -1.148)
        (xy -2.356 -1.155)
        (xy -2.349 -1.158)
        (xy -2.333 -1.162)
        (xy -2.309 -1.167)
        (xy -2.278 -1.173)
        (xy -2.24 -1.181)
        (xy -2.197 -1.189)
        (xy -2.149 -1.198)
        (xy -2.098 -1.208)
        (xy -2.051 -1.217)
        (xy -1.996 -1.227)
        (xy -1.945 -1.237)
        (xy -1.897 -1.246)
        (xy -1.854 -1.254)
        (xy -1.817 -1.262)
        (xy -1.787 -1.268)
        (xy -1.764 -1.273)
        (xy -1.75 -1.277)
        (xy -1.745 -1.279)
        (xy -1.741 -1.285)
        (xy -1.733 -1.3)
        (xy -1.722 -1.322)
        (xy -1.709 -1.35)
        (xy -1.694 -1.382)
        (xy -1.677 -1.419)
        (xy -1.66 -1.458)
        (xy -1.642 -1.498)
        (xy -1.625 -1.539)
        (xy -1.608 -1.58)
        (xy -1.592 -1.618)
        (xy -1.578 -1.653)
        (xy -1.565 -1.684)
        (xy -1.556 -1.709)
        (xy -1.549 -1.729)
        (xy -1.546 -1.74)
        (xy -1.546 -1.742)
        (xy -1.549 -1.749)
        (xy -1.558 -1.763)
        (xy -1.571 -1.784)
        (xy -1.588 -1.811)
        (xy -1.61 -1.843)
        (xy -1.634 -1.88)
        (xy -1.661 -1.92)
        (xy -1.691 -1.963)
        (xy -1.722 -2.008)
        (xy -1.762 -2.067)
        (xy -1.796 -2.117)
        (xy -1.825 -2.16)
        (xy -1.848 -2.196)
        (xy -1.867 -2.225)
        (xy -1.881 -2.247)
        (xy -1.89 -2.262)
        (xy -1.895 -2.272)
        (xy -1.895 -2.275)
        (xy -1.894 -2.279)
        (xy -1.891 -2.285)
        (xy -1.884 -2.293)
        (xy -1.875 -2.305)
        (xy -1.861 -2.32)
        (xy -1.843 -2.339)
        (xy -1.82 -2.363)
        (xy -1.792 -2.392)
        (xy -1.758 -2.426)
        (xy -1.718 -2.466)
        (xy -1.676 -2.509)
        (xy -1.627 -2.557)
        (xy -1.585 -2.599)
        (xy -1.549 -2.634)
        (xy -1.52 -2.663)
        (xy -1.495 -2.686)
        (xy -1.476 -2.704)
        (xy -1.462 -2.716)
        (xy -1.452 -2.724)
        (xy -1.446 -2.728)
        (xy -1.444 -2.728)
        (xy -1.437 -2.726)
        (xy -1.423 -2.717)
        (xy -1.401 -2.703)
        (xy -1.372 -2.685)
        (xy -1.337 -2.661)
        (xy -1.295 -2.634)
        (xy -1.248 -2.602)
        (xy -1.196 -2.566)
        (xy -1.173 -2.551)
        (xy -1.118 -2.513)
        (xy -1.071 -2.481)
        (xy -1.031 -2.454)
        (xy -0.998 -2.432)
        (xy -0.97 -2.413)
        (xy -0.948 -2.399)
        (xy -0.931 -2.389)
        (xy -0.917 -2.381)
        (xy -0.907 -2.376)
        (xy -0.901 -2.373)
        (xy -0.897 -2.373)
        (xy -0.888 -2.375)
        (xy -0.87 -2.38)
        (xy -0.845 -2.39)
        (xy -0.813 -2.402)
        (xy -0.774 -2.417)
        (xy -0.73 -2.434)
        (xy -0.681 -2.454)
        (xy -0.629 -2.475)
        (xy -0.586 -2.493)
        (xy -0.55 -2.508)
        (xy -0.522 -2.52)
        (xy -0.499 -2.529)
        (xy -0.482 -2.537)
        (xy -0.47 -2.543)
        (xy -0.461 -2.548)
        (xy -0.455 -2.551)
        (xy -0.452 -2.554)
        (xy -0.449 -2.557)
        (xy -0.448 -2.56)
        (xy -0.447 -2.566)
        (xy -0.443 -2.582)
        (xy -0.438 -2.605)
        (xy -0.432 -2.637)
        (xy -0.425 -2.674)
        (xy -0.417 -2.717)
        (xy -0.407 -2.765)
        (xy -0.398 -2.817)
        (xy -0.388 -2.871)
        (xy -0.387 -2.876)
        (xy -0.375 -2.94)
        (xy -0.364 -2.995)
        (xy -0.356 -3.042)
        (xy -0.348 -3.081)
        (xy -0.342 -3.112)
        (xy -0.337 -3.137)
        (xy -0.332 -3.157)
        (xy -0.328 -3.171)
        (xy -0.325 -3.181)
        (xy -0.323 -3.188)
        (xy -0.32 -3.191)
        (xy -0.32 -3.192)
        (xy -0.317 -3.194)
        (xy -0.313 -3.195)
        (xy -0.307 -3.197)
        (xy -0.298 -3.198)
        (xy -0.286 -3.199)
        (xy -0.269 -3.199)
        (xy -0.247 -3.2)
        (xy -0.219 -3.2)
        (xy -0.184 -3.201)
        (xy -0.142 -3.201)
        (xy -0.092 -3.201)
        (xy -0.033 -3.201)
        (xy -0.001 -3.201)
        (xy 0.063 -3.201)
      )

      (stroke (width 0.01) (type solid)) (fill solid) (layer "F.Mask"))
  )

  (footprint "sdi-mipi-bridge-footprints:R_0402_1005Metric" (layer "F.Cu")
    (at 127 107.4 -90)
    (descr "Resistor SMD 0402")
    (tags "resistor SMD 0402")
    (property "Author" "Antmicro")
    (property "License" "Apache-2.0")
    (property "MPN" "CR0402-FX-1000GLF")
    (property "Manufacturer" "Bourns")
    (property "Sheetfile" "sdi-mipi-bridge.kicad_sch")
    (property "Sheetname" "")
    (property "Tolerance" "1%")
    (property "Val" "100R")
    (property "ki_description" "100R resistor in 0402 package with 1% tolerance")
    (attr smd)
    (fp_text reference "R93" (at 0.9 0.6 -90) (layer "F.SilkS")
        (effects (font (size 0.65 0.65) (thickness 0.15)) (justify left bottom))
    )
    (fp_text value "R_100R_0402" (at 0 1.4 -90) (layer "F.Fab") hide
        (effects (font (size 0.7 0.7) (thickness 0.15)) (justify left bottom))
    )
    (fp_text user "Author: Antmicro" (at -0.95 4.169 -90) (layer "F.Fab") hide
        (effects (font (size 0.7 0.7) (thickness 0.15)) (justify left bottom))
    )
    (fp_text user "License: Apache-2.0" (at -0.95 5.169 -90) (layer "F.Fab") hide
        (effects (font (size 0.7 0.7) (thickness 0.15)) (justify left bottom))
    )
    (fp_text user "${REFERENCE}" (at -0.95 3.168 -90) (layer "F.Fab") hide
        (effects (font (size 0.7 0.7) (thickness 0.15)) (justify left bottom))
    )
    (fp_rect (start -0.93 -0.47) (end 0.93 0.47)
      (stroke (width 0.05) (type solid)) (fill none) (layer "F.CrtYd"))
    (fp_rect (start -0.5 -0.25) (end 0.5 0.25)
      (stroke (width 0.15) (type solid)) (fill none) (layer "F.Fab"))
    (pad "1" smd roundrect (at -0.485 0 270) (size 0.59 0.64) (layers "F.Cu" "F.Paste" "F.Mask") (roundrect_rratio 0.25)
      (net 91 "Net-(D4-Pad1)") (pintype "passive"))
    (pad "2" smd roundrect (at 0.485 0 270) (size 0.59 0.64) (layers "F.Cu" "F.Paste" "F.Mask") (roundrect_rratio 0.25)
      (net 106 "/USER_LED") (pintype "passive"))
  )

  (footprint "sdi-mipi-bridge-footprints:LED_0603_1608Metric_G" (layer "F.Cu")
    (at 127 104.4 90)
    (descr "LED SMD 0603 Green")
    (tags "LED SMD 0603 Green")
    (property "Author" "Antmicro")
    (property "License" "Apache-2.0")
    (property "MPN" "LG L29K-G2J1-24-Z")
    (property "Manufacturer" "Osram")
    (property "Sheetfile" "sdi-mipi-bridge.kicad_sch")
    (property "Sheetname" "")
    (attr smd)
    (fp_text reference "D4" (at 0.2 -0.7 90) (layer "F.SilkS")
        (effects (font (size 0.65 0.65) (thickness 0.15)) (justify left bottom))
    )
    (fp_text value "LED_G_0603_LG_L29K-G2J1-24-Z" (at 0 1.6 90) (layer "F.Fab") hide
        (effects (font (size 0.7 0.7) (thickness 0.15)) (justify left bottom))
    )
    (fp_text user "License: Apache-2.0" (at -1.31 5.769 90) (layer "F.Fab") hide
        (effects (font (size 0.7 0.7) (thickness 0.15)) (justify left bottom))
    )
    (fp_text user "${REFERENCE}" (at -1.31 3.769 90) (layer "F.Fab") hide
        (effects (font (size 0.7 0.7) (thickness 0.15)) (justify left bottom))
    )
    (fp_text user "Author: Antmicro" (at -1.31 4.769 90) (layer "F.Fab") hide
        (effects (font (size 0.7 0.7) (thickness 0.15)) (justify left bottom))
    )
    (fp_line (start -0.27 -0.35) (end 0.27 -0.35)
      (stroke (width 0.15) (type solid)) (layer "F.SilkS"))
    (fp_line (start -0.27 0.351) (end 0.27 0.351)
      (stroke (width 0.15) (type solid)) (layer "F.SilkS"))
    (fp_line (start -0.106328 -0.200008) (end -0.106328 0.199992)
      (stroke (width 0.1) (type solid)) (layer "F.SilkS"))
    (fp_line (start -0.106328 -0.200008) (end 0.093672 -0.000008)
      (stroke (width 0.1) (type solid)) (layer "F.SilkS"))
    (fp_line (start -0.106328 -0.000008) (end -0.29 0)
      (stroke (width 0.1) (type solid)) (layer "F.SilkS"))
    (fp_line (start 0.093672 -0.200008) (end 0.093672 0.199992)
      (stroke (width 0.1) (type solid)) (layer "F.SilkS"))
    (fp_line (start 0.093672 -0.000008) (end -0.106328 0.199992)
      (stroke (width 0.1) (type solid)) (layer "F.SilkS"))
    (fp_line (start 0.093672 -0.000008) (end 0.293672 -0.000008)
      (stroke (width 0.1) (type solid)) (layer "F.SilkS"))
    (fp_line (start 1.25 0.32) (end 1.25 -0.32)
      (stroke (width 0.15) (type solid)) (layer "F.SilkS"))
    (fp_rect (start 1.26 0.65) (end -1.26 -0.65)
      (stroke (width 0.05) (type solid)) (fill none) (layer "F.CrtYd"))
    (fp_line (start -0.599 0) (end -0.201 0)
      (stroke (width 0.15) (type solid)) (layer "F.Fab"))
    (fp_line (start -0.201 -0.2) (end -0.201 0)
      (stroke (width 0.15) (type solid)) (layer "F.Fab"))
    (fp_line (start -0.201 0) (end -0.201 0.202)
      (stroke (width 0.15) (type solid)) (layer "F.Fab"))
    (fp_line (start -0.201 0.202) (end 0.101 0)
      (stroke (width 0.15) (type solid)) (layer "F.Fab"))
    (fp_line (start 0.101 0) (end -0.201 -0.2)
      (stroke (width 0.15) (type solid)) (layer "F.Fab"))
    (fp_line (start 0.199 -0.2) (end 0.199 -0.1)
      (stroke (width 0.15) (type solid)) (layer "F.Fab"))
    (fp_line (start 0.199 0) (end 0.597 0)
      (stroke (width 0.15) (type solid)) (layer "F.Fab"))
    (fp_line (start 0.199 0.202) (end 0.199 -0.1)
      (stroke (width 0.15) (type solid)) (layer "F.Fab"))
    (fp_rect (start -0.848 -0.4) (end 0.85 0.402)
      (stroke (width 0.15) (type solid)) (fill none) (layer "F.Fab"))
    (pad "1" smd rect (at -0.75 0 270) (size 0.8 0.8) (layers "F.Cu" "F.Paste" "F.Mask")
      (net 91 "Net-(D4-Pad1)") (pintype "passive"))
    (pad "2" smd rect (at 0.75 0 270) (size 0.8 0.8) (layers "F.Cu" "F.Paste" "F.Mask")
      (net 1 "GNDREF") (pinfunction "2") (pintype "passive"))
  )

  (footprint "sdi-mipi-bridge-footprints:R_0402_1005Metric" (layer "F.Cu")
    (at 129 107.4 -90)
    (descr "Resistor SMD 0402")
    (tags "resistor SMD 0402")
    (property "Author" "Antmicro")
    (property "License" "Apache-2.0")
    (property "MPN" "CR0402-FX-1000GLF")
    (property "Manufacturer" "Bourns")
    (property "Sheetfile" "sdi-mipi-bridge.kicad_sch")
    (property "Sheetname" "")
    (property "Tolerance" "1%")
    (property "Val" "100R")
    (property "ki_description" "100R resistor in 0402 package with 1% tolerance")
    (attr smd)
    (fp_text reference "R33" (at 0.9 -3.3 -90) (layer "F.SilkS")
        (effects (font (size 0.65 0.65) (thickness 0.15)) (justify left bottom))
    )
    (fp_text value "R_100R_0402" (at 0 1.4 -90) (layer "F.Fab") hide
        (effects (font (size 0.7 0.7) (thickness 0.15)) (justify left bottom))
    )
    (fp_text user "${REFERENCE}" (at -0.95 3.168 -90) (layer "F.Fab") hide
        (effects (font (size 0.7 0.7) (thickness 0.15)) (justify left bottom))
    )
    (fp_text user "License: Apache-2.0" (at -0.95 5.169 -90) (layer "F.Fab") hide
        (effects (font (size 0.7 0.7) (thickness 0.15)) (justify left bottom))
    )
    (fp_text user "Author: Antmicro" (at -0.95 4.169 -90) (layer "F.Fab") hide
        (effects (font (size 0.7 0.7) (thickness 0.15)) (justify left bottom))
    )
    (fp_rect (start -0.93 -0.47) (end 0.93 0.47)
      (stroke (width 0.05) (type solid)) (fill none) (layer "F.CrtYd"))
    (fp_rect (start -0.5 -0.25) (end 0.5 0.25)
      (stroke (width 0.15) (type solid)) (fill none) (layer "F.Fab"))
    (pad "1" smd roundrect (at -0.485 0 270) (size 0.59 0.64) (layers "F.Cu" "F.Paste" "F.Mask") (roundrect_rratio 0.25)
      (net 56 "Net-(D1-Pad1)") (pintype "passive"))
    (pad "2" smd roundrect (at 0.485 0 270) (size 0.59 0.64) (layers "F.Cu" "F.Paste" "F.Mask") (roundrect_rratio 0.25)
      (net 20 "/LOCKED") (pintype "passive"))
  )

  (footprint "sdi-mipi-bridge-footprints:LED_0603_1608Metric_G" (layer "F.Cu")
    (at 129 104.4 90)
    (descr "LED SMD 0603 Green")
    (tags "LED SMD 0603 Green")
    (property "Author" "Antmicro")
    (property "License" "Apache-2.0")
    (property "MPN" "LG L29K-G2J1-24-Z")
    (property "Manufacturer" "Osram")
    (property "Sheetfile" "sdi-mipi-bridge.kicad_sch")
    (property "Sheetname" "")
    (attr smd)
    (fp_text reference "D1" (at 0.2 -0.7 90) (layer "F.SilkS")
        (effects (font (size 0.65 0.65) (thickness 0.15)) (justify left bottom))
    )
    (fp_text value "LED_G_0603_LG_L29K-G2J1-24-Z" (at 0 1.6 90) (layer "F.Fab") hide
        (effects (font (size 0.7 0.7) (thickness 0.15)) (justify left bottom))
    )
    (fp_text user "License: Apache-2.0" (at -1.31 5.769 90) (layer "F.Fab") hide
        (effects (font (size 0.7 0.7) (thickness 0.15)) (justify left bottom))
    )
    (fp_text user "${REFERENCE}" (at -1.31 3.769 90) (layer "F.Fab") hide
        (effects (font (size 0.7 0.7) (thickness 0.15)) (justify left bottom))
    )
    (fp_text user "Author: Antmicro" (at -1.31 4.769 90) (layer "F.Fab") hide
        (effects (font (size 0.7 0.7) (thickness 0.15)) (justify left bottom))
    )
    (fp_line (start -0.27 -0.35) (end 0.27 -0.35)
      (stroke (width 0.15) (type solid)) (layer "F.SilkS"))
    (fp_line (start -0.27 0.351) (end 0.27 0.351)
      (stroke (width 0.15) (type solid)) (layer "F.SilkS"))
    (fp_line (start -0.106328 -0.200008) (end -0.106328 0.199992)
      (stroke (width 0.1) (type solid)) (layer "F.SilkS"))
    (fp_line (start -0.106328 -0.200008) (end 0.093672 -0.000008)
      (stroke (width 0.1) (type solid)) (layer "F.SilkS"))
    (fp_line (start -0.106328 -0.000008) (end -0.29 0)
      (stroke (width 0.1) (type solid)) (layer "F.SilkS"))
    (fp_line (start 0.093672 -0.200008) (end 0.093672 0.199992)
      (stroke (width 0.1) (type solid)) (layer "F.SilkS"))
    (fp_line (start 0.093672 -0.000008) (end -0.106328 0.199992)
      (stroke (width 0.1) (type solid)) (layer "F.SilkS"))
    (fp_line (start 0.093672 -0.000008) (end 0.293672 -0.000008)
      (stroke (width 0.1) (type solid)) (layer "F.SilkS"))
    (fp_line (start 1.25 0.32) (end 1.25 -0.32)
      (stroke (width 0.15) (type solid)) (layer "F.SilkS"))
    (fp_rect (start 1.26 0.65) (end -1.26 -0.65)
      (stroke (width 0.05) (type solid)) (fill none) (layer "F.CrtYd"))
    (fp_line (start -0.599 0) (end -0.201 0)
      (stroke (width 0.15) (type solid)) (layer "F.Fab"))
    (fp_line (start -0.201 -0.2) (end -0.201 0)
      (stroke (width 0.15) (type solid)) (layer "F.Fab"))
    (fp_line (start -0.201 0) (end -0.201 0.202)
      (stroke (width 0.15) (type solid)) (layer "F.Fab"))
    (fp_line (start -0.201 0.202) (end 0.101 0)
      (stroke (width 0.15) (type solid)) (layer "F.Fab"))
    (fp_line (start 0.101 0) (end -0.201 -0.2)
      (stroke (width 0.15) (type solid)) (layer "F.Fab"))
    (fp_line (start 0.199 -0.2) (end 0.199 -0.1)
      (stroke (width 0.15) (type solid)) (layer "F.Fab"))
    (fp_line (start 0.199 0) (end 0.597 0)
      (stroke (width 0.15) (type solid)) (layer "F.Fab"))
    (fp_line (start 0.199 0.202) (end 0.199 -0.1)
      (stroke (width 0.15) (type solid)) (layer "F.Fab"))
    (fp_rect (start -0.848 -0.4) (end 0.85 0.402)
      (stroke (width 0.15) (type solid)) (fill none) (layer "F.Fab"))
    (pad "1" smd rect (at -0.75 0 270) (size 0.8 0.8) (layers "F.Cu" "F.Paste" "F.Mask")
      (net 56 "Net-(D1-Pad1)") (pintype "passive"))
    (pad "2" smd rect (at 0.75 0 270) (size 0.8 0.8) (layers "F.Cu" "F.Paste" "F.Mask")
      (net 1 "GNDREF") (pinfunction "2") (pintype "passive"))
  )

  (footprint "sdi-mipi-bridge-footprints:R_0402_1005Metric" (layer "F.Cu")
    (at 159.8 105.9 180)
    (descr "Resistor SMD 0402")
    (tags "resistor SMD 0402")
    (property "Author" "Antmicro")
    (property "Current" "1A")
    (property "License" "Apache-2.0")
    (property "MPN" "ERJ2GE0R00X")
    (property "Manufacturer" "Panasonic")
    (property "Sheetfile" "sdi-mipi-bridge.kicad_sch")
    (property "Sheetname" "")
    (property "Tolerance" "")
    (property "Val" "0R")
    (property "ki_description" "0R resistor in 0402 package with unspecified tolerance")
    (attr smd)
    (fp_text reference "R92" (at 1.6 0.7 180) (layer "F.SilkS")
        (effects (font (size 0.65 0.65) (thickness 0.15)) (justify left bottom))
    )
    (fp_text value "R_0R_0402" (at 0 1.4 180) (layer "F.Fab") hide
        (effects (font (size 0.7 0.7) (thickness 0.15)) (justify left bottom))
    )
    (fp_text user "${REFERENCE}" (at -0.95 3.168 180) (layer "F.Fab") hide
        (effects (font (size 0.7 0.7) (thickness 0.15)) (justify left bottom))
    )
    (fp_text user "Author: Antmicro" (at -0.95 4.169 180) (layer "F.Fab") hide
        (effects (font (size 0.7 0.7) (thickness 0.15)) (justify left bottom))
    )
    (fp_text user "License: Apache-2.0" (at -0.95 5.169 180) (layer "F.Fab") hide
        (effects (font (size 0.7 0.7) (thickness 0.15)) (justify left bottom))
    )
    (fp_rect (start -0.93 -0.47) (end 0.93 0.47)
      (stroke (width 0.05) (type solid)) (fill none) (layer "F.CrtYd"))
    (fp_rect (start -0.5 -0.25) (end 0.5 0.25)
      (stroke (width 0.15) (type solid)) (fill none) (layer "F.Fab"))
    (pad "1" smd roundrect (at -0.485 0 180) (size 0.59 0.64) (layers "F.Cu" "F.Paste" "F.Mask") (roundrect_rratio 0.25)
      (net 136 "Net-(J3-Pad47)") (pintype "passive"))
    (pad "2" smd roundrect (at 0.485 0 180) (size 0.59 0.64) (layers "F.Cu" "F.Paste" "F.Mask") (roundrect_rratio 0.25)
      (net 6 "+3V3") (pintype "passive"))
  )

  (footprint "sdi-mipi-bridge-footprints:Mount-hole-M2.5" (layer "F.Cu")
    (at 101.5 98)
    (attr through_hole board_only)
    (fp_text reference "REF**" (at 0 0.5) (layer "F.SilkS") hide
        (effects (font (size 0.65 0.65) (thickness 0.12)))
    )
    (fp_text value "Mount-hole-M2.5" (at 0 -0.5) (layer "F.Fab") hide
        (effects (font (size 1 1) (thickness 0.15)))
    )
    (pad "1" thru_hole circle (at 0 0) (size 4.4 4.4) (drill 2.5) (layers "*.Cu" "*.Mask")
      (net 3 "GNDA"))
  )

  (footprint "sdi-mipi-bridge-footprints:R_0402_1005Metric" (layer "F.Cu")
    (at 149.25 129.75 90)
    (descr "Resistor SMD 0402")
    (tags "resistor SMD 0402")
    (property "Author" "Antmicro")
    (property "DNP" "DNP")
    (property "License" "Apache-2.0")
    (property "MPN" "CR0402-FX-1002GLF")
    (property "Manufacturer" "Bourns")
    (property "Sheetfile" "sdi-mipi-bridge.kicad_sch")
    (property "Sheetname" "")
    (property "Tolerance" "1%")
    (property "Val" "10k")
    (property "ki_description" "10k resistor in 0402 package with 1% tolerance")
    (attr exclude_from_pos_files)
    (fp_text reference "R106" (at -0.865 7.66 90) (layer "F.SilkS")
        (effects (font (size 0.65 0.65) (thickness 0.15)) (justify left bottom))
    )
    (fp_text value "R_10k_0402" (at 0 1.4 90) (layer "F.Fab") hide
        (effects (font (size 0.7 0.7) (thickness 0.15)) (justify left bottom))
    )
    (fp_text user "Author: Antmicro" (at -0.95 4.169 90) (layer "F.Fab") hide
        (effects (font (size 0.7 0.7) (thickness 0.15)) (justify left bottom))
    )
    (fp_text user "${REFERENCE}" (at -0.95 3.168 90) (layer "F.Fab") hide
        (effects (font (size 0.7 0.7) (thickness 0.15)) (justify left bottom))
    )
    (fp_text user "License: Apache-2.0" (at -0.95 5.169 90) (layer "F.Fab") hide
        (effects (font (size 0.7 0.7) (thickness 0.15)) (justify left bottom))
    )
    (fp_rect (start -0.93 -0.47) (end 0.93 0.47)
      (stroke (width 0.05) (type solid)) (fill none) (layer "F.CrtYd"))
    (fp_rect (start -0.5 -0.25) (end 0.5 0.25)
      (stroke (width 0.15) (type solid)) (fill none) (layer "F.Fab"))
    (pad "1" smd roundrect (at -0.485 0 90) (size 0.59 0.64) (layers "F.Cu" "F.Paste" "F.Mask") (roundrect_rratio 0.25)
      (net 24 "/~{RC_BYP}") (pintype "passive"))
    (pad "2" smd roundrect (at 0.485 0 90) (size 0.59 0.64) (layers "F.Cu" "F.Paste" "F.Mask") (roundrect_rratio 0.25)
      (net 76 "IO_VDD") (pintype "passive"))
  )

  (footprint "sdi-mipi-bridge-footprints:R_0402_1005Metric" (layer "F.Cu")
    (at 144.25 131.75 90)
    (descr "Resistor SMD 0402")
    (tags "resistor SMD 0402")
    (property "Author" "Antmicro")
    (property "DNP" "DNP")
    (property "License" "Apache-2.0")
    (property "MPN" "CR0402-FX-1002GLF")
    (property "Manufacturer" "Bourns")
    (property "Sheetfile" "sdi-mipi-bridge.kicad_sch")
    (property "Sheetname" "")
    (property "Tolerance" "1%")
    (property "Val" "10k")
    (property "ki_description" "10k resistor in 0402 package with 1% tolerance")
    (attr exclude_from_pos_files)
    (fp_text reference "R97" (at -5.75 0.4 90) (layer "F.SilkS")
        (effects (font (size 0.65 0.65) (thickness 0.15)) (justify left bottom))
    )
    (fp_text value "R_10k_0402" (at 0 1.4 90) (layer "F.Fab") hide
        (effects (font (size 0.7 0.7) (thickness 0.15)) (justify left bottom))
    )
    (fp_text user "License: Apache-2.0" (at -0.95 5.169 90) (layer "F.Fab") hide
        (effects (font (size 0.7 0.7) (thickness 0.15)) (justify left bottom))
    )
    (fp_text user "${REFERENCE}" (at -0.95 3.168 90) (layer "F.Fab") hide
        (effects (font (size 0.7 0.7) (thickness 0.15)) (justify left bottom))
    )
    (fp_text user "Author: Antmicro" (at -0.95 4.169 90) (layer "F.Fab") hide
        (effects (font (size 0.7 0.7) (thickness 0.15)) (justify left bottom))
    )
    (fp_rect (start -0.93 -0.47) (end 0.93 0.47)
      (stroke (width 0.05) (type solid)) (fill none) (layer "F.CrtYd"))
    (fp_rect (start -0.5 -0.25) (end 0.5 0.25)
      (stroke (width 0.15) (type solid)) (fill none) (layer "F.Fab"))
    (pad "1" smd roundrect (at -0.485 0 90) (size 0.59 0.64) (layers "F.Cu" "F.Paste" "F.Mask") (roundrect_rratio 0.25)
      (net 3 "GNDA") (pintype "passive"))
    (pad "2" smd roundrect (at 0.485 0 90) (size 0.59 0.64) (layers "F.Cu" "F.Paste" "F.Mask") (roundrect_rratio 0.25)
      (net 17 "/~{SMPTE_BYPASS}") (pintype "passive"))
  )

  (footprint "sdi-mipi-bridge-footprints:SW_SPST_4.2x2.8" (layer "F.Cu")
    (at 156.9 134.3 180)
    (descr "KMR211G")
    (tags "SPST Button Switch")
    (property "Author" "Antmicro")
    (property "License" "Apache-2.0")
    (property "MPN" "KMR211NGLFS")
    (property "Manufacturer" "C&K")
    (property "Sheetfile" "sdi-mipi-bridge.kicad_sch")
    (property "Sheetname" "")
    (attr smd)
    (fp_text reference "SW1" (at -1 -2.8) (layer "F.SilkS")
        (effects (font (size 0.65 0.65) (thickness 0.15)) (justify right bottom))
    )
    (fp_text value "SW_SPST_KMR211NGLFS" (at -3 3) (layer "F.Fab") hide
        (effects (font (size 0.7 0.7) (thickness 0.15)) (justify right bottom))
    )
    (fp_text user "License: Apache-2.0" (at -3 6.75) (layer "F.Fab") hide
        (effects (font (size 0.7 0.7) (thickness 0.15)) (justify right bottom))
    )
    (fp_text user "Author: Antmicro" (at -3 5.5) (layer "F.Fab") hide
        (effects (font (size 0.7 0.7) (thickness 0.15)) (justify right bottom))
    )
    (fp_text user "${REFERENCE}" (at -3 4.25) (layer "F.Fab") hide
        (effects (font (size 0.7 0.7) (thickness 0.15)) (justify right bottom))
    )
    (fp_line (start -2.101 -1.601) (end -2.101 -1.48)
      (stroke (width 0.15) (type solid)) (layer "F.SilkS"))
    (fp_line (start -2.101 -1.601) (end 2.1 -1.601)
      (stroke (width 0.15) (type solid)) (layer "F.SilkS"))
    (fp_line (start -2.101 1.58) (end -2.101 1.459)
      (stroke (width 0.15) (type solid)) (layer "F.SilkS"))
    (fp_line (start -2.101 1.6) (end 2.1 1.6)
      (stroke (width 0.15) (type solid)) (layer "F.SilkS"))
    (fp_line (start 2.1 -1.601) (end 2.1 -1.48)
      (stroke (width 0.15) (type solid)) (layer "F.SilkS"))
    (fp_line (start 2.1 1.6) (end 2.1 1.499)
      (stroke (width 0.15) (type solid)) (layer "F.SilkS"))
    (fp_rect (start -2.751 -1.75) (end 2.748 1.749)
      (stroke (width 0.05) (type solid)) (fill none) (layer "F.CrtYd"))
    (fp_line (start -2.101 -1.601) (end -2.101 1.6)
      (stroke (width 0.15) (type solid)) (layer "F.Fab"))
    (fp_line (start -2.101 1.6) (end 2.1 1.6)
      (stroke (width 0.15) (type solid)) (layer "F.Fab"))
    (fp_line (start -0.25 -0.802) (end 0.248 -0.802)
      (stroke (width 0.15) (type solid)) (layer "F.Fab"))
    (fp_line (start 0.248 0.8) (end -0.25 0.8)
      (stroke (width 0.15) (type solid)) (layer "F.Fab"))
    (fp_line (start 2.1 -1.601) (end -2.101 -1.601)
      (stroke (width 0.15) (type solid)) (layer "F.Fab"))
    (fp_line (start 2.1 1.6) (end 2.1 -1.601)
      (stroke (width 0.15) (type solid)) (layer "F.Fab"))
    (fp_arc (start -0.25 0.8) (mid -1.051001 -0.001) (end -0.25 -0.802)
      (stroke (width 0.15) (type solid)) (layer "F.Fab"))
    (fp_arc (start 0.248 -0.802) (mid 1.050001 -0.001) (end 0.248 0.8)
      (stroke (width 0.15) (type solid)) (layer "F.Fab"))
    (pad "1" smd rect (at 2.048 -0.802 180) (size 0.9 1) (layers "F.Cu" "F.Paste" "F.Mask")
      (net 3 "GNDA") (pintype "passive"))
    (pad "2" smd rect (at 2.048 0.8 180) (size 0.9 1) (layers "F.Cu" "F.Paste" "F.Mask")
      (net 125 "Net-(R82-Pad2)") (pintype "passive"))
    (pad "3" smd rect (at -2.05 -0.802 180) (size 0.9 1) (layers "F.Cu" "F.Paste" "F.Mask")
      (net 3 "GNDA") (pintype "passive"))
    (pad "4" smd rect (at -2.05 0.8 180) (size 0.9 1) (layers "F.Cu" "F.Paste" "F.Mask")
      (net 125 "Net-(R82-Pad2)") (pintype "passive"))
  )

  (footprint "sdi-mipi-bridge-footprints:R_0402_1005Metric" (layer "F.Cu")
    (at 145.5 129.75 90)
    (descr "Resistor SMD 0402")
    (tags "resistor SMD 0402")
    (property "Author" "Antmicro")
    (property "DNP" "DNP")
    (property "License" "Apache-2.0")
    (property "MPN" "CR0402-FX-1002GLF")
    (property "Manufacturer" "Bourns")
    (property "Sheetfile" "sdi-mipi-bridge.kicad_sch")
    (property "Sheetname" "")
    (property "Tolerance" "1%")
    (property "Val" "10k")
    (property "ki_description" "10k resistor in 0402 package with 1% tolerance")
    (attr exclude_from_pos_files)
    (fp_text reference "R99" (at -0.865 7.78 90) (layer "F.SilkS")
        (effects (font (size 0.65 0.65) (thickness 0.15)) (justify left bottom))
    )
    (fp_text value "R_10k_0402" (at 0 1.4 90) (layer "F.Fab") hide
        (effects (font (size 0.7 0.7) (thickness 0.15)) (justify left bottom))
    )
    (fp_text user "${REFERENCE}" (at -0.95 3.168 90) (layer "F.Fab") hide
        (effects (font (size 0.7 0.7) (thickness 0.15)) (justify left bottom))
    )
    (fp_text user "License: Apache-2.0" (at -0.95 5.169 90) (layer "F.Fab") hide
        (effects (font (size 0.7 0.7) (thickness 0.15)) (justify left bottom))
    )
    (fp_text user "Author: Antmicro" (at -0.95 4.169 90) (layer "F.Fab") hide
        (effects (font (size 0.7 0.7) (thickness 0.15)) (justify left bottom))
    )
    (fp_rect (start -0.93 -0.47) (end 0.93 0.47)
      (stroke (width 0.05) (type solid)) (fill none) (layer "F.CrtYd"))
    (fp_rect (start -0.5 -0.25) (end 0.5 0.25)
      (stroke (width 0.15) (type solid)) (fill none) (layer "F.Fab"))
    (pad "1" smd roundrect (at -0.485 0 90) (size 0.59 0.64) (layers "F.Cu" "F.Paste" "F.Mask") (roundrect_rratio 0.25)
      (net 18 "/DVB_ASI") (pintype "passive"))
    (pad "2" smd roundrect (at 0.485 0 90) (size 0.59 0.64) (layers "F.Cu" "F.Paste" "F.Mask") (roundrect_rratio 0.25)
      (net 76 "IO_VDD") (pintype "passive"))
  )

  (footprint "sdi-mipi-bridge-footprints:R_0402_1005Metric" (layer "F.Cu")
    (at 151.75 131.765 90)
    (descr "Resistor SMD 0402")
    (tags "resistor SMD 0402")
    (property "Author" "Antmicro")
    (property "License" "Apache-2.0")
    (property "MPN" "CR0402-FX-1002GLF")
    (property "Manufacturer" "Bourns")
    (property "Sheetfile" "sdi-mipi-bridge.kicad_sch")
    (property "Sheetname" "")
    (property "Tolerance" "1%")
    (property "Val" "10k")
    (property "ki_description" "10k resistor in 0402 package with 1% tolerance")
    (attr smd)
    (fp_text reference "R111" (at -5.75 0.4 90) (layer "F.SilkS")
        (effects (font (size 0.65 0.65) (thickness 0.15)) (justify left bottom))
    )
    (fp_text value "R_10k_0402" (at 0 1.4 90) (layer "F.Fab") hide
        (effects (font (size 0.7 0.7) (thickness 0.15)) (justify left bottom))
    )
    (fp_text user "License: Apache-2.0" (at -0.95 5.169 90) (layer "F.Fab") hide
        (effects (font (size 0.7 0.7) (thickness 0.15)) (justify left bottom))
    )
    (fp_text user "Author: Antmicro" (at -0.95 4.169 90) (layer "F.Fab") hide
        (effects (font (size 0.7 0.7) (thickness 0.15)) (justify left bottom))
    )
    (fp_text user "${REFERENCE}" (at -0.95 3.168 90) (layer "F.Fab") hide
        (effects (font (size 0.7 0.7) (thickness 0.15)) (justify left bottom))
    )
    (fp_rect (start -0.93 -0.47) (end 0.93 0.47)
      (stroke (width 0.05) (type solid)) (fill none) (layer "F.CrtYd"))
    (fp_rect (start -0.5 -0.25) (end 0.5 0.25)
      (stroke (width 0.15) (type solid)) (fill none) (layer "F.Fab"))
    (pad "1" smd roundrect (at -0.485 0 90) (size 0.59 0.64) (layers "F.Cu" "F.Paste" "F.Mask") (roundrect_rratio 0.25)
      (net 3 "GNDA") (pintype "passive"))
    (pad "2" smd roundrect (at 0.485 0 90) (size 0.59 0.64) (layers "F.Cu" "F.Paste" "F.Mask") (roundrect_rratio 0.25)
      (net 44 "/JTAG_~{HOST}") (pintype "passive"))
  )

  (footprint "sdi-mipi-bridge-footprints:R_0402_1005Metric" (layer "F.Cu")
    (at 146.75 129.75 90)
    (descr "Resistor SMD 0402")
    (tags "resistor SMD 0402")
    (property "Author" "Antmicro")
    (property "DNP" "DNP")
    (property "License" "Apache-2.0")
    (property "MPN" "CR0402-FX-1002GLF")
    (property "Manufacturer" "Bourns")
    (property "Sheetfile" "sdi-mipi-bridge.kicad_sch")
    (property "Sheetname" "")
    (property "Tolerance" "1%")
    (property "Val" "10k")
    (property "ki_description" "10k resistor in 0402 package with 1% tolerance")
    (attr exclude_from_pos_files)
    (fp_text reference "R101" (at -0.865 7.74 90) (layer "F.SilkS")
        (effects (font (size 0.65 0.65) (thickness 0.15)) (justify left bottom))
    )
    (fp_text value "R_10k_0402" (at 0 1.4 90) (layer "F.Fab") hide
        (effects (font (size 0.7 0.7) (thickness 0.15)) (justify left bottom))
    )
    (fp_text user "Author: Antmicro" (at -0.95 4.169 90) (layer "F.Fab") hide
        (effects (font (size 0.7 0.7) (thickness 0.15)) (justify left bottom))
    )
    (fp_text user "${REFERENCE}" (at -0.95 3.168 90) (layer "F.Fab") hide
        (effects (font (size 0.7 0.7) (thickness 0.15)) (justify left bottom))
    )
    (fp_text user "License: Apache-2.0" (at -0.95 5.169 90) (layer "F.Fab") hide
        (effects (font (size 0.7 0.7) (thickness 0.15)) (justify left bottom))
    )
    (fp_rect (start -0.93 -0.47) (end 0.93 0.47)
      (stroke (width 0.05) (type solid)) (fill none) (layer "F.CrtYd"))
    (fp_rect (start -0.5 -0.25) (end 0.5 0.25)
      (stroke (width 0.15) (type solid)) (fill none) (layer "F.Fab"))
    (pad "1" smd roundrect (at -0.485 0 90) (size 0.59 0.64) (layers "F.Cu" "F.Paste" "F.Mask") (roundrect_rratio 0.25)
      (net 47 "/SW_EN") (pintype "passive"))
    (pad "2" smd roundrect (at 0.485 0 90) (size 0.59 0.64) (layers "F.Cu" "F.Paste" "F.Mask") (roundrect_rratio 0.25)
      (net 76 "IO_VDD") (pintype "passive"))
  )

  (footprint "sdi-mipi-bridge-footprints:R_0402_1005Metric" (layer "F.Cu")
    (at 150.5 129.765 90)
    (descr "Resistor SMD 0402")
    (tags "resistor SMD 0402")
    (property "Author" "Antmicro")
    (property "DNP" "DNP")
    (property "License" "Apache-2.0")
    (property "MPN" "CR0402-FX-1002GLF")
    (property "Manufacturer" "Bourns")
    (property "Sheetfile" "sdi-mipi-bridge.kicad_sch")
    (property "Sheetname" "")
    (property "Tolerance" "1%")
    (property "Val" "10k")
    (property "ki_description" "10k resistor in 0402 package with 1% tolerance")
    (attr exclude_from_pos_files)
    (fp_text reference "R108" (at -0.85 7.62 90) (layer "F.SilkS")
        (effects (font (size 0.65 0.65) (thickness 0.15)) (justify left bottom))
    )
    (fp_text value "R_10k_0402" (at 0 1.4 90) (layer "F.Fab") hide
        (effects (font (size 0.7 0.7) (thickness 0.15)) (justify left bottom))
    )
    (fp_text user "Author: Antmicro" (at -0.95 4.169 90) (layer "F.Fab") hide
        (effects (font (size 0.7 0.7) (thickness 0.15)) (justify left bottom))
    )
    (fp_text user "License: Apache-2.0" (at -0.95 5.169 90) (layer "F.Fab") hide
        (effects (font (size 0.7 0.7) (thickness 0.15)) (justify left bottom))
    )
    (fp_text user "${REFERENCE}" (at -0.95 3.168 90) (layer "F.Fab") hide
        (effects (font (size 0.7 0.7) (thickness 0.15)) (justify left bottom))
    )
    (fp_rect (start -0.93 -0.47) (end 0.93 0.47)
      (stroke (width 0.05) (type solid)) (fill none) (layer "F.CrtYd"))
    (fp_rect (start -0.5 -0.25) (end 0.5 0.25)
      (stroke (width 0.15) (type solid)) (fill none) (layer "F.Fab"))
    (pad "1" smd roundrect (at -0.485 0 90) (size 0.59 0.64) (layers "F.Cu" "F.Paste" "F.Mask") (roundrect_rratio 0.25)
      (net 54 "/STANDBY") (pintype "passive"))
    (pad "2" smd roundrect (at 0.485 0 90) (size 0.59 0.64) (layers "F.Cu" "F.Paste" "F.Mask") (roundrect_rratio 0.25)
      (net 76 "IO_VDD") (pintype "passive"))
  )

  (footprint "sdi-mipi-bridge-footprints:R_0402_1005Metric" (layer "F.Cu")
    (at 151.75 129.75 90)
    (descr "Resistor SMD 0402")
    (tags "resistor SMD 0402")
    (property "Author" "Antmicro")
    (property "DNP" "DNP")
    (property "License" "Apache-2.0")
    (property "MPN" "CR0402-FX-1002GLF")
    (property "Manufacturer" "Bourns")
    (property "Sheetfile" "sdi-mipi-bridge.kicad_sch")
    (property "Sheetname" "")
    (property "Tolerance" "1%")
    (property "Val" "10k")
    (property "ki_description" "10k resistor in 0402 package with 1% tolerance")
    (attr exclude_from_pos_files)
    (fp_text reference "R110" (at -0.865 7.58 90) (layer "F.SilkS")
        (effects (font (size 0.65 0.65) (thickness 0.15)) (justify left bottom))
    )
    (fp_text value "R_10k_0402" (at 0 1.4 90) (layer "F.Fab") hide
        (effects (font (size 0.7 0.7) (thickness 0.15)) (justify left bottom))
    )
    (fp_text user "Author: Antmicro" (at -0.95 4.169 90) (layer "F.Fab") hide
        (effects (font (size 0.7 0.7) (thickness 0.15)) (justify left bottom))
    )
    (fp_text user "License: Apache-2.0" (at -0.95 5.169 90) (layer "F.Fab") hide
        (effects (font (size 0.7 0.7) (thickness 0.15)) (justify left bottom))
    )
    (fp_text user "${REFERENCE}" (at -0.95 3.168 90) (layer "F.Fab") hide
        (effects (font (size 0.7 0.7) (thickness 0.15)) (justify left bottom))
    )
    (fp_rect (start -0.93 -0.47) (end 0.93 0.47)
      (stroke (width 0.05) (type solid)) (fill none) (layer "F.CrtYd"))
    (fp_rect (start -0.5 -0.25) (end 0.5 0.25)
      (stroke (width 0.15) (type solid)) (fill none) (layer "F.Fab"))
    (pad "1" smd roundrect (at -0.485 0 90) (size 0.59 0.64) (layers "F.Cu" "F.Paste" "F.Mask") (roundrect_rratio 0.25)
      (net 44 "/JTAG_~{HOST}") (pintype "passive"))
    (pad "2" smd roundrect (at 0.485 0 90) (size 0.59 0.64) (layers "F.Cu" "F.Paste" "F.Mask") (roundrect_rratio 0.25)
      (net 76 "IO_VDD") (pintype "passive"))
  )

  (footprint "sdi-mipi-bridge-footprints:Mount-hole-M2.5" (layer "F.Cu")
    (at 101.5 135)
    (attr through_hole board_only)
    (fp_text reference "REF**" (at 0 0.5) (layer "F.SilkS") hide
        (effects (font (size 0.65 0.65) (thickness 0.12)))
    )
    (fp_text value "Mount-hole-M2.5" (at 0 -0.5) (layer "F.Fab") hide
        (effects (font (size 1 1) (thickness 0.15)))
    )
    (pad "1" thru_hole circle (at 0 0) (size 4.4 4.4) (drill 2.5) (layers "*.Cu" "*.Mask")
      (net 3 "GNDA"))
  )

  (footprint "sdi-mipi-bridge-footprints:R_0402_1005Metric" (layer "F.Cu")
    (at 146.75 131.75 90)
    (descr "Resistor SMD 0402")
    (tags "resistor SMD 0402")
    (property "Author" "Antmicro")
    (property "License" "Apache-2.0")
    (property "MPN" "CR0402-FX-1002GLF")
    (property "Manufacturer" "Bourns")
    (property "Sheetfile" "sdi-mipi-bridge.kicad_sch")
    (property "Sheetname" "")
    (property "Tolerance" "1%")
    (property "Val" "10k")
    (property "ki_description" "10k resistor in 0402 package with 1% tolerance")
    (attr smd)
    (fp_text reference "R102" (at -5.75 0.4 90) (layer "F.SilkS")
        (effects (font (size 0.65 0.65) (thickness 0.15)) (justify left bottom))
    )
    (fp_text value "R_10k_0402" (at 0 1.4 90) (layer "F.Fab") hide
        (effects (font (size 0.7 0.7) (thickness 0.15)) (justify left bottom))
    )
    (fp_text user "Author: Antmicro" (at -0.95 4.169 90) (layer "F.Fab") hide
        (effects (font (size 0.7 0.7) (thickness 0.15)) (justify left bottom))
    )
    (fp_text user "License: Apache-2.0" (at -0.95 5.169 90) (layer "F.Fab") hide
        (effects (font (size 0.7 0.7) (thickness 0.15)) (justify left bottom))
    )
    (fp_text user "${REFERENCE}" (at -0.95 3.168 90) (layer "F.Fab") hide
        (effects (font (size 0.7 0.7) (thickness 0.15)) (justify left bottom))
    )
    (fp_rect (start -0.93 -0.47) (end 0.93 0.47)
      (stroke (width 0.05) (type solid)) (fill none) (layer "F.CrtYd"))
    (fp_rect (start -0.5 -0.25) (end 0.5 0.25)
      (stroke (width 0.15) (type solid)) (fill none) (layer "F.Fab"))
    (pad "1" smd roundrect (at -0.485 0 90) (size 0.59 0.64) (layers "F.Cu" "F.Paste" "F.Mask") (roundrect_rratio 0.25)
      (net 3 "GNDA") (pintype "passive"))
    (pad "2" smd roundrect (at 0.485 0 90) (size 0.59 0.64) (layers "F.Cu" "F.Paste" "F.Mask") (roundrect_rratio 0.25)
      (net 47 "/SW_EN") (pintype "passive"))
  )

  (footprint "" (layer "F.Cu")
    (at 164.5 135)
    (attr board_only)
    (fp_text reference "" (at 0 0) (layer "F.SilkS")
        (effects (font (size 0.65 0.65) (thickness 0.12)))
    )
    (fp_text value "" (at 0 0) (layer "F.SilkS")
        (effects (font (size 1.27 1.27) (thickness 0.15)))
    )
    (pad "1" thru_hole circle (at 0 0) (size 4.4 4.4) (drill 2.5) (layers "*.Cu" "*.Mask")
      (net 1 "GNDREF"))
  )

  (footprint "" (layer "F.Cu")
    (at 164.5 98)
    (attr board_only)
    (fp_text reference "" (at 0 0) (layer "F.SilkS")
        (effects (font (size 0.65 0.65) (thickness 0.12)))
    )
    (fp_text value "" (at 0 0) (layer "F.SilkS")
        (effects (font (size 1.27 1.27) (thickness 0.15)))
    )
    (pad "1" thru_hole circle (at 0 0) (size 4.4 4.4) (drill 2.5) (layers "*.Cu" "*.Mask")
      (net 1 "GNDREF"))
  )

  (footprint "sdi-mipi-bridge-footprints:R_0402_1005Metric" (layer "F.Cu")
    (at 149.25 131.75 90)
    (descr "Resistor SMD 0402")
    (tags "resistor SMD 0402")
    (property "Author" "Antmicro")
    (property "License" "Apache-2.0")
    (property "MPN" "CR0402-FX-1002GLF")
    (property "Manufacturer" "Bourns")
    (property "Sheetfile" "sdi-mipi-bridge.kicad_sch")
    (property "Sheetname" "")
    (property "Tolerance" "1%")
    (property "Val" "10k")
    (property "ki_description" "10k resistor in 0402 package with 1% tolerance")
    (attr smd)
    (fp_text reference "R107" (at -5.75 0.4 90) (layer "F.SilkS")
        (effects (font (size 0.65 0.65) (thickness 0.15)) (justify left bottom))
    )
    (fp_text value "R_10k_0402" (at 0 1.4 90) (layer "F.Fab") hide
        (effects (font (size 0.7 0.7) (thickness 0.15)) (justify left bottom))
    )
    (fp_text user "Author: Antmicro" (at -0.95 4.169 90) (layer "F.Fab") hide
        (effects (font (size 0.7 0.7) (thickness 0.15)) (justify left bottom))
    )
    (fp_text user "${REFERENCE}" (at -0.95 3.168 90) (layer "F.Fab") hide
        (effects (font (size 0.7 0.7) (thickness 0.15)) (justify left bottom))
    )
    (fp_text user "License: Apache-2.0" (at -0.95 5.169 90) (layer "F.Fab") hide
        (effects (font (size 0.7 0.7) (thickness 0.15)) (justify left bottom))
    )
    (fp_rect (start -0.93 -0.47) (end 0.93 0.47)
      (stroke (width 0.05) (type solid)) (fill none) (layer "F.CrtYd"))
    (fp_rect (start -0.5 -0.25) (end 0.5 0.25)
      (stroke (width 0.15) (type solid)) (fill none) (layer "F.Fab"))
    (pad "1" smd roundrect (at -0.485 0 90) (size 0.59 0.64) (layers "F.Cu" "F.Paste" "F.Mask") (roundrect_rratio 0.25)
      (net 3 "GNDA") (pintype "passive"))
    (pad "2" smd roundrect (at 0.485 0 90) (size 0.59 0.64) (layers "F.Cu" "F.Paste" "F.Mask") (roundrect_rratio 0.25)
      (net 24 "/~{RC_BYP}") (pintype "passive"))
  )

  (footprint "sdi-mipi-bridge-footprints:R_0402_1005Metric" (layer "F.Cu")
    (at 150.5 131.765 90)
    (descr "Resistor SMD 0402")
    (tags "resistor SMD 0402")
    (property "Author" "Antmicro")
    (property "License" "Apache-2.0")
    (property "MPN" "CR0402-FX-1002GLF")
    (property "Manufacturer" "Bourns")
    (property "Sheetfile" "sdi-mipi-bridge.kicad_sch")
    (property "Sheetname" "")
    (property "Tolerance" "1%")
    (property "Val" "10k")
    (property "ki_description" "10k resistor in 0402 package with 1% tolerance")
    (attr smd)
    (fp_text reference "R109" (at -5.75 0.4 90) (layer "F.SilkS")
        (effects (font (size 0.65 0.65) (thickness 0.15)) (justify left bottom))
    )
    (fp_text value "R_10k_0402" (at 0 1.4 90) (layer "F.Fab") hide
        (effects (font (size 0.7 0.7) (thickness 0.15)) (justify left bottom))
    )
    (fp_text user "License: Apache-2.0" (at -0.95 5.169 90) (layer "F.Fab") hide
        (effects (font (size 0.7 0.7) (thickness 0.15)) (justify left bottom))
    )
    (fp_text user "${REFERENCE}" (at -0.95 3.168 90) (layer "F.Fab") hide
        (effects (font (size 0.7 0.7) (thickness 0.15)) (justify left bottom))
    )
    (fp_text user "Author: Antmicro" (at -0.95 4.169 90) (layer "F.Fab") hide
        (effects (font (size 0.7 0.7) (thickness 0.15)) (justify left bottom))
    )
    (fp_rect (start -0.93 -0.47) (end 0.93 0.47)
      (stroke (width 0.05) (type solid)) (fill none) (layer "F.CrtYd"))
    (fp_rect (start -0.5 -0.25) (end 0.5 0.25)
      (stroke (width 0.15) (type solid)) (fill none) (layer "F.Fab"))
    (pad "1" smd roundrect (at -0.485 0 90) (size 0.59 0.64) (layers "F.Cu" "F.Paste" "F.Mask") (roundrect_rratio 0.25)
      (net 3 "GNDA") (pintype "passive"))
    (pad "2" smd roundrect (at 0.485 0 90) (size 0.59 0.64) (layers "F.Cu" "F.Paste" "F.Mask") (roundrect_rratio 0.25)
      (net 54 "/STANDBY") (pintype "passive"))
  )

  (footprint "sdi-mipi-bridge-footprints:R_0402_1005Metric" (layer "F.Cu")
    (at 145.5 131.75 90)
    (descr "Resistor SMD 0402")
    (tags "resistor SMD 0402")
    (property "Author" "Antmicro")
    (property "License" "Apache-2.0")
    (property "MPN" "CR0402-FX-1002GLF")
    (property "Manufacturer" "Bourns")
    (property "Sheetfile" "sdi-mipi-bridge.kicad_sch")
    (property "Sheetname" "")
    (property "Tolerance" "1%")
    (property "Val" "10k")
    (property "ki_description" "10k resistor in 0402 package with 1% tolerance")
    (attr smd)
    (fp_text reference "R100" (at -5.75 0.4 90) (layer "F.SilkS")
        (effects (font (size 0.65 0.65) (thickness 0.15)) (justify left bottom))
    )
    (fp_text value "R_10k_0402" (at 0 1.4 90) (layer "F.Fab") hide
        (effects (font (size 0.7 0.7) (thickness 0.15)) (justify left bottom))
    )
    (fp_text user "${REFERENCE}" (at -0.95 3.168 90) (layer "F.Fab") hide
        (effects (font (size 0.7 0.7) (thickness 0.15)) (justify left bottom))
    )
    (fp_text user "License: Apache-2.0" (at -0.95 5.169 90) (layer "F.Fab") hide
        (effects (font (size 0.7 0.7) (thickness 0.15)) (justify left bottom))
    )
    (fp_text user "Author: Antmicro" (at -0.95 4.169 90) (layer "F.Fab") hide
        (effects (font (size 0.7 0.7) (thickness 0.15)) (justify left bottom))
    )
    (fp_rect (start -0.93 -0.47) (end 0.93 0.47)
      (stroke (width 0.05) (type solid)) (fill none) (layer "F.CrtYd"))
    (fp_rect (start -0.5 -0.25) (end 0.5 0.25)
      (stroke (width 0.15) (type solid)) (fill none) (layer "F.Fab"))
    (pad "1" smd roundrect (at -0.485 0 90) (size 0.59 0.64) (layers "F.Cu" "F.Paste" "F.Mask") (roundrect_rratio 0.25)
      (net 3 "GNDA") (pintype "passive"))
    (pad "2" smd roundrect (at 0.485 0 90) (size 0.59 0.64) (layers "F.Cu" "F.Paste" "F.Mask") (roundrect_rratio 0.25)
      (net 18 "/DVB_ASI") (pintype "passive"))
  )

  (footprint "sdi-mipi-bridge-footprints:R_0402_1005Metric" (layer "F.Cu")
    (at 148 131.75 90)
    (descr "Resistor SMD 0402")
    (tags "resistor SMD 0402")
    (property "Author" "Antmicro")
    (property "DNP" "")
    (property "License" "Apache-2.0")
    (property "MPN" "CR0402-FX-1002GLF")
    (property "Manufacturer" "Bourns")
    (property "Sheetfile" "sdi-mipi-bridge.kicad_sch")
    (property "Sheetname" "")
    (property "Tolerance" "1%")
    (property "Val" "10k")
    (property "ki_description" "10k resistor in 0402 package with 1% tolerance")
    (attr smd)
    (fp_text reference "R104" (at -5.75 0.4 90) (layer "F.SilkS")
        (effects (font (size 0.65 0.65) (thickness 0.15)) (justify left bottom))
    )
    (fp_text value "R_10k_0402" (at 0 1.4 90) (layer "F.Fab") hide
        (effects (font (size 0.7 0.7) (thickness 0.15)) (justify left bottom))
    )
    (fp_text user "License: Apache-2.0" (at -0.95 5.169 90) (layer "F.Fab") hide
        (effects (font (size 0.7 0.7) (thickness 0.15)) (justify left bottom))
    )
    (fp_text user "${REFERENCE}" (at -0.95 3.168 90) (layer "F.Fab") hide
        (effects (font (size 0.7 0.7) (thickness 0.15)) (justify left bottom))
    )
    (fp_text user "Author: Antmicro" (at -0.95 4.169 90) (layer "F.Fab") hide
        (effects (font (size 0.7 0.7) (thickness 0.15)) (justify left bottom))
    )
    (fp_rect (start -0.93 -0.47) (end 0.93 0.47)
      (stroke (width 0.05) (type solid)) (fill none) (layer "F.CrtYd"))
    (fp_rect (start -0.5 -0.25) (end 0.5 0.25)
      (stroke (width 0.15) (type solid)) (fill none) (layer "F.Fab"))
    (pad "1" smd roundrect (at -0.485 0 90) (size 0.59 0.64) (layers "F.Cu" "F.Paste" "F.Mask") (roundrect_rratio 0.25)
      (net 3 "GNDA") (pintype "passive"))
    (pad "2" smd roundrect (at 0.485 0 90) (size 0.59 0.64) (layers "F.Cu" "F.Paste" "F.Mask") (roundrect_rratio 0.25)
      (net 23 "/TIM_861") (pintype "passive"))
  )

  (footprint "sdi-mipi-bridge-footprints:R_0402_1005Metric" (layer "F.Cu")
    (at 148 129.735 90)
    (descr "Resistor SMD 0402")
    (tags "resistor SMD 0402")
    (property "Author" "Antmicro")
    (property "DNP" "DNP")
    (property "License" "Apache-2.0")
    (property "MPN" "CR0402-FX-1002GLF")
    (property "Manufacturer" "Bourns")
    (property "Sheetfile" "sdi-mipi-bridge.kicad_sch")
    (property "Sheetname" "")
    (property "Tolerance" "1%")
    (property "Val" "10k")
    (property "ki_description" "10k resistor in 0402 package with 1% tolerance")
    (attr exclude_from_pos_files)
    (fp_text reference "R103" (at -0.88 7.7 90) (layer "F.SilkS")
        (effects (font (size 0.65 0.65) (thickness 0.15)) (justify left bottom))
    )
    (fp_text value "R_10k_0402" (at 0 1.4 90) (layer "F.Fab") hide
        (effects (font (size 0.7 0.7) (thickness 0.15)) (justify left bottom))
    )
    (fp_text user "${REFERENCE}" (at -0.95 3.168 90) (layer "F.Fab") hide
        (effects (font (size 0.7 0.7) (thickness 0.15)) (justify left bottom))
    )
    (fp_text user "Author: Antmicro" (at -0.95 4.169 90) (layer "F.Fab") hide
        (effects (font (size 0.7 0.7) (thickness 0.15)) (justify left bottom))
    )
    (fp_text user "License: Apache-2.0" (at -0.95 5.169 90) (layer "F.Fab") hide
        (effects (font (size 0.7 0.7) (thickness 0.15)) (justify left bottom))
    )
    (fp_rect (start -0.93 -0.47) (end 0.93 0.47)
      (stroke (width 0.05) (type solid)) (fill none) (layer "F.CrtYd"))
    (fp_rect (start -0.5 -0.25) (end 0.5 0.25)
      (stroke (width 0.15) (type solid)) (fill none) (layer "F.Fab"))
    (pad "1" smd roundrect (at -0.485 0 90) (size 0.59 0.64) (layers "F.Cu" "F.Paste" "F.Mask") (roundrect_rratio 0.25)
      (net 23 "/TIM_861") (pintype "passive"))
    (pad "2" smd roundrect (at 0.485 0 90) (size 0.59 0.64) (layers "F.Cu" "F.Paste" "F.Mask") (roundrect_rratio 0.25)
      (net 76 "IO_VDD") (pintype "passive"))
  )

  (footprint "sdi-mipi-bridge-footprints:R_0402_1005Metric" (layer "B.Cu")
    (at 116.75 124 90)
    (descr "Resistor SMD 0402")
    (tags "resistor SMD 0402")
    (property "Author" "Antmicro")
    (property "License" "Apache-2.0")
    (property "MPN" "CR0402-FX-22R0GLF")
    (property "Manufacturer" "Bourns")
    (property "Sheetfile" "sdi-mipi-bridge.kicad_sch")
    (property "Sheetname" "")
    (property "Tolerance" "1%")
    (property "Val" "22R")
    (property "ki_description" "22R resistor in 0402 package with 1% tolerance")
    (attr smd)
    (fp_text reference "R1" (at 1.4 0.45 90) (layer "B.SilkS")
        (effects (font (size 0.7 0.7) (thickness 0.15)) (justify right bottom mirror))
    )
    (fp_text value "R_22R_0402" (at 0 -1.4 90) (layer "B.Fab") hide
        (effects (font (size 0.7 0.7) (thickness 0.15)) (justify right bottom mirror))
    )
    (fp_text user "Author: Antmicro" (at -0.95 -4.169 90) (layer "B.Fab") hide
        (effects (font (size 0.7 0.7) (thickness 0.15)) (justify right bottom mirror))
    )
    (fp_text user "${REFERENCE}" (at -0.95 -3.168 90) (layer "B.Fab") hide
        (effects (font (size 0.7 0.7) (thickness 0.15)) (justify right bottom mirror))
    )
    (fp_text user "License: Apache-2.0" (at -0.95 -5.169 90) (layer "B.Fab") hide
        (effects (font (size 0.7 0.7) (thickness 0.15)) (justify right bottom mirror))
    )
    (fp_rect (start -0.93 0.47) (end 0.93 -0.47)
      (stroke (width 0.05) (type solid)) (fill none) (layer "B.CrtYd"))
    (fp_rect (start -0.5 0.25) (end 0.5 -0.25)
      (stroke (width 0.15) (type solid)) (fill none) (layer "B.Fab"))
    (pad "1" smd roundrect (at -0.485 0 90) (size 0.59 0.64) (layers "B.Cu" "B.Paste" "B.Mask") (roundrect_rratio 0.25)
      (net 26 "/AUDIO_MASTER_CLK") (pintype "passive"))
    (pad "2" smd roundrect (at 0.485 0 90) (size 0.59 0.64) (layers "B.Cu" "B.Paste" "B.Mask") (roundrect_rratio 0.25)
      (net 63 "Net-(U2A-AMCLK)") (pintype "passive"))
  )

  (footprint "sdi-mipi-bridge-footprints:R_0402_1005Metric" (layer "B.Cu")
    (at 118.75 124 90)
    (descr "Resistor SMD 0402")
    (tags "resistor SMD 0402")
    (property "Author" "Antmicro")
    (property "License" "Apache-2.0")
    (property "MPN" "CR0402-FX-22R0GLF")
    (property "Manufacturer" "Bourns")
    (property "Sheetfile" "sdi-mipi-bridge.kicad_sch")
    (property "Sheetname" "")
    (property "Tolerance" "1%")
    (property "Val" "22R")
    (property "ki_description" "22R resistor in 0402 package with 1% tolerance")
    (attr smd)
    (fp_text reference "R2" (at 1.4 0.45 90) (layer "B.SilkS")
        (effects (font (size 0.7 0.7) (thickness 0.15)) (justify right bottom mirror))
    )
    (fp_text value "R_22R_0402" (at 0 -1.4 90) (layer "B.Fab") hide
        (effects (font (size 0.7 0.7) (thickness 0.15)) (justify right bottom mirror))
    )
    (fp_text user "License: Apache-2.0" (at -0.95 -5.169 90) (layer "B.Fab") hide
        (effects (font (size 0.7 0.7) (thickness 0.15)) (justify right bottom mirror))
    )
    (fp_text user "Author: Antmicro" (at -0.95 -4.169 90) (layer "B.Fab") hide
        (effects (font (size 0.7 0.7) (thickness 0.15)) (justify right bottom mirror))
    )
    (fp_text user "${REFERENCE}" (at -0.95 -3.168 90) (layer "B.Fab") hide
        (effects (font (size 0.7 0.7) (thickness 0.15)) (justify right bottom mirror))
    )
    (fp_rect (start -0.93 0.47) (end 0.93 -0.47)
      (stroke (width 0.05) (type solid)) (fill none) (layer "B.CrtYd"))
    (fp_rect (start -0.5 0.25) (end 0.5 -0.25)
      (stroke (width 0.15) (type solid)) (fill none) (layer "B.Fab"))
    (pad "1" smd roundrect (at -0.485 0 90) (size 0.59 0.64) (layers "B.Cu" "B.Paste" "B.Mask") (roundrect_rratio 0.25)
      (net 28 "/AUDIO_SERIAL_BIT_CLK") (pintype "passive"))
    (pad "2" smd roundrect (at 0.485 0 90) (size 0.59 0.64) (layers "B.Cu" "B.Paste" "B.Mask") (roundrect_rratio 0.25)
      (net 64 "Net-(U2A-ACLK)") (pintype "passive"))
  )

  (footprint "sdi-mipi-bridge-footprints:R_0402_1005Metric" (layer "B.Cu")
    (at 117.75 124 90)
    (descr "Resistor SMD 0402")
    (tags "resistor SMD 0402")
    (property "Author" "Antmicro")
    (property "License" "Apache-2.0")
    (property "MPN" "CR0402-FX-22R0GLF")
    (property "Manufacturer" "Bourns")
    (property "Sheetfile" "sdi-mipi-bridge.kicad_sch")
    (property "Sheetname" "")
    (property "Tolerance" "1%")
    (property "Val" "22R")
    (property "ki_description" "22R resistor in 0402 package with 1% tolerance")
    (attr smd)
    (fp_text reference "R3" (at 1.4 0.45 90) (layer "B.SilkS")
        (effects (font (size 0.7 0.7) (thickness 0.15)) (justify right bottom mirror))
    )
    (fp_text value "R_22R_0402" (at 0 -1.4 90) (layer "B.Fab") hide
        (effects (font (size 0.7 0.7) (thickness 0.15)) (justify right bottom mirror))
    )
    (fp_text user "${REFERENCE}" (at -0.95 -3.168 90) (layer "B.Fab") hide
        (effects (font (size 0.7 0.7) (thickness 0.15)) (justify right bottom mirror))
    )
    (fp_text user "Author: Antmicro" (at -0.95 -4.169 90) (layer "B.Fab") hide
        (effects (font (size 0.7 0.7) (thickness 0.15)) (justify right bottom mirror))
    )
    (fp_text user "License: Apache-2.0" (at -0.95 -5.169 90) (layer "B.Fab") hide
        (effects (font (size 0.7 0.7) (thickness 0.15)) (justify right bottom mirror))
    )
    (fp_rect (start -0.93 0.47) (end 0.93 -0.47)
      (stroke (width 0.05) (type solid)) (fill none) (layer "B.CrtYd"))
    (fp_rect (start -0.5 0.25) (end 0.5 -0.25)
      (stroke (width 0.15) (type solid)) (fill none) (layer "B.Fab"))
    (pad "1" smd roundrect (at -0.485 0 90) (size 0.59 0.64) (layers "B.Cu" "B.Paste" "B.Mask") (roundrect_rratio 0.25)
      (net 60 "/AUDIO_WORD_CLK") (pintype "passive"))
    (pad "2" smd roundrect (at 0.485 0 90) (size 0.59 0.64) (layers "B.Cu" "B.Paste" "B.Mask") (roundrect_rratio 0.25)
      (net 66 "Net-(U2A-WCLK)") (pintype "passive"))
  )

  (footprint "sdi-mipi-bridge-footprints:C_0402_1005Metric" (layer "B.Cu")
    (at 122.5 110.9 90)
    (descr "Capacitor SMD 0402")
    (tags "capacitor SMD 0402")
    (property "Author" "Antmicro")
    (property "Dielectric" "X7R")
    (property "License" "Apache-2.0")
    (property "MPN" "GRM155R71H103KA88D")
    (property "Manufacturer" "Murata")
    (property "Sheetfile" "sdi-mipi-bridge.kicad_sch")
    (property "Sheetname" "")
    (property "Val" "10n")
    (property "Voltage" "50V")
    (property "ki_description" " ")
    (attr smd)
    (fp_text reference "C3" (at -0.9 0.3 90) (layer "B.SilkS")
        (effects (font (size 0.7 0.7) (thickness 0.15)) (justify left bottom mirror))
    )
    (fp_text value "C_10n_0402" (at 0 -1.4 90) (layer "B.Fab") hide
        (effects (font (size 0.7 0.7) (thickness 0.15)) (justify right bottom mirror))
    )
    (fp_text user "License: Apache-2.0" (at -0.932 -5.17 90) (layer "B.Fab") hide
        (effects (font (size 0.7 0.7) (thickness 0.15)) (justify right bottom mirror))
    )
    (fp_text user "${REFERENCE}" (at -0.932 -3.168 90) (layer "B.Fab") hide
        (effects (font (size 0.7 0.7) (thickness 0.15)) (justify right bottom mirror))
    )
    (fp_text user "Author: Antmicro" (at -0.932 -4.17 90) (layer "B.Fab") hide
        (effects (font (size 0.7 0.7) (thickness 0.15)) (justify right bottom mirror))
    )
    (fp_rect (start -0.94 0.47) (end 0.94 -0.47)
      (stroke (width 0.05) (type solid)) (fill none) (layer "B.CrtYd"))
    (fp_rect (start -0.499 0.249) (end 0.499 -0.249)
      (stroke (width 0.15) (type solid)) (fill none) (layer "B.Fab"))
    (pad "1" smd roundrect (at -0.484 0 90) (size 0.59 0.64) (layers "B.Cu" "B.Paste" "B.Mask") (roundrect_rratio 0.25)
      (net 1 "GNDREF") (pintype "passive"))
    (pad "2" smd roundrect (at 0.484 0 90) (size 0.59 0.64) (layers "B.Cu" "B.Paste" "B.Mask") (roundrect_rratio 0.25)
      (net 76 "IO_VDD") (pintype "passive"))
  )

  (footprint "sdi-mipi-bridge-footprints:C_0402_1005Metric" (layer "B.Cu")
    (at 121 117.4 -90)
    (descr "Capacitor SMD 0402")
    (tags "capacitor SMD 0402")
    (property "Author" "Antmicro")
    (property "Dielectric" "X7R")
    (property "License" "Apache-2.0")
    (property "MPN" "GRM155R71H103KA88D")
    (property "Manufacturer" "Murata")
    (property "Sheetfile" "sdi-mipi-bridge.kicad_sch")
    (property "Sheetname" "")
    (property "Val" "10n")
    (property "Voltage" "50V")
    (property "ki_description" " ")
    (attr smd)
    (fp_text reference "C4" (at 1 -0.4 90) (layer "B.SilkS")
        (effects (font (size 0.7 0.7) (thickness 0.15)) (justify left bottom mirror))
    )
    (fp_text value "C_10n_0402" (at 0 -1.4 90) (layer "B.Fab") hide
        (effects (font (size 0.7 0.7) (thickness 0.15)) (justify left bottom mirror))
    )
    (fp_text user "${REFERENCE}" (at -0.932 -3.168 90) (layer "B.Fab") hide
        (effects (font (size 0.7 0.7) (thickness 0.15)) (justify left bottom mirror))
    )
    (fp_text user "License: Apache-2.0" (at -0.932 -5.17 90) (layer "B.Fab") hide
        (effects (font (size 0.7 0.7) (thickness 0.15)) (justify left bottom mirror))
    )
    (fp_text user "Author: Antmicro" (at -0.932 -4.17 90) (layer "B.Fab") hide
        (effects (font (size 0.7 0.7) (thickness 0.15)) (justify left bottom mirror))
    )
    (fp_rect (start -0.94 0.47) (end 0.94 -0.47)
      (stroke (width 0.05) (type solid)) (fill none) (layer "B.CrtYd"))
    (fp_rect (start -0.499 0.249) (end 0.499 -0.249)
      (stroke (width 0.15) (type solid)) (fill none) (layer "B.Fab"))
    (pad "1" smd roundrect (at -0.484 0 270) (size 0.59 0.64) (layers "B.Cu" "B.Paste" "B.Mask") (roundrect_rratio 0.25)
      (net 1 "GNDREF") (pintype "passive"))
    (pad "2" smd roundrect (at 0.484 0 270) (size 0.59 0.64) (layers "B.Cu" "B.Paste" "B.Mask") (roundrect_rratio 0.25)
      (net 2 "+1V2") (pintype "passive"))
  )

  (footprint "sdi-mipi-bridge-footprints:C_0402_1005Metric" (layer "B.Cu")
    (at 123.5 110.9 -90)
    (descr "Capacitor SMD 0402")
    (tags "capacitor SMD 0402")
    (property "Author" "Antmicro")
    (property "Dielectric" "X7R")
    (property "License" "Apache-2.0")
    (property "MPN" "GRM155R71H103KA88D")
    (property "Manufacturer" "Murata")
    (property "Sheetfile" "sdi-mipi-bridge.kicad_sch")
    (property "Sheetname" "")
    (property "Val" "10n")
    (property "Voltage" "50V")
    (property "ki_description" " ")
    (attr smd)
    (fp_text reference "C5" (at 0.9 -0.3 90) (layer "B.SilkS")
        (effects (font (size 0.7 0.7) (thickness 0.15)) (justify left bottom mirror))
    )
    (fp_text value "C_10n_0402" (at 0 -1.4 90) (layer "B.Fab") hide
        (effects (font (size 0.7 0.7) (thickness 0.15)) (justify left bottom mirror))
    )
    (fp_text user "${REFERENCE}" (at -0.932 -3.168 90) (layer "B.Fab") hide
        (effects (font (size 0.7 0.7) (thickness 0.15)) (justify left bottom mirror))
    )
    (fp_text user "License: Apache-2.0" (at -0.932 -5.17 90) (layer "B.Fab") hide
        (effects (font (size 0.7 0.7) (thickness 0.15)) (justify left bottom mirror))
    )
    (fp_text user "Author: Antmicro" (at -0.932 -4.17 90) (layer "B.Fab") hide
        (effects (font (size 0.7 0.7) (thickness 0.15)) (justify left bottom mirror))
    )
    (fp_rect (start -0.94 0.47) (end 0.94 -0.47)
      (stroke (width 0.05) (type solid)) (fill none) (layer "B.CrtYd"))
    (fp_rect (start -0.499 0.249) (end 0.499 -0.249)
      (stroke (width 0.15) (type solid)) (fill none) (layer "B.Fab"))
    (pad "1" smd roundrect (at -0.484 0 270) (size 0.59 0.64) (layers "B.Cu" "B.Paste" "B.Mask") (roundrect_rratio 0.25)
      (net 1 "GNDREF") (pintype "passive"))
    (pad "2" smd roundrect (at 0.484 0 270) (size 0.59 0.64) (layers "B.Cu" "B.Paste" "B.Mask") (roundrect_rratio 0.25)
      (net 76 "IO_VDD") (pintype "passive"))
  )

  (footprint "sdi-mipi-bridge-footprints:C_0402_1005Metric" (layer "B.Cu")
    (at 124.5 110.9 -90)
    (descr "Capacitor SMD 0402")
    (tags "capacitor SMD 0402")
    (property "Author" "Antmicro")
    (property "Dielectric" "X7R")
    (property "License" "Apache-2.0")
    (property "MPN" "GRM155R71H103KA88D")
    (property "Manufacturer" "Murata")
    (property "Sheetfile" "sdi-mipi-bridge.kicad_sch")
    (property "Sheetname" "")
    (property "Val" "10n")
    (property "Voltage" "50V")
    (property "ki_description" " ")
    (attr smd)
    (fp_text reference "C9" (at 0.9 -0.3 90) (layer "B.SilkS")
        (effects (font (size 0.7 0.7) (thickness 0.15)) (justify left bottom mirror))
    )
    (fp_text value "C_10n_0402" (at 0 -1.4 90) (layer "B.Fab") hide
        (effects (font (size 0.7 0.7) (thickness 0.15)) (justify left bottom mirror))
    )
    (fp_text user "License: Apache-2.0" (at -0.932 -5.17 90) (layer "B.Fab") hide
        (effects (font (size 0.7 0.7) (thickness 0.15)) (justify left bottom mirror))
    )
    (fp_text user "Author: Antmicro" (at -0.932 -4.17 90) (layer "B.Fab") hide
        (effects (font (size 0.7 0.7) (thickness 0.15)) (justify left bottom mirror))
    )
    (fp_text user "${REFERENCE}" (at -0.932 -3.168 90) (layer "B.Fab") hide
        (effects (font (size 0.7 0.7) (thickness 0.15)) (justify left bottom mirror))
    )
    (fp_rect (start -0.94 0.47) (end 0.94 -0.47)
      (stroke (width 0.05) (type solid)) (fill none) (layer "B.CrtYd"))
    (fp_rect (start -0.499 0.249) (end 0.499 -0.249)
      (stroke (width 0.15) (type solid)) (fill none) (layer "B.Fab"))
    (pad "1" smd roundrect (at -0.484 0 270) (size 0.59 0.64) (layers "B.Cu" "B.Paste" "B.Mask") (roundrect_rratio 0.25)
      (net 1 "GNDREF") (pintype "passive"))
    (pad "2" smd roundrect (at 0.484 0 270) (size 0.59 0.64) (layers "B.Cu" "B.Paste" "B.Mask") (roundrect_rratio 0.25)
      (net 76 "IO_VDD") (pintype "passive"))
  )

  (footprint "sdi-mipi-bridge-footprints:C_0402_1005Metric" (layer "B.Cu")
    (at 116.5 112.9 90)
    (descr "Capacitor SMD 0402")
    (tags "capacitor SMD 0402")
    (property "Author" "Antmicro")
    (property "Dielectric" "X7R")
    (property "License" "Apache-2.0")
    (property "MPN" "GRM155R71H103KA88D")
    (property "Manufacturer" "Murata")
    (property "Sheetfile" "sdi-mipi-bridge.kicad_sch")
    (property "Sheetname" "")
    (property "Val" "10n")
    (property "Voltage" "50V")
    (property "ki_description" " ")
    (attr smd)
    (fp_text reference "C12" (at -1.1 -0.7 90) (layer "B.SilkS")
        (effects (font (size 0.7 0.7) (thickness 0.15)) (justify right bottom mirror))
    )
    (fp_text value "C_10n_0402" (at 0 -1.4 90) (layer "B.Fab") hide
        (effects (font (size 0.7 0.7) (thickness 0.15)) (justify right bottom mirror))
    )
    (fp_text user "${REFERENCE}" (at -0.932 -3.168 90) (layer "B.Fab") hide
        (effects (font (size 0.7 0.7) (thickness 0.15)) (justify right bottom mirror))
    )
    (fp_text user "Author: Antmicro" (at -0.932 -4.17 90) (layer "B.Fab") hide
        (effects (font (size 0.7 0.7) (thickness 0.15)) (justify right bottom mirror))
    )
    (fp_text user "License: Apache-2.0" (at -0.932 -5.17 90) (layer "B.Fab") hide
        (effects (font (size 0.7 0.7) (thickness 0.15)) (justify right bottom mirror))
    )
    (fp_rect (start -0.94 0.47) (end 0.94 -0.47)
      (stroke (width 0.05) (type solid)) (fill none) (layer "B.CrtYd"))
    (fp_rect (start -0.499 0.249) (end 0.499 -0.249)
      (stroke (width 0.15) (type solid)) (fill none) (layer "B.Fab"))
    (pad "1" smd roundrect (at -0.484 0 90) (size 0.59 0.64) (layers "B.Cu" "B.Paste" "B.Mask") (roundrect_rratio 0.25)
      (net 3 "GNDA") (pintype "passive"))
    (pad "2" smd roundrect (at 0.484 0 90) (size 0.59 0.64) (layers "B.Cu" "B.Paste" "B.Mask") (roundrect_rratio 0.25)
      (net 5 "+3.3VA") (pintype "passive"))
  )

  (footprint "sdi-mipi-bridge-footprints:C_0402_1005Metric" (layer "B.Cu")
    (at 116.5 115.4 90)
    (descr "Capacitor SMD 0402")
    (tags "capacitor SMD 0402")
    (property "Author" "Antmicro")
    (property "Dielectric" "X7R")
    (property "License" "Apache-2.0")
    (property "MPN" "GRM155R71H103KA88D")
    (property "Manufacturer" "Murata")
    (property "Sheetfile" "sdi-mipi-bridge.kicad_sch")
    (property "Sheetname" "")
    (property "Val" "10n")
    (property "Voltage" "50V")
    (property "ki_description" " ")
    (attr smd)
    (fp_text reference "C14" (at -1 1.3 90) (layer "B.SilkS")
        (effects (font (size 0.7 0.7) (thickness 0.15)) (justify right bottom mirror))
    )
    (fp_text value "C_10n_0402" (at 0 -1.4 90) (layer "B.Fab") hide
        (effects (font (size 0.7 0.7) (thickness 0.15)) (justify right bottom mirror))
    )
    (fp_text user "Author: Antmicro" (at -0.932 -4.17 90) (layer "B.Fab") hide
        (effects (font (size 0.7 0.7) (thickness 0.15)) (justify right bottom mirror))
    )
    (fp_text user "${REFERENCE}" (at -0.932 -3.168 90) (layer "B.Fab") hide
        (effects (font (size 0.7 0.7) (thickness 0.15)) (justify right bottom mirror))
    )
    (fp_text user "License: Apache-2.0" (at -0.932 -5.17 90) (layer "B.Fab") hide
        (effects (font (size 0.7 0.7) (thickness 0.15)) (justify right bottom mirror))
    )
    (fp_rect (start -0.94 0.47) (end 0.94 -0.47)
      (stroke (width 0.05) (type solid)) (fill none) (layer "B.CrtYd"))
    (fp_rect (start -0.499 0.249) (end 0.499 -0.249)
      (stroke (width 0.15) (type solid)) (fill none) (layer "B.Fab"))
    (pad "1" smd roundrect (at -0.484 0 90) (size 0.59 0.64) (layers "B.Cu" "B.Paste" "B.Mask") (roundrect_rratio 0.25)
      (net 3 "GNDA") (pintype "passive"))
    (pad "2" smd roundrect (at 0.484 0 90) (size 0.59 0.64) (layers "B.Cu" "B.Paste" "B.Mask") (roundrect_rratio 0.25)
      (net 5 "+3.3VA") (pintype "passive"))
  )

  (footprint "sdi-mipi-bridge-footprints:C_0402_1005Metric" (layer "B.Cu")
    (at 116.5 118.4 90)
    (descr "Capacitor SMD 0402")
    (tags "capacitor SMD 0402")
    (property "Author" "Antmicro")
    (property "Dielectric" "X7R")
    (property "License" "Apache-2.0")
    (property "MPN" "GRM155R71H103KA88D")
    (property "Manufacturer" "Murata")
    (property "Sheetfile" "sdi-mipi-bridge.kicad_sch")
    (property "Sheetname" "")
    (property "Val" "10n")
    (property "Voltage" "50V")
    (property "ki_description" " ")
    (attr smd)
    (fp_text reference "C17" (at -1 1.3 90) (layer "B.SilkS")
        (effects (font (size 0.7 0.7) (thickness 0.15)) (justify right bottom mirror))
    )
    (fp_text value "C_10n_0402" (at 0 -1.4 90) (layer "B.Fab") hide
        (effects (font (size 0.7 0.7) (thickness 0.15)) (justify right bottom mirror))
    )
    (fp_text user "${REFERENCE}" (at -0.932 -3.168 90) (layer "B.Fab") hide
        (effects (font (size 0.7 0.7) (thickness 0.15)) (justify right bottom mirror))
    )
    (fp_text user "Author: Antmicro" (at -0.932 -4.17 90) (layer "B.Fab") hide
        (effects (font (size 0.7 0.7) (thickness 0.15)) (justify right bottom mirror))
    )
    (fp_text user "License: Apache-2.0" (at -0.932 -5.17 90) (layer "B.Fab") hide
        (effects (font (size 0.7 0.7) (thickness 0.15)) (justify right bottom mirror))
    )
    (fp_rect (start -0.94 0.47) (end 0.94 -0.47)
      (stroke (width 0.05) (type solid)) (fill none) (layer "B.CrtYd"))
    (fp_rect (start -0.499 0.249) (end 0.499 -0.249)
      (stroke (width 0.15) (type solid)) (fill none) (layer "B.Fab"))
    (pad "1" smd roundrect (at -0.484 0 90) (size 0.59 0.64) (layers "B.Cu" "B.Paste" "B.Mask") (roundrect_rratio 0.25)
      (net 3 "GNDA") (pintype "passive"))
    (pad "2" smd roundrect (at 0.484 0 90) (size 0.59 0.64) (layers "B.Cu" "B.Paste" "B.Mask") (roundrect_rratio 0.25)
      (net 5 "+3.3VA") (pintype "passive"))
  )

  (footprint "sdi-mipi-bridge-footprints:C_0402_1005Metric" (layer "B.Cu")
    (at 125.5 110.9 -90)
    (descr "Capacitor SMD 0402")
    (tags "capacitor SMD 0402")
    (property "Author" "Antmicro")
    (property "Dielectric" "")
    (property "License" "Apache-2.0")
    (property "MPN" "C1005X6S1A105K050BC")
    (property "Manufacturer" "TDK")
    (property "Sheetfile" "sdi-mipi-bridge.kicad_sch")
    (property "Sheetname" "")
    (property "Val" "1u")
    (property "Voltage" "")
    (property "ki_description" " ")
    (attr smd)
    (fp_text reference "C35" (at 0.9 -0.3 90) (layer "B.SilkS")
        (effects (font (size 0.7 0.7) (thickness 0.15)) (justify left bottom mirror))
    )
    (fp_text value "C_1u_0402" (at 0 -1.4 90) (layer "B.Fab") hide
        (effects (font (size 0.7 0.7) (thickness 0.15)) (justify left bottom mirror))
    )
    (fp_text user "Author: Antmicro" (at -0.932 -4.17 90) (layer "B.Fab") hide
        (effects (font (size 0.7 0.7) (thickness 0.15)) (justify left bottom mirror))
    )
    (fp_text user "License: Apache-2.0" (at -0.932 -5.17 90) (layer "B.Fab") hide
        (effects (font (size 0.7 0.7) (thickness 0.15)) (justify left bottom mirror))
    )
    (fp_text user "${REFERENCE}" (at -0.932 -3.168 90) (layer "B.Fab") hide
        (effects (font (size 0.7 0.7) (thickness 0.15)) (justify left bottom mirror))
    )
    (fp_rect (start -0.94 0.47) (end 0.94 -0.47)
      (stroke (width 0.05) (type solid)) (fill none) (layer "B.CrtYd"))
    (fp_rect (start -0.499 0.249) (end 0.499 -0.249)
      (stroke (width 0.15) (type solid)) (fill none) (layer "B.Fab"))
    (pad "1" smd roundrect (at -0.484 0 270) (size 0.59 0.64) (layers "B.Cu" "B.Paste" "B.Mask") (roundrect_rratio 0.25)
      (net 1 "GNDREF") (pintype "passive"))
    (pad "2" smd roundrect (at 0.484 0 270) (size 0.59 0.64) (layers "B.Cu" "B.Paste" "B.Mask") (roundrect_rratio 0.25)
      (net 76 "IO_VDD") (pintype "passive"))
  )

  (footprint "sdi-mipi-bridge-footprints:R_0402_1005Metric" (layer "B.Cu")
    (at 120 110.9 90)
    (descr "Resistor SMD 0402")
    (tags "resistor SMD 0402")
    (property "Author" "Antmicro")
    (property "License" "Apache-2.0")
    (property "MPN" "CR0402-FX-1050GLF")
    (property "Manufacturer" "Bourns")
    (property "Sheetfile" "sdi-mipi-bridge.kicad_sch")
    (property "Sheetname" "")
    (property "Tolerance" "1%")
    (property "Val" "105R")
    (property "ki_description" "105R resistor in 0402 package with 1% tolerance")
    (attr smd)
    (fp_text reference "R30" (at 2.1 0.4 90) (layer "B.SilkS")
        (effects (font (size 0.7 0.7) (thickness 0.15)) (justify right bottom mirror))
    )
    (fp_text value "R_105R_0402" (at 0 -1.4 90) (layer "B.Fab") hide
        (effects (font (size 0.7 0.7) (thickness 0.15)) (justify right bottom mirror))
    )
    (fp_text user "Author: Antmicro" (at -0.95 -4.169 90) (layer "B.Fab") hide
        (effects (font (size 0.7 0.7) (thickness 0.15)) (justify right bottom mirror))
    )
    (fp_text user "${REFERENCE}" (at -0.95 -3.168 90) (layer "B.Fab") hide
        (effects (font (size 0.7 0.7) (thickness 0.15)) (justify right bottom mirror))
    )
    (fp_text user "License: Apache-2.0" (at -0.95 -5.169 90) (layer "B.Fab") hide
        (effects (font (size 0.7 0.7) (thickness 0.15)) (justify right bottom mirror))
    )
    (fp_rect (start -0.93 0.47) (end 0.93 -0.47)
      (stroke (width 0.05) (type solid)) (fill none) (layer "B.CrtYd"))
    (fp_rect (start -0.5 0.25) (end 0.5 -0.25)
      (stroke (width 0.15) (type solid)) (fill none) (layer "B.Fab"))
    (pad "1" smd roundrect (at -0.485 0 90) (size 0.59 0.64) (layers "B.Cu" "B.Paste" "B.Mask") (roundrect_rratio 0.25)
      (net 4 "VPP") (pintype "passive"))
    (pad "2" smd roundrect (at 0.485 0 90) (size 0.59 0.64) (layers "B.Cu" "B.Paste" "B.Mask") (roundrect_rratio 0.25)
      (net 78 "VCO_VDD") (pintype "passive"))
  )

  (footprint "sdi-mipi-bridge-footprints:C_0603_1608Metric" (layer "B.Cu")
    (at 121.25 110.85 -90)
    (descr "Capacitor SMD 0603")
    (tags "capacitor 0603")
    (property "Author" "Antmicro")
    (property "Dielectric" "")
    (property "License" "Apache-2.0")
    (property "MPN" "F980G336MMA")
    (property "Manufacturer" "AVX")
    (property "Sheetfile" "sdi-mipi-bridge.kicad_sch")
    (property "Sheetname" "")
    (property "Val" "33u")
    (property "Voltage" "")
    (property "ki_description" " ")
    (attr smd)
    (fp_text reference "C58" (at -4.25 -0.35 90) (layer "B.SilkS")
        (effects (font (size 0.7 0.7) (thickness 0.15)) (justify left bottom mirror))
    )
    (fp_text value "C_33u_0603" (at 0 -1.6 90) (layer "B.Fab") hide
        (effects (font (size 0.7 0.7) (thickness 0.15)) (justify left bottom mirror))
    )
    (fp_text user "License: Apache-2.0" (at -1.682 -5.895 90) (layer "B.Fab") hide
        (effects (font (size 0.7 0.7) (thickness 0.15)) (justify left bottom mirror))
    )
    (fp_text user "Author: Antmicro" (at -1.682 -4.894 90) (layer "B.Fab") hide
        (effects (font (size 0.7 0.7) (thickness 0.15)) (justify left bottom mirror))
    )
    (fp_text user "${REFERENCE}" (at -1.682 -3.895 90) (layer "B.Fab") hide
        (effects (font (size 0.7 0.7) (thickness 0.15)) (justify left bottom mirror))
    )
    (fp_line (start -0.3 -0.3) (end 0.3 -0.3)
      (stroke (width 0.15) (type solid)) (layer "B.SilkS"))
    (fp_line (start -0.3 0.3) (end 0.3 0.3)
      (stroke (width 0.15) (type solid)) (layer "B.SilkS"))
    (fp_rect (start -1.24 0.7) (end 1.24 -0.7)
      (stroke (width 0.05) (type solid)) (fill none) (layer "B.CrtYd"))
    (fp_rect (start -0.8 0.4) (end 0.8 -0.4)
      (stroke (width 0.15) (type solid)) (fill none) (layer "B.Fab"))
    (pad "1" smd roundrect (at -0.7 0 270) (size 0.6 0.8) (layers "B.Cu" "B.Paste" "B.Mask") (roundrect_rratio 0.2)
      (net 78 "VCO_VDD") (pintype "passive"))
    (pad "2" smd roundrect (at 0.7 0 270) (size 0.6 0.8) (layers "B.Cu" "B.Paste" "B.Mask") (roundrect_rratio 0.2)
      (net 3 "GNDA") (pintype "passive"))
  )

  (footprint "sdi-mipi-bridge-footprints:C_0402_1005Metric" (layer "B.Cu")
    (at 145.465 109.525 -90)
    (descr "Capacitor SMD 0402")
    (tags "capacitor SMD 0402")
    (property "Author" "Antmicro")
    (property "Dielectric" "")
    (property "License" "Apache-2.0")
    (property "MPN" "C1005X5R1A225K050BC")
    (property "Manufacturer" "TDK")
    (property "Sheetfile" "sdi-mipi-bridge.kicad_sch")
    (property "Sheetname" "")
    (property "Val" "2u2")
    (property "Voltage" "")
    (property "ki_description" " ")
    (attr smd)
    (fp_text reference "C37" (at -5.124 3.3825 90) (layer "B.SilkS")
        (effects (font (size 0.7 0.7) (thickness 0.15)) (justify left bottom mirror))
    )
    (fp_text value "C_2u2_0402" (at 0 -1.4 90) (layer "B.Fab") hide
        (effects (font (size 0.7 0.7) (thickness 0.15)) (justify left bottom mirror))
    )
    (fp_text user "Author: Antmicro" (at -0.932 -4.17 90) (layer "B.Fab") hide
        (effects (font (size 0.7 0.7) (thickness 0.15)) (justify left bottom mirror))
    )
    (fp_text user "${REFERENCE}" (at -0.932 -3.168 90) (layer "B.Fab") hide
        (effects (font (size 0.7 0.7) (thickness 0.15)) (justify left bottom mirror))
    )
    (fp_text user "License: Apache-2.0" (at -0.932 -5.17 90) (layer "B.Fab") hide
        (effects (font (size 0.7 0.7) (thickness 0.15)) (justify left bottom mirror))
    )
    (fp_rect (start -0.94 0.47) (end 0.94 -0.47)
      (stroke (width 0.05) (type solid)) (fill none) (layer "B.CrtYd"))
    (fp_rect (start -0.499 0.249) (end 0.499 -0.249)
      (stroke (width 0.15) (type solid)) (fill none) (layer "B.Fab"))
    (pad "1" smd roundrect (at -0.484 0 270) (size 0.59 0.64) (layers "B.Cu" "B.Paste" "B.Mask") (roundrect_rratio 0.25)
      (net 1 "GNDREF") (pintype "passive"))
    (pad "2" smd roundrect (at 0.484 0 270) (size 0.59 0.64) (layers "B.Cu" "B.Paste" "B.Mask") (roundrect_rratio 0.25)
      (net 79 "VCC_IO") (pintype "passive"))
  )

  (footprint "sdi-mipi-bridge-footprints:C_0402_1005Metric" (layer "B.Cu")
    (at 142 112.23 90)
    (descr "Capacitor SMD 0402")
    (tags "capacitor SMD 0402")
    (property "Author" "Antmicro")
    (property "Dielectric" "")
    (property "License" "Apache-2.0")
    (property "MPN" "C1005X5R1A225K050BC")
    (property "Manufacturer" "TDK")
    (property "Sheetfile" "sdi-mipi-bridge.kicad_sch")
    (property "Sheetname" "")
    (property "Val" "2u2")
    (property "Voltage" "")
    (property "ki_description" " ")
    (attr smd)
    (fp_text reference "C38" (at -0.97 -0.6 90) (layer "B.SilkS")
        (effects (font (size 0.7 0.7) (thickness 0.15)) (justify right bottom mirror))
    )
    (fp_text value "C_2u2_0402" (at 0 -1.4 90) (layer "B.Fab") hide
        (effects (font (size 0.7 0.7) (thickness 0.15)) (justify right bottom mirror))
    )
    (fp_text user "Author: Antmicro" (at -0.932 -4.17 90) (layer "B.Fab") hide
        (effects (font (size 0.7 0.7) (thickness 0.15)) (justify right bottom mirror))
    )
    (fp_text user "${REFERENCE}" (at -0.932 -3.168 90) (layer "B.Fab") hide
        (effects (font (size 0.7 0.7) (thickness 0.15)) (justify right bottom mirror))
    )
    (fp_text user "License: Apache-2.0" (at -0.932 -5.17 90) (layer "B.Fab") hide
        (effects (font (size 0.7 0.7) (thickness 0.15)) (justify right bottom mirror))
    )
    (fp_rect (start -0.94 0.47) (end 0.94 -0.47)
      (stroke (width 0.05) (type solid)) (fill none) (layer "B.CrtYd"))
    (fp_rect (start -0.499 0.249) (end 0.499 -0.249)
      (stroke (width 0.15) (type solid)) (fill none) (layer "B.Fab"))
    (pad "1" smd roundrect (at -0.484 0 90) (size 0.59 0.64) (layers "B.Cu" "B.Paste" "B.Mask") (roundrect_rratio 0.25)
      (net 1 "GNDREF") (pintype "passive"))
    (pad "2" smd roundrect (at 0.484 0 90) (size 0.59 0.64) (layers "B.Cu" "B.Paste" "B.Mask") (roundrect_rratio 0.25)
      (net 77 "VCCA_DPHY") (pintype "passive"))
  )

  (footprint "sdi-mipi-bridge-footprints:C_0402_1005Metric" (layer "B.Cu")
    (at 148.99 118.87 90)
    (descr "Capacitor SMD 0402")
    (tags "capacitor SMD 0402")
    (property "Author" "Antmicro")
    (property "Dielectric" "")
    (property "License" "Apache-2.0")
    (property "MPN" "0402X104K6R3CT")
    (property "Manufacturer" "Walsin")
    (property "Sheetfile" "sdi-mipi-bridge.kicad_sch")
    (property "Sheetname" "")
    (property "Val" "100n")
    (property "Voltage" "")
    (property "ki_description" " ")
    (attr smd)
    (fp_text reference "C48" (at -6.73 9.21 90) (layer "B.SilkS")
        (effects (font (size 0.7 0.7) (thickness 0.15)) (justify left bottom mirror))
    )
    (fp_text value "C_100n_6V3_0402" (at 0 -1.4 90) (layer "B.Fab") hide
        (effects (font (size 0.7 0.7) (thickness 0.15)) (justify right bottom mirror))
    )
    (fp_text user "${REFERENCE}" (at -0.932 -3.168 90) (layer "B.Fab") hide
        (effects (font (size 0.7 0.7) (thickness 0.15)) (justify right bottom mirror))
    )
    (fp_text user "Author: Antmicro" (at -0.932 -4.17 90) (layer "B.Fab") hide
        (effects (font (size 0.7 0.7) (thickness 0.15)) (justify right bottom mirror))
    )
    (fp_text user "License: Apache-2.0" (at -0.932 -5.17 90) (layer "B.Fab") hide
        (effects (font (size 0.7 0.7) (thickness 0.15)) (justify right bottom mirror))
    )
    (fp_rect (start -0.94 0.47) (end 0.94 -0.47)
      (stroke (width 0.05) (type solid)) (fill none) (layer "B.CrtYd"))
    (fp_rect (start -0.499 0.249) (end 0.499 -0.249)
      (stroke (width 0.15) (type solid)) (fill none) (layer "B.Fab"))
    (pad "1" smd roundrect (at -0.484 0 90) (size 0.59 0.64) (layers "B.Cu" "B.Paste" "B.Mask") (roundrect_rratio 0.25)
      (net 1 "GNDREF") (pintype "passive"))
    (pad "2" smd roundrect (at 0.484 0 90) (size 0.59 0.64) (layers "B.Cu" "B.Paste" "B.Mask") (roundrect_rratio 0.25)
      (net 2 "+1V2") (pintype "passive"))
  )

  (footprint "sdi-mipi-bridge-footprints:C_0402_1005Metric" (layer "B.Cu")
    (at 148.95 112.94 -90)
    (descr "Capacitor SMD 0402")
    (tags "capacitor SMD 0402")
    (property "Author" "Antmicro")
    (property "Dielectric" "")
    (property "License" "Apache-2.0")
    (property "MPN" "C1005X6S1A105K050BC")
    (property "Manufacturer" "TDK")
    (property "Sheetfile" "sdi-mipi-bridge.kicad_sch")
    (property "Sheetname" "")
    (property "Val" "1u")
    (property "Voltage" "")
    (property "ki_description" " ")
    (attr smd)
    (fp_text reference "C45" (at 6.66 -9.25 90) (layer "B.SilkS")
        (effects (font (size 0.7 0.7) (thickness 0.15)) (justify left bottom mirror))
    )
    (fp_text value "C_1u_0402" (at 0 -1.4 90) (layer "B.Fab") hide
        (effects (font (size 0.7 0.7) (thickness 0.15)) (justify left bottom mirror))
    )
    (fp_text user "License: Apache-2.0" (at -0.932 -5.17 90) (layer "B.Fab") hide
        (effects (font (size 0.7 0.7) (thickness 0.15)) (justify left bottom mirror))
    )
    (fp_text user "Author: Antmicro" (at -0.932 -4.17 90) (layer "B.Fab") hide
        (effects (font (size 0.7 0.7) (thickness 0.15)) (justify left bottom mirror))
    )
    (fp_text user "${REFERENCE}" (at -0.932 -3.168 90) (layer "B.Fab") hide
        (effects (font (size 0.7 0.7) (thickness 0.15)) (justify left bottom mirror))
    )
    (fp_rect (start -0.94 0.47) (end 0.94 -0.47)
      (stroke (width 0.05) (type solid)) (fill none) (layer "B.CrtYd"))
    (fp_rect (start -0.499 0.249) (end 0.499 -0.249)
      (stroke (width 0.15) (type solid)) (fill none) (layer "B.Fab"))
    (pad "1" smd roundrect (at -0.484 0 270) (size 0.59 0.64) (layers "B.Cu" "B.Paste" "B.Mask") (roundrect_rratio 0.25)
      (net 1 "GNDREF") (pintype "passive"))
    (pad "2" smd roundrect (at 0.484 0 270) (size 0.59 0.64) (layers "B.Cu" "B.Paste" "B.Mask") (roundrect_rratio 0.25)
      (net 141 "Net-(C45-Pad2)") (pintype "passive"))
  )

  (footprint "sdi-mipi-bridge-footprints:C_0402_1005Metric" (layer "B.Cu")
    (at 149.02 116.9 -90)
    (descr "Capacitor SMD 0402")
    (tags "capacitor SMD 0402")
    (property "Author" "Antmicro")
    (property "Dielectric" "")
    (property "License" "Apache-2.0")
    (property "MPN" "GRM155R61A475MEAAD")
    (property "Manufacturer" "Murata")
    (property "Sheetfile" "sdi-mipi-bridge.kicad_sch")
    (property "Sheetname" "")
    (property "Val" "4u7")
    (property "Voltage" "")
    (property "ki_description" " ")
    (attr smd)
    (fp_text reference "C52" (at 6.7 -9.18 90) (layer "B.SilkS")
        (effects (font (size 0.7 0.7) (thickness 0.15)) (justify left bottom mirror))
    )
    (fp_text value "C_4u7_0402" (at 0 -1.4 90) (layer "B.Fab") hide
        (effects (font (size 0.7 0.7) (thickness 0.15)) (justify left bottom mirror))
    )
    (fp_text user "License: Apache-2.0" (at -0.932 -5.17 90) (layer "B.Fab") hide
        (effects (font (size 0.7 0.7) (thickness 0.15)) (justify left bottom mirror))
    )
    (fp_text user "Author: Antmicro" (at -0.932 -4.17 90) (layer "B.Fab") hide
        (effects (font (size 0.7 0.7) (thickness 0.15)) (justify left bottom mirror))
    )
    (fp_text user "${REFERENCE}" (at -0.932 -3.168 90) (layer "B.Fab") hide
        (effects (font (size 0.7 0.7) (thickness 0.15)) (justify left bottom mirror))
    )
    (fp_rect (start -0.94 0.47) (end 0.94 -0.47)
      (stroke (width 0.05) (type solid)) (fill none) (layer "B.CrtYd"))
    (fp_rect (start -0.499 0.249) (end 0.499 -0.249)
      (stroke (width 0.15) (type solid)) (fill none) (layer "B.Fab"))
    (pad "1" smd roundrect (at -0.484 0 270) (size 0.59 0.64) (layers "B.Cu" "B.Paste" "B.Mask") (roundrect_rratio 0.25)
      (net 1 "GNDREF") (pintype "passive"))
    (pad "2" smd roundrect (at 0.484 0 270) (size 0.59 0.64) (layers "B.Cu" "B.Paste" "B.Mask") (roundrect_rratio 0.25)
      (net 2 "+1V2") (pintype "passive"))
  )

  (footprint "sdi-mipi-bridge-footprints:C_0402_1005Metric" (layer "B.Cu")
    (at 142.14 116.28 90)
    (descr "Capacitor SMD 0402")
    (tags "capacitor SMD 0402")
    (property "Author" "Antmicro")
    (property "Dielectric" "")
    (property "License" "Apache-2.0")
    (property "MPN" "C1005X6S1A105K050BC")
    (property "Manufacturer" "TDK")
    (property "Sheetfile" "sdi-mipi-bridge.kicad_sch")
    (property "Sheetname" "")
    (property "Val" "1u")
    (property "Voltage" "")
    (property "ki_description" " ")
    (attr smd)
    (fp_text reference "C47" (at -8.72 9.26 90) (layer "B.SilkS")
        (effects (font (size 0.7 0.7) (thickness 0.15)) (justify right bottom mirror))
    )
    (fp_text value "C_1u_0402" (at 0 -1.4 90) (layer "B.Fab") hide
        (effects (font (size 0.7 0.7) (thickness 0.15)) (justify right bottom mirror))
    )
    (fp_text user "License: Apache-2.0" (at -0.932 -5.17 90) (layer "B.Fab") hide
        (effects (font (size 0.7 0.7) (thickness 0.15)) (justify right bottom mirror))
    )
    (fp_text user "${REFERENCE}" (at -0.932 -3.168 90) (layer "B.Fab") hide
        (effects (font (size 0.7 0.7) (thickness 0.15)) (justify right bottom mirror))
    )
    (fp_text user "Author: Antmicro" (at -0.932 -4.17 90) (layer "B.Fab") hide
        (effects (font (size 0.7 0.7) (thickness 0.15)) (justify right bottom mirror))
    )
    (fp_rect (start -0.94 0.47) (end 0.94 -0.47)
      (stroke (width 0.05) (type solid)) (fill none) (layer "B.CrtYd"))
    (fp_rect (start -0.499 0.249) (end 0.499 -0.249)
      (stroke (width 0.15) (type solid)) (fill none) (layer "B.Fab"))
    (pad "1" smd roundrect (at -0.484 0 90) (size 0.59 0.64) (layers "B.Cu" "B.Paste" "B.Mask") (roundrect_rratio 0.25)
      (net 59 "/GNDGPLL") (pintype "passive"))
    (pad "2" smd roundrect (at 0.484 0 90) (size 0.59 0.64) (layers "B.Cu" "B.Paste" "B.Mask") (roundrect_rratio 0.25)
      (net 89 "VCCGPLL") (pintype "passive"))
  )

  (footprint "sdi-mipi-bridge-footprints:C_0402_1005Metric" (layer "B.Cu")
    (at 141.14 116.28 90)
    (descr "Capacitor SMD 0402")
    (tags "capacitor SMD 0402")
    (property "Author" "Antmicro")
    (property "Dielectric" "")
    (property "License" "Apache-2.0")
    (property "MPN" "0402X104K6R3CT")
    (property "Manufacturer" "Walsin")
    (property "Sheetfile" "sdi-mipi-bridge.kicad_sch")
    (property "Sheetname" "")
    (property "Val" "100n")
    (property "Voltage" "")
    (property "ki_description" " ")
    (attr smd)
    (fp_text reference "C51" (at -8.72 9.26 90) (layer "B.SilkS")
        (effects (font (size 0.7 0.7) (thickness 0.15)) (justify right bottom mirror))
    )
    (fp_text value "C_100n_6V3_0402" (at 0 -1.4 90) (layer "B.Fab") hide
        (effects (font (size 0.7 0.7) (thickness 0.15)) (justify right bottom mirror))
    )
    (fp_text user "Author: Antmicro" (at -0.932 -4.17 90) (layer "B.Fab") hide
        (effects (font (size 0.7 0.7) (thickness 0.15)) (justify right bottom mirror))
    )
    (fp_text user "License: Apache-2.0" (at -0.932 -5.17 90) (layer "B.Fab") hide
        (effects (font (size 0.7 0.7) (thickness 0.15)) (justify right bottom mirror))
    )
    (fp_text user "${REFERENCE}" (at -0.932 -3.168 90) (layer "B.Fab") hide
        (effects (font (size 0.7 0.7) (thickness 0.15)) (justify right bottom mirror))
    )
    (fp_rect (start -0.94 0.47) (end 0.94 -0.47)
      (stroke (width 0.05) (type solid)) (fill none) (layer "B.CrtYd"))
    (fp_rect (start -0.499 0.249) (end 0.499 -0.249)
      (stroke (width 0.15) (type solid)) (fill none) (layer "B.Fab"))
    (pad "1" smd roundrect (at -0.484 0 90) (size 0.59 0.64) (layers "B.Cu" "B.Paste" "B.Mask") (roundrect_rratio 0.25)
      (net 59 "/GNDGPLL") (pintype "passive"))
    (pad "2" smd roundrect (at 0.484 0 90) (size 0.59 0.64) (layers "B.Cu" "B.Paste" "B.Mask") (roundrect_rratio 0.25)
      (net 89 "VCCGPLL") (pintype "passive"))
  )

  (footprint "sdi-mipi-bridge-footprints:FB_0603_1608Metric" (layer "B.Cu")
    (at 147.505 109.6)
    (property "Author" "Antmicro")
    (property "License" "Apache-2.0")
    (property "MPN" "BLM18PG121SN1D")
    (property "Manufacturer" "Murata")
    (property "Sheetfile" "sdi-mipi-bridge.kicad_sch")
    (property "Sheetname" "")
    (property "ki_description" "Ferrite Beads WE-TMSB Suppression 240Ohm 200mA ")
    (property "ki_keywords" " Multilayer Suppression Beads ")
    (attr smd)
    (fp_text reference "FB2" (at 1.095 1.6 180) (layer "B.SilkS")
        (effects (font (size 0.7 0.7) (thickness 0.15)) (justify left bottom mirror))
    )
    (fp_text value "BLM18PG121SH1D" (at 0 -1.5 180) (layer "B.Fab") hide
        (effects (font (size 0.7 0.7) (thickness 0.15)) (justify left bottom mirror))
    )
    (fp_text user "${REFERENCE}" (at -1.653 -4.6 180) (layer "B.Fab") hide
        (effects (font (size 0.7 0.7) (thickness 0.15)) (justify left bottom mirror))
    )
    (fp_text user "Author: Antmicro" (at -1.653 -3.162 180) (layer "B.Fab") hide
        (effects (font (size 0.7 0.7) (thickness 0.15)) (justify left bottom mirror))
    )
    (fp_text user "License: Apache-2.0" (at -1.653 -5.9 180) (layer "B.Fab") hide
        (effects (font (size 0.7 0.7) (thickness 0.15)) (justify left bottom mirror))
    )
    (fp_line (start -0.196 -0.406) (end 0.193 -0.406)
      (stroke (width 0.15) (type solid)) (layer "B.SilkS"))
    (fp_line (start -0.196 0.408) (end 0.193 0.408)
      (stroke (width 0.15) (type solid)) (layer "B.SilkS"))
    (fp_rect (start -1.3 0.6) (end 1.3 -0.6)
      (stroke (width 0.05) (type solid)) (fill none) (layer "B.CrtYd"))
    (fp_line (start -0.803 -0.406) (end -0.803 0.408)
      (stroke (width 0.15) (type solid)) (layer "B.Fab"))
    (fp_line (start 0.8 -0.406) (end -0.803 -0.406)
      (stroke (width 0.15) (type solid)) (layer "B.Fab"))
    (fp_line (start 0.8 0.408) (end -0.803 0.408)
      (stroke (width 0.15) (type solid)) (layer "B.Fab"))
    (fp_line (start 0.8 0.408) (end 0.8 -0.406)
      (stroke (width 0.15) (type solid)) (layer "B.Fab"))
    (pad "1" smd roundrect (at -0.891 0) (size 0.762 1.09) (layers "B.Cu" "B.Paste" "B.Mask") (roundrect_rratio 0.15)
      (net 2 "+1V2") (pintype "passive"))
    (pad "2" smd roundrect (at 0.888 0) (size 0.762 1.09) (layers "B.Cu" "B.Paste" "B.Mask") (roundrect_rratio 0.15)
      (net 77 "VCCA_DPHY") (pintype "passive"))
  )

  (footprint "sdi-mipi-bridge-footprints:FB_0603_1608Metric" (layer "B.Cu")
    (at 141.65 118.6 -90)
    (property "Author" "Antmicro")
    (property "License" "Apache-2.0")
    (property "MPN" "BLM18PG121SN1D")
    (property "Manufacturer" "Murata")
    (property "Sheetfile" "sdi-mipi-bridge.kicad_sch")
    (property "Sheetname" "")
    (property "ki_description" "Ferrite Beads WE-TMSB Suppression 240Ohm 200mA ")
    (property "ki_keywords" " Multilayer Suppression Beads ")
    (attr smd)
    (fp_text reference "FB3" (at 6.8 -9.15 90) (layer "B.SilkS")
        (effects (font (size 0.7 0.7) (thickness 0.15)) (justify left bottom mirror))
    )
    (fp_text value "BLM18PG121SH1D" (at 0 -1.5 90) (layer "B.Fab") hide
        (effects (font (size 0.7 0.7) (thickness 0.15)) (justify left bottom mirror))
    )
    (fp_text user "License: Apache-2.0" (at -1.653 -5.9 90) (layer "B.Fab") hide
        (effects (font (size 0.7 0.7) (thickness 0.15)) (justify left bottom mirror))
    )
    (fp_text user "${REFERENCE}" (at -1.653 -4.6 90) (layer "B.Fab") hide
        (effects (font (size 0.7 0.7) (thickness 0.15)) (justify left bottom mirror))
    )
    (fp_text user "Author: Antmicro" (at -1.653 -3.162 90) (layer "B.Fab") hide
        (effects (font (size 0.7 0.7) (thickness 0.15)) (justify left bottom mirror))
    )
    (fp_line (start -0.196 -0.406) (end 0.193 -0.406)
      (stroke (width 0.15) (type solid)) (layer "B.SilkS"))
    (fp_line (start -0.196 0.408) (end 0.193 0.408)
      (stroke (width 0.15) (type solid)) (layer "B.SilkS"))
    (fp_rect (start -1.3 0.6) (end 1.3 -0.6)
      (stroke (width 0.05) (type solid)) (fill none) (layer "B.CrtYd"))
    (fp_line (start -0.803 -0.406) (end -0.803 0.408)
      (stroke (width 0.15) (type solid)) (layer "B.Fab"))
    (fp_line (start 0.8 -0.406) (end -0.803 -0.406)
      (stroke (width 0.15) (type solid)) (layer "B.Fab"))
    (fp_line (start 0.8 0.408) (end -0.803 0.408)
      (stroke (width 0.15) (type solid)) (layer "B.Fab"))
    (fp_line (start 0.8 0.408) (end 0.8 -0.406)
      (stroke (width 0.15) (type solid)) (layer "B.Fab"))
    (pad "1" smd roundrect (at -0.891 0 270) (size 0.762 1.09) (layers "B.Cu" "B.Paste" "B.Mask") (roundrect_rratio 0.15)
      (net 89 "VCCGPLL") (pintype "passive"))
    (pad "2" smd roundrect (at 0.888 0 270) (size 0.762 1.09) (layers "B.Cu" "B.Paste" "B.Mask") (roundrect_rratio 0.15)
      (net 2 "+1V2") (pintype "passive"))
  )

  (footprint "sdi-mipi-bridge-footprints:R_0402_1005Metric" (layer "B.Cu")
    (at 148.98 114.94 90)
    (descr "Resistor SMD 0402")
    (tags "resistor SMD 0402")
    (property "Author" "Antmicro")
    (property "Current" "1A")
    (property "License" "Apache-2.0")
    (property "MPN" "ERJ2GE0R00X")
    (property "Manufacturer" "Panasonic")
    (property "Sheetfile" "sdi-mipi-bridge.kicad_sch")
    (property "Sheetname" "")
    (property "Tolerance" "")
    (property "Val" "0R")
    (property "ki_description" "0R resistor in 0402 package with unspecified tolerance")
    (attr smd)
    (fp_text reference "R26" (at -8.86 9.22 90) (layer "B.SilkS")
        (effects (font (size 0.7 0.7) (thickness 0.15)) (justify right bottom mirror))
    )
    (fp_text value "R_0R_0402" (at 0 -1.4 90) (layer "B.Fab") hide
        (effects (font (size 0.7 0.7) (thickness 0.15)) (justify right bottom mirror))
    )
    (fp_text user "License: Apache-2.0" (at -0.95 -5.169 90) (layer "B.Fab") hide
        (effects (font (size 0.7 0.7) (thickness 0.15)) (justify right bottom mirror))
    )
    (fp_text user "Author: Antmicro" (at -0.95 -4.169 90) (layer "B.Fab") hide
        (effects (font (size 0.7 0.7) (thickness 0.15)) (justify right bottom mirror))
    )
    (fp_text user "${REFERENCE}" (at -0.95 -3.168 90) (layer "B.Fab") hide
        (effects (font (size 0.7 0.7) (thickness 0.15)) (justify right bottom mirror))
    )
    (fp_rect (start -0.93 0.47) (end 0.93 -0.47)
      (stroke (width 0.05) (type solid)) (fill none) (layer "B.CrtYd"))
    (fp_rect (start -0.5 0.25) (end 0.5 -0.25)
      (stroke (width 0.15) (type solid)) (fill none) (layer "B.Fab"))
    (pad "1" smd roundrect (at -0.485 0 90) (size 0.59 0.64) (layers "B.Cu" "B.Paste" "B.Mask") (roundrect_rratio 0.25)
      (net 6 "+3V3") (pintype "passive"))
    (pad "2" smd roundrect (at 0.485 0 90) (size 0.59 0.64) (layers "B.Cu" "B.Paste" "B.Mask") (roundrect_rratio 0.25)
      (net 141 "Net-(C45-Pad2)") (pintype "passive"))
  )

  (footprint "sdi-mipi-bridge-footprints:R_0402_1005Metric" (layer "B.Cu")
    (at 144.2825 109.525 -90)
    (descr "Resistor SMD 0402")
    (tags "resistor SMD 0402")
    (property "Author" "Antmicro")
    (property "License" "Apache-2.0")
    (property "MPN" "CR0402-FX-4701GLF")
    (property "Manufacturer" "Bourns")
    (property "Sheetfile" "sdi-mipi-bridge.kicad_sch")
    (property "Sheetname" "")
    (property "Tolerance" "1%")
    (property "Val" "4k7")
    (property "ki_description" "4k7 resistor in 0402 package with 1% tolerance")
    (attr smd)
    (fp_text reference "R35" (at -5.125 3.1825 90) (layer "B.SilkS")
        (effects (font (size 0.7 0.7) (thickness 0.15)) (justify left bottom mirror))
    )
    (fp_text value "R_4k7_0402" (at 0 -1.4 90) (layer "B.Fab") hide
        (effects (font (size 0.7 0.7) (thickness 0.15)) (justify left bottom mirror))
    )
    (fp_text user "Author: Antmicro" (at -0.95 -4.169 90) (layer "B.Fab") hide
        (effects (font (size 0.7 0.7) (thickness 0.15)) (justify left bottom mirror))
    )
    (fp_text user "License: Apache-2.0" (at -0.95 -5.169 90) (layer "B.Fab") hide
        (effects (font (size 0.7 0.7) (thickness 0.15)) (justify left bottom mirror))
    )
    (fp_text user "${REFERENCE}" (at -0.95 -3.168 90) (layer "B.Fab") hide
        (effects (font (size 0.7 0.7) (thickness 0.15)) (justify left bottom mirror))
    )
    (fp_rect (start -0.93 0.47) (end 0.93 -0.47)
      (stroke (width 0.05) (type solid)) (fill none) (layer "B.CrtYd"))
    (fp_rect (start -0.5 0.25) (end 0.5 -0.25)
      (stroke (width 0.15) (type solid)) (fill none) (layer "B.Fab"))
    (pad "1" smd roundrect (at -0.485 0 270) (size 0.59 0.64) (layers "B.Cu" "B.Paste" "B.Mask") (roundrect_rratio 0.25)
      (net 100 "/CRESET_B") (pintype "passive"))
    (pad "2" smd roundrect (at 0.485 0 270) (size 0.59 0.64) (layers "B.Cu" "B.Paste" "B.Mask") (roundrect_rratio 0.25)
      (net 79 "VCC_IO") (pintype "passive"))
  )

  (footprint "sdi-mipi-bridge-footprints:R_0402_1005Metric" (layer "B.Cu")
    (at 143.1 109.525 -90)
    (descr "Resistor SMD 0402")
    (tags "resistor SMD 0402")
    (property "Author" "Antmicro")
    (property "License" "Apache-2.0")
    (property "MPN" "CR0402-FX-4701GLF")
    (property "Manufacturer" "Bourns")
    (property "Sheetfile" "sdi-mipi-bridge.kicad_sch")
    (property "Sheetname" "")
    (property "Tolerance" "1%")
    (property "Val" "4k7")
    (property "ki_description" "4k7 resistor in 0402 package with 1% tolerance")
    (attr smd)
    (fp_text reference "R36" (at -5.124 3.0175 90) (layer "B.SilkS")
        (effects (font (size 0.7 0.7) (thickness 0.15)) (justify left bottom mirror))
    )
    (fp_text value "R_4k7_0402" (at 0 -1.4 90) (layer "B.Fab") hide
        (effects (font (size 0.7 0.7) (thickness 0.15)) (justify left bottom mirror))
    )
    (fp_text user "${REFERENCE}" (at -0.95 -3.168 90) (layer "B.Fab") hide
        (effects (font (size 0.7 0.7) (thickness 0.15)) (justify left bottom mirror))
    )
    (fp_text user "License: Apache-2.0" (at -0.95 -5.169 90) (layer "B.Fab") hide
        (effects (font (size 0.7 0.7) (thickness 0.15)) (justify left bottom mirror))
    )
    (fp_text user "Author: Antmicro" (at -0.95 -4.169 90) (layer "B.Fab") hide
        (effects (font (size 0.7 0.7) (thickness 0.15)) (justify left bottom mirror))
    )
    (fp_rect (start -0.93 0.47) (end 0.93 -0.47)
      (stroke (width 0.05) (type solid)) (fill none) (layer "B.CrtYd"))
    (fp_rect (start -0.5 0.25) (end 0.5 -0.25)
      (stroke (width 0.15) (type solid)) (fill none) (layer "B.Fab"))
    (pad "1" smd roundrect (at -0.485 0 270) (size 0.59 0.64) (layers "B.Cu" "B.Paste" "B.Mask") (roundrect_rratio 0.25)
      (net 88 "/CDONE") (pintype "passive"))
    (pad "2" smd roundrect (at 0.485 0 270) (size 0.59 0.64) (layers "B.Cu" "B.Paste" "B.Mask") (roundrect_rratio 0.25)
      (net 79 "VCC_IO") (pintype "passive"))
  )

  (footprint "sdi-mipi-bridge-footprints:TP_SMD_0.75mm" (layer "B.Cu")
    (at 130.9492 122.4 90)
    (property "Author" "Antmicro")
    (property "License" "Apache-2.0")
    (property "MPN" "")
    (property "Manufacturer" "")
    (property "Sheetfile" "sdi-mipi-bridge.kicad_sch")
    (property "Sheetname" "")
    (property "ki_description" "Test Point 0.75mm")
    (attr smd)
    (fp_text reference "TP7" (at -0.4 -0.5492 180) (layer "B.SilkS")
        (effects (font (size 0.7 0.7) (thickness 0.15)) (justify left bottom mirror))
    )
    (fp_text value "TP_0.75mm_SMD" (at 0 -1.2 90) (layer "B.Fab") hide
        (effects (font (size 0.7 0.7) (thickness 0.15)) (justify right bottom mirror))
    )
    (fp_text user "Author: Antmicro" (at -0.4 -3.901 90) (layer "B.Fab") hide
        (effects (font (size 0.7 0.7) (thickness 0.15)) (justify right bottom mirror))
    )
    (fp_text user "${REFERENCE}" (at -0.4 -2.7 90) (layer "B.Fab") hide
        (effects (font (size 0.7 0.7) (thickness 0.15)) (justify right bottom mirror))
    )
    (fp_text user "License: Apache-2.0" (at -0.4 -5.101 90) (layer "B.Fab") hide
        (effects (font (size 0.7 0.7) (thickness 0.15)) (justify right bottom mirror))
    )
    (pad "1" smd circle (at 0 0 90) (size 0.75 0.75) (layers "B.Cu" "B.Mask")
      (net 30 "/D0") (pinfunction "1") (pintype "passive"))
  )

  (footprint "sdi-mipi-bridge-footprints:TP_SMD_0.75mm" (layer "B.Cu")
    (at 130.9492 121.4 90)
    (property "Author" "Antmicro")
    (property "License" "Apache-2.0")
    (property "MPN" "")
    (property "Manufacturer" "")
    (property "Sheetfile" "sdi-mipi-bridge.kicad_sch")
    (property "Sheetname" "")
    (property "ki_description" "Test Point 0.75mm")
    (attr smd)
    (fp_text reference "TP8" (at -0.4 0.6508 180) (layer "B.SilkS")
        (effects (font (size 0.7 0.7) (thickness 0.15)) (justify right bottom mirror))
    )
    (fp_text value "TP_0.75mm_SMD" (at 0 -1.2 90) (layer "B.Fab") hide
        (effects (font (size 0.7 0.7) (thickness 0.15)) (justify right bottom mirror))
    )
    (fp_text user "License: Apache-2.0" (at -0.4 -5.101 90) (layer "B.Fab") hide
        (effects (font (size 0.7 0.7) (thickness 0.15)) (justify right bottom mirror))
    )
    (fp_text user "${REFERENCE}" (at -0.4 -2.7 90) (layer "B.Fab") hide
        (effects (font (size 0.7 0.7) (thickness 0.15)) (justify right bottom mirror))
    )
    (fp_text user "Author: Antmicro" (at -0.4 -3.901 90) (layer "B.Fab") hide
        (effects (font (size 0.7 0.7) (thickness 0.15)) (justify right bottom mirror))
    )
    (pad "1" smd circle (at 0 0 90) (size 0.75 0.75) (layers "B.Cu" "B.Mask")
      (net 31 "/D1") (pinfunction "1") (pintype "passive"))
  )

  (footprint "sdi-mipi-bridge-footprints:TP_SMD_0.75mm" (layer "B.Cu")
    (at 130.9492 120.4 90)
    (property "Author" "Antmicro")
    (property "License" "Apache-2.0")
    (property "MPN" "")
    (property "Manufacturer" "")
    (property "Sheetfile" "sdi-mipi-bridge.kicad_sch")
    (property "Sheetname" "")
    (property "ki_description" "Test Point 0.75mm")
    (attr smd)
    (fp_text reference "TP9" (at -0.4 0.6508 180) (layer "B.SilkS")
        (effects (font (size 0.7 0.7) (thickness 0.15)) (justify right bottom mirror))
    )
    (fp_text value "TP_0.75mm_SMD" (at 0 -1.2 90) (layer "B.Fab") hide
        (effects (font (size 0.7 0.7) (thickness 0.15)) (justify right bottom mirror))
    )
    (fp_text user "${REFERENCE}" (at -0.4 -2.7 90) (layer "B.Fab") hide
        (effects (font (size 0.7 0.7) (thickness 0.15)) (justify right bottom mirror))
    )
    (fp_text user "Author: Antmicro" (at -0.4 -3.901 90) (layer "B.Fab") hide
        (effects (font (size 0.7 0.7) (thickness 0.15)) (justify right bottom mirror))
    )
    (fp_text user "License: Apache-2.0" (at -0.4 -5.101 90) (layer "B.Fab") hide
        (effects (font (size 0.7 0.7) (thickness 0.15)) (justify right bottom mirror))
    )
    (pad "1" smd circle (at 0 0 90) (size 0.75 0.75) (layers "B.Cu" "B.Mask")
      (net 32 "/D2") (pinfunction "1") (pintype "passive"))
  )

  (footprint "sdi-mipi-bridge-footprints:TP_SMD_0.75mm" (layer "B.Cu")
    (at 130.9492 119.4 90)
    (property "Author" "Antmicro")
    (property "License" "Apache-2.0")
    (property "MPN" "")
    (property "Manufacturer" "")
    (property "Sheetfile" "sdi-mipi-bridge.kicad_sch")
    (property "Sheetname" "")
    (property "ki_description" "Test Point 0.75mm")
    (attr smd)
    (fp_text reference "TP10" (at -0.4 0.6508 180) (layer "B.SilkS")
        (effects (font (size 0.7 0.7) (thickness 0.15)) (justify right bottom mirror))
    )
    (fp_text value "TP_0.75mm_SMD" (at 0 -1.2 90) (layer "B.Fab") hide
        (effects (font (size 0.7 0.7) (thickness 0.15)) (justify right bottom mirror))
    )
    (fp_text user "${REFERENCE}" (at -0.4 -2.7 90) (layer "B.Fab") hide
        (effects (font (size 0.7 0.7) (thickness 0.15)) (justify right bottom mirror))
    )
    (fp_text user "Author: Antmicro" (at -0.4 -3.901 90) (layer "B.Fab") hide
        (effects (font (size 0.7 0.7) (thickness 0.15)) (justify right bottom mirror))
    )
    (fp_text user "License: Apache-2.0" (at -0.4 -5.101 90) (layer "B.Fab") hide
        (effects (font (size 0.7 0.7) (thickness 0.15)) (justify right bottom mirror))
    )
    (pad "1" smd circle (at 0 0 90) (size 0.75 0.75) (layers "B.Cu" "B.Mask")
      (net 33 "/D3") (pinfunction "1") (pintype "passive"))
  )

  (footprint "sdi-mipi-bridge-footprints:TP_SMD_0.75mm" (layer "B.Cu")
    (at 130.9492 118.4 90)
    (property "Author" "Antmicro")
    (property "License" "Apache-2.0")
    (property "MPN" "")
    (property "Manufacturer" "")
    (property "Sheetfile" "sdi-mipi-bridge.kicad_sch")
    (property "Sheetname" "")
    (property "ki_description" "Test Point 0.75mm")
    (attr smd)
    (fp_text reference "TP11" (at -0.4 0.6508 180) (layer "B.SilkS")
        (effects (font (size 0.7 0.7) (thickness 0.15)) (justify right bottom mirror))
    )
    (fp_text value "TP_0.75mm_SMD" (at 0 -1.2 90) (layer "B.Fab") hide
        (effects (font (size 0.7 0.7) (thickness 0.15)) (justify right bottom mirror))
    )
    (fp_text user "${REFERENCE}" (at -0.4 -2.7 90) (layer "B.Fab") hide
        (effects (font (size 0.7 0.7) (thickness 0.15)) (justify right bottom mirror))
    )
    (fp_text user "Author: Antmicro" (at -0.4 -3.901 90) (layer "B.Fab") hide
        (effects (font (size 0.7 0.7) (thickness 0.15)) (justify right bottom mirror))
    )
    (fp_text user "License: Apache-2.0" (at -0.4 -5.101 90) (layer "B.Fab") hide
        (effects (font (size 0.7 0.7) (thickness 0.15)) (justify right bottom mirror))
    )
    (pad "1" smd circle (at 0 0 90) (size 0.75 0.75) (layers "B.Cu" "B.Mask")
      (net 34 "/D4") (pinfunction "1") (pintype "passive"))
  )

  (footprint "sdi-mipi-bridge-footprints:TP_SMD_0.75mm" (layer "B.Cu")
    (at 130.9492 117.4 90)
    (property "Author" "Antmicro")
    (property "License" "Apache-2.0")
    (property "MPN" "")
    (property "Manufacturer" "")
    (property "Sheetfile" "sdi-mipi-bridge.kicad_sch")
    (property "Sheetname" "")
    (property "ki_description" "Test Point 0.75mm")
    (attr smd)
    (fp_text reference "TP12" (at -0.4 0.6508 180) (layer "B.SilkS")
        (effects (font (size 0.7 0.7) (thickness 0.15)) (justify right bottom mirror))
    )
    (fp_text value "TP_0.75mm_SMD" (at 0 -1.2 90) (layer "B.Fab") hide
        (effects (font (size 0.7 0.7) (thickness 0.15)) (justify right bottom mirror))
    )
    (fp_text user "${REFERENCE}" (at -0.4 -2.7 90) (layer "B.Fab") hide
        (effects (font (size 0.7 0.7) (thickness 0.15)) (justify right bottom mirror))
    )
    (fp_text user "License: Apache-2.0" (at -0.4 -5.101 90) (layer "B.Fab") hide
        (effects (font (size 0.7 0.7) (thickness 0.15)) (justify right bottom mirror))
    )
    (fp_text user "Author: Antmicro" (at -0.4 -3.901 90) (layer "B.Fab") hide
        (effects (font (size 0.7 0.7) (thickness 0.15)) (justify right bottom mirror))
    )
    (pad "1" smd circle (at 0 0 90) (size 0.75 0.75) (layers "B.Cu" "B.Mask")
      (net 35 "/D5") (pinfunction "1") (pintype "passive"))
  )

  (footprint "sdi-mipi-bridge-footprints:TP_SMD_0.75mm" (layer "B.Cu")
    (at 130.9492 116.4 90)
    (property "Author" "Antmicro")
    (property "License" "Apache-2.0")
    (property "MPN" "")
    (property "Manufacturer" "")
    (property "Sheetfile" "sdi-mipi-bridge.kicad_sch")
    (property "Sheetname" "")
    (property "ki_description" "Test Point 0.75mm")
    (attr smd)
    (fp_text reference "TP13" (at -0.4 0.6508 180) (layer "B.SilkS")
        (effects (font (size 0.7 0.7) (thickness 0.15)) (justify right bottom mirror))
    )
    (fp_text value "TP_0.75mm_SMD" (at 0 -1.2 90) (layer "B.Fab") hide
        (effects (font (size 0.7 0.7) (thickness 0.15)) (justify right bottom mirror))
    )
    (fp_text user "${REFERENCE}" (at -0.4 -2.7 90) (layer "B.Fab") hide
        (effects (font (size 0.7 0.7) (thickness 0.15)) (justify right bottom mirror))
    )
    (fp_text user "Author: Antmicro" (at -0.4 -3.901 90) (layer "B.Fab") hide
        (effects (font (size 0.7 0.7) (thickness 0.15)) (justify right bottom mirror))
    )
    (fp_text user "License: Apache-2.0" (at -0.4 -5.101 90) (layer "B.Fab") hide
        (effects (font (size 0.7 0.7) (thickness 0.15)) (justify right bottom mirror))
    )
    (pad "1" smd circle (at 0 0 90) (size 0.75 0.75) (layers "B.Cu" "B.Mask")
      (net 36 "/D6") (pinfunction "1") (pintype "passive"))
  )

  (footprint "sdi-mipi-bridge-footprints:TP_SMD_0.75mm" (layer "B.Cu")
    (at 130.9492 115.4 90)
    (property "Author" "Antmicro")
    (property "License" "Apache-2.0")
    (property "MPN" "")
    (property "Manufacturer" "")
    (property "Sheetfile" "sdi-mipi-bridge.kicad_sch")
    (property "Sheetname" "")
    (property "ki_description" "Test Point 0.75mm")
    (attr smd)
    (fp_text reference "TP14" (at -0.4 0.6508 180) (layer "B.SilkS")
        (effects (font (size 0.7 0.7) (thickness 0.15)) (justify right bottom mirror))
    )
    (fp_text value "TP_0.75mm_SMD" (at 0 -1.2 90) (layer "B.Fab") hide
        (effects (font (size 0.7 0.7) (thickness 0.15)) (justify right bottom mirror))
    )
    (fp_text user "License: Apache-2.0" (at -0.4 -5.101 90) (layer "B.Fab") hide
        (effects (font (size 0.7 0.7) (thickness 0.15)) (justify right bottom mirror))
    )
    (fp_text user "${REFERENCE}" (at -0.4 -2.7 90) (layer "B.Fab") hide
        (effects (font (size 0.7 0.7) (thickness 0.15)) (justify right bottom mirror))
    )
    (fp_text user "Author: Antmicro" (at -0.4 -3.901 90) (layer "B.Fab") hide
        (effects (font (size 0.7 0.7) (thickness 0.15)) (justify right bottom mirror))
    )
    (pad "1" smd circle (at 0 0 90) (size 0.75 0.75) (layers "B.Cu" "B.Mask")
      (net 37 "/D7") (pinfunction "1") (pintype "passive"))
  )

  (footprint "sdi-mipi-bridge-footprints:TP_SMD_0.75mm" (layer "B.Cu")
    (at 130.9492 114.4 90)
    (property "Author" "Antmicro")
    (property "License" "Apache-2.0")
    (property "MPN" "")
    (property "Manufacturer" "")
    (property "Sheetfile" "sdi-mipi-bridge.kicad_sch")
    (property "Sheetname" "")
    (property "ki_description" "Test Point 0.75mm")
    (attr smd)
    (fp_text reference "TP15" (at -0.4 0.6508 180) (layer "B.SilkS")
        (effects (font (size 0.7 0.7) (thickness 0.15)) (justify right bottom mirror))
    )
    (fp_text value "TP_0.75mm_SMD" (at 0 -1.2 90) (layer "B.Fab") hide
        (effects (font (size 0.7 0.7) (thickness 0.15)) (justify right bottom mirror))
    )
    (fp_text user "Author: Antmicro" (at -0.4 -3.901 90) (layer "B.Fab") hide
        (effects (font (size 0.7 0.7) (thickness 0.15)) (justify right bottom mirror))
    )
    (fp_text user "${REFERENCE}" (at -0.4 -2.7 90) (layer "B.Fab") hide
        (effects (font (size 0.7 0.7) (thickness 0.15)) (justify right bottom mirror))
    )
    (fp_text user "License: Apache-2.0" (at -0.4 -5.101 90) (layer "B.Fab") hide
        (effects (font (size 0.7 0.7) (thickness 0.15)) (justify right bottom mirror))
    )
    (pad "1" smd circle (at 0 0 90) (size 0.75 0.75) (layers "B.Cu" "B.Mask")
      (net 38 "/D8") (pinfunction "1") (pintype "passive"))
  )

  (footprint "sdi-mipi-bridge-footprints:TP_SMD_0.75mm" (layer "B.Cu")
    (at 130.9492 113.4 90)
    (property "Author" "Antmicro")
    (property "License" "Apache-2.0")
    (property "MPN" "")
    (property "Manufacturer" "")
    (property "Sheetfile" "sdi-mipi-bridge.kicad_sch")
    (property "Sheetname" "")
    (property "ki_description" "Test Point 0.75mm")
    (attr smd)
    (fp_text reference "TP16" (at -0.4 0.6508 180) (layer "B.SilkS")
        (effects (font (size 0.7 0.7) (thickness 0.15)) (justify right bottom mirror))
    )
    (fp_text value "TP_0.75mm_SMD" (at 0 -1.2 90) (layer "B.Fab") hide
        (effects (font (size 0.7 0.7) (thickness 0.15)) (justify right bottom mirror))
    )
    (fp_text user "Author: Antmicro" (at -0.4 -3.901 90) (layer "B.Fab") hide
        (effects (font (size 0.7 0.7) (thickness 0.15)) (justify right bottom mirror))
    )
    (fp_text user "${REFERENCE}" (at -0.4 -2.7 90) (layer "B.Fab") hide
        (effects (font (size 0.7 0.7) (thickness 0.15)) (justify right bottom mirror))
    )
    (fp_text user "License: Apache-2.0" (at -0.4 -5.101 90) (layer "B.Fab") hide
        (effects (font (size 0.7 0.7) (thickness 0.15)) (justify right bottom mirror))
    )
    (pad "1" smd circle (at 0 0 90) (size 0.75 0.75) (layers "B.Cu" "B.Mask")
      (net 39 "/D9") (pinfunction "1") (pintype "passive"))
  )

  (footprint "sdi-mipi-bridge-footprints:C_0603_1608Metric" (layer "B.Cu")
    (at 130.5 133.253 90)
    (descr "Capacitor SMD 0603")
    (tags "capacitor 0603")
    (property "Author" "Antmicro")
    (property "License" "Apache-2.0")
    (property "MPN" "GRM188R61A106KE69D")
    (property "Manufacturer" "Murata")
    (property "Sheetfile" "sdi-mipi-bridge.kicad_sch")
    (property "Sheetname" "")
    (property "Val" "10u")
    (property "Voltage" "")
    (property "ki_description" " ")
    (attr smd)
    (fp_text reference "C15" (at 1.253 0.3 90) (layer "B.SilkS")
        (effects (font (size 0.7 0.7) (thickness 0.15)) (justify right bottom mirror))
    )
    (fp_text value "C_10u_0603" (at 0 -1.6 90) (layer "B.Fab") hide
        (effects (font (size 0.7 0.7) (thickness 0.15)) (justify right bottom mirror))
    )
    (fp_text user "${REFERENCE}" (at -1.682 -3.895 90) (layer "B.Fab") hide
        (effects (font (size 0.7 0.7) (thickness 0.15)) (justify right bottom mirror))
    )
    (fp_text user "License: Apache-2.0" (at -1.682 -5.895 90) (layer "B.Fab") hide
        (effects (font (size 0.7 0.7) (thickness 0.15)) (justify right bottom mirror))
    )
    (fp_text user "Author: Antmicro" (at -1.682 -4.894 90) (layer "B.Fab") hide
        (effects (font (size 0.7 0.7) (thickness 0.15)) (justify right bottom mirror))
    )
    (fp_line (start -0.3 -0.3) (end 0.3 -0.3)
      (stroke (width 0.15) (type solid)) (layer "B.SilkS"))
    (fp_line (start -0.3 0.3) (end 0.3 0.3)
      (stroke (width 0.15) (type solid)) (layer "B.SilkS"))
    (fp_rect (start -1.24 0.7) (end 1.24 -0.7)
      (stroke (width 0.05) (type solid)) (fill none) (layer "B.CrtYd"))
    (fp_rect (start -0.8 0.4) (end 0.8 -0.4)
      (stroke (width 0.15) (type solid)) (fill none) (layer "B.Fab"))
    (pad "1" smd roundrect (at -0.7 0 90) (size 0.6 0.8) (layers "B.Cu" "B.Paste" "B.Mask") (roundrect_rratio 0.2)
      (net 1 "GNDREF") (pintype "passive"))
    (pad "2" smd roundrect (at 0.7 0 90) (size 0.6 0.8) (layers "B.Cu" "B.Paste" "B.Mask") (roundrect_rratio 0.2)
      (net 2 "+1V2") (pintype "passive"))
  )

  (footprint "sdi-mipi-bridge-footprints:C_0402_1005Metric" (layer "B.Cu")
    (at 126.1 132.53 180)
    (descr "Capacitor SMD 0402")
    (tags "capacitor SMD 0402")
    (property "Author" "Antmicro")
    (property "Dielectric" "")
    (property "License" "Apache-2.0")
    (property "MPN" "C1005X6S1A105K050BC")
    (property "Manufacturer" "TDK")
    (property "Sheetfile" "sdi-mipi-bridge.kicad_sch")
    (property "Sheetname" "")
    (property "Val" "1u")
    (property "Voltage" "")
    (property "ki_description" " ")
    (attr smd)
    (fp_text reference "C28" (at 1.301 -0.35) (layer "B.SilkS")
        (effects (font (size 0.7 0.7) (thickness 0.15)) (justify left bottom mirror))
    )
    (fp_text value "C_1u_0402" (at -100.01 -1.42) (layer "B.Fab") hide
        (effects (font (size 0.7 0.7) (thickness 0.15)) (justify left bottom mirror))
    )
    (fp_text user "License: Apache-2.0" (at -0.932 -5.17) (layer "B.Fab") hide
        (effects (font (size 0.7 0.7) (thickness 0.15)) (justify left bottom mirror))
    )
    (fp_text user "Author: Antmicro" (at -0.932 -4.17) (layer "B.Fab") hide
        (effects (font (size 0.7 0.7) (thickness 0.15)) (justify left bottom mirror))
    )
    (fp_text user "${REFERENCE}" (at -0.932 -3.168) (layer "B.Fab") hide
        (effects (font (size 0.7 0.7) (thickness 0.15)) (justify left bottom mirror))
    )
    (fp_rect (start -0.94 0.47) (end 0.94 -0.47)
      (stroke (width 0.05) (type solid)) (fill none) (layer "B.CrtYd"))
    (fp_rect (start -0.499 0.249) (end 0.499 -0.249)
      (stroke (width 0.15) (type solid)) (fill none) (layer "B.Fab"))
    (pad "1" smd roundrect (at -0.484 0 180) (size 0.59 0.64) (layers "B.Cu" "B.Paste" "B.Mask") (roundrect_rratio 0.25)
      (net 3 "GNDA") (pintype "passive"))
    (pad "2" smd roundrect (at 0.484 0 180) (size 0.59 0.64) (layers "B.Cu" "B.Paste" "B.Mask") (roundrect_rratio 0.25)
      (net 5 "+3.3VA") (pintype "passive"))
  )

  (footprint "sdi-mipi-bridge-footprints:C_0402_1005Metric" (layer "B.Cu")
    (at 126.1 133.53 180)
    (descr "Capacitor SMD 0402")
    (tags "capacitor SMD 0402")
    (property "Author" "Antmicro")
    (property "Dielectric" "")
    (property "License" "Apache-2.0")
    (property "MPN" "C1005X6S1A105K050BC")
    (property "Manufacturer" "TDK")
    (property "Sheetfile" "sdi-mipi-bridge.kicad_sch")
    (property "Sheetname" "")
    (property "Val" "1u")
    (property "Voltage" "")
    (property "ki_description" " ")
    (attr smd)
    (fp_text reference "C24" (at 1.301 -0.35) (layer "B.SilkS")
        (effects (font (size 0.7 0.7) (thickness 0.15)) (justify left bottom mirror))
    )
    (fp_text value "C_1u_0402" (at 0 -1.4) (layer "B.Fab") hide
        (effects (font (size 0.7 0.7) (thickness 0.15)) (justify left bottom mirror))
    )
    (fp_text user "License: Apache-2.0" (at -0.932 -5.17) (layer "B.Fab") hide
        (effects (font (size 0.7 0.7) (thickness 0.15)) (justify left bottom mirror))
    )
    (fp_text user "${REFERENCE}" (at -0.932 -3.168) (layer "B.Fab") hide
        (effects (font (size 0.7 0.7) (thickness 0.15)) (justify left bottom mirror))
    )
    (fp_text user "Author: Antmicro" (at -0.932 -4.17) (layer "B.Fab") hide
        (effects (font (size 0.7 0.7) (thickness 0.15)) (justify left bottom mirror))
    )
    (fp_rect (start -0.94 0.47) (end 0.94 -0.47)
      (stroke (width 0.05) (type solid)) (fill none) (layer "B.CrtYd"))
    (fp_rect (start -0.499 0.249) (end 0.499 -0.249)
      (stroke (width 0.15) (type solid)) (fill none) (layer "B.Fab"))
    (pad "1" smd roundrect (at -0.484 0 180) (size 0.59 0.64) (layers "B.Cu" "B.Paste" "B.Mask") (roundrect_rratio 0.25)
      (net 1 "GNDREF") (pintype "passive"))
    (pad "2" smd roundrect (at 0.484 0 180) (size 0.59 0.64) (layers "B.Cu" "B.Paste" "B.Mask") (roundrect_rratio 0.25)
      (net 6 "+3V3") (pintype "passive"))
  )

  (footprint "sdi-mipi-bridge-footprints:C_0402_1005Metric" (layer "B.Cu")
    (at 146.93 118.86 90)
    (descr "Capacitor SMD 0402")
    (tags "capacitor SMD 0402")
    (property "Author" "Antmicro")
    (property "Dielectric" "")
    (property "License" "Apache-2.0")
    (property "MPN" "0402X104K6R3CT")
    (property "Manufacturer" "Walsin")
    (property "Sheetfile" "sdi-mipi-bridge.kicad_sch")
    (property "Sheetname" "")
    (property "Val" "100n")
    (property "Voltage" "")
    (property "ki_description" " ")
    (attr smd)
    (fp_text reference "C39" (at -8.94 9.07 90) (layer "B.SilkS")
        (effects (font (size 0.7 0.7) (thickness 0.15)) (justify right bottom mirror))
    )
    (fp_text value "C_100n_6V3_0402" (at 0 -1.4 90) (layer "B.Fab") hide
        (effects (font (size 0.7 0.7) (thickness 0.15)) (justify right bottom mirror))
    )
    (fp_text user "${REFERENCE}" (at -0.932 -3.168 90) (layer "B.Fab") hide
        (effects (font (size 0.7 0.7) (thickness 0.15)) (justify right bottom mirror))
    )
    (fp_text user "Author: Antmicro" (at -0.932 -4.17 90) (layer "B.Fab") hide
        (effects (font (size 0.7 0.7) (thickness 0.15)) (justify right bottom mirror))
    )
    (fp_text user "License: Apache-2.0" (at -0.932 -5.17 90) (layer "B.Fab") hide
        (effects (font (size 0.7 0.7) (thickness 0.15)) (justify right bottom mirror))
    )
    (fp_rect (start -0.94 0.47) (end 0.94 -0.47)
      (stroke (width 0.05) (type solid)) (fill none) (layer "B.CrtYd"))
    (fp_rect (start -0.499 0.249) (end 0.499 -0.249)
      (stroke (width 0.15) (type solid)) (fill none) (layer "B.Fab"))
    (pad "1" smd roundrect (at -0.484 0 90) (size 0.59 0.64) (layers "B.Cu" "B.Paste" "B.Mask") (roundrect_rratio 0.25)
      (net 1 "GNDREF") (pintype "passive"))
    (pad "2" smd roundrect (at 0.484 0 90) (size 0.59 0.64) (layers "B.Cu" "B.Paste" "B.Mask") (roundrect_rratio 0.25)
      (net 2 "+1V2") (pintype "passive"))
  )

  (footprint "sdi-mipi-bridge-footprints:C_0402_1005Metric" (layer "B.Cu")
    (at 145.255 114.96 180)
    (descr "Capacitor SMD 0402")
    (tags "capacitor SMD 0402")
    (property "Author" "Antmicro")
    (property "Dielectric" "")
    (property "License" "Apache-2.0")
    (property "MPN" "0402X104K6R3CT")
    (property "Manufacturer" "Walsin")
    (property "Sheetfile" "sdi-mipi-bridge.kicad_sch")
    (property "Sheetname" "")
    (property "Val" "100n")
    (property "Voltage" "")
    (property "ki_description" " ")
    (attr smd)
    (fp_text reference "C50" (at -9.745 -8.24) (layer "B.SilkS")
        (effects (font (size 0.7 0.7) (thickness 0.15)) (justify left bottom mirror))
    )
    (fp_text value "C_100n_6V3_0402" (at 0 -1.4) (layer "B.Fab") hide
        (effects (font (size 0.7 0.7) (thickness 0.15)) (justify left bottom mirror))
    )
    (fp_text user "License: Apache-2.0" (at -0.932 -5.17) (layer "B.Fab") hide
        (effects (font (size 0.7 0.7) (thickness 0.15)) (justify left bottom mirror))
    )
    (fp_text user "${REFERENCE}" (at -0.932 -3.168) (layer "B.Fab") hide
        (effects (font (size 0.7 0.7) (thickness 0.15)) (justify left bottom mirror))
    )
    (fp_text user "Author: Antmicro" (at -0.932 -4.17) (layer "B.Fab") hide
        (effects (font (size 0.7 0.7) (thickness 0.15)) (justify left bottom mirror))
    )
    (fp_rect (start -0.94 0.47) (end 0.94 -0.47)
      (stroke (width 0.05) (type solid)) (fill none) (layer "B.CrtYd"))
    (fp_rect (start -0.499 0.249) (end 0.499 -0.249)
      (stroke (width 0.15) (type solid)) (fill none) (layer "B.Fab"))
    (pad "1" smd roundrect (at -0.484 0 180) (size 0.59 0.64) (layers "B.Cu" "B.Paste" "B.Mask") (roundrect_rratio 0.25)
      (net 1 "GNDREF") (pintype "passive"))
    (pad "2" smd roundrect (at 0.484 0 180) (size 0.59 0.64) (layers "B.Cu" "B.Paste" "B.Mask") (roundrect_rratio 0.25)
      (net 79 "VCC_IO") (pintype "passive"))
  )

  (footprint "sdi-mipi-bridge-footprints:C_0402_1005Metric" (layer "B.Cu")
    (at 143.25 117.19 90)
    (descr "Capacitor SMD 0402")
    (tags "capacitor SMD 0402")
    (property "Author" "Antmicro")
    (property "Dielectric" "")
    (property "License" "Apache-2.0")
    (property "MPN" "0402X104K6R3CT")
    (property "Manufacturer" "Walsin")
    (property "Sheetfile" "sdi-mipi-bridge.kicad_sch")
    (property "Sheetname" "")
    (property "Val" "100n")
    (property "Voltage" "")
    (property "ki_description" " ")
    (attr smd)
    (fp_text reference "C41" (at -8.81 9.15 90) (layer "B.SilkS")
        (effects (font (size 0.7 0.7) (thickness 0.15)) (justify right bottom mirror))
    )
    (fp_text value "C_100n_6V3_0402" (at 0 -1.4 90) (layer "B.Fab") hide
        (effects (font (size 0.7 0.7) (thickness 0.15)) (justify right bottom mirror))
    )
    (fp_text user "Author: Antmicro" (at -0.932 -4.17 90) (layer "B.Fab") hide
        (effects (font (size 0.7 0.7) (thickness 0.15)) (justify right bottom mirror))
    )
    (fp_text user "License: Apache-2.0" (at -0.932 -5.17 90) (layer "B.Fab") hide
        (effects (font (size 0.7 0.7) (thickness 0.15)) (justify right bottom mirror))
    )
    (fp_text user "${REFERENCE}" (at -0.932 -3.168 90) (layer "B.Fab") hide
        (effects (font (size 0.7 0.7) (thickness 0.15)) (justify right bottom mirror))
    )
    (fp_rect (start -0.94 0.47) (end 0.94 -0.47)
      (stroke (width 0.05) (type solid)) (fill none) (layer "B.CrtYd"))
    (fp_rect (start -0.499 0.249) (end 0.499 -0.249)
      (stroke (width 0.15) (type solid)) (fill none) (layer "B.Fab"))
    (pad "1" smd roundrect (at -0.484 0 90) (size 0.59 0.64) (layers "B.Cu" "B.Paste" "B.Mask") (roundrect_rratio 0.25)
      (net 1 "GNDREF") (pintype "passive"))
    (pad "2" smd roundrect (at 0.484 0 90) (size 0.59 0.64) (layers "B.Cu" "B.Paste" "B.Mask") (roundrect_rratio 0.25)
      (net 79 "VCC_IO") (pintype "passive"))
  )

  (footprint "sdi-mipi-bridge-footprints:C_0402_1005Metric" (layer "B.Cu")
    (at 143.25 114.75 90)
    (descr "Capacitor SMD 0402")
    (tags "capacitor SMD 0402")
    (property "Author" "Antmicro")
    (property "Dielectric" "")
    (property "License" "Apache-2.0")
    (property "MPN" "0402X104K6R3CT")
    (property "Manufacturer" "Walsin")
    (property "Sheetfile" "sdi-mipi-bridge.kicad_sch")
    (property "Sheetname" "")
    (property "Val" "100n")
    (property "Voltage" "")
    (property "ki_description" " ")
    (attr smd)
    (fp_text reference "C46" (at -9.05 9.15 90) (layer "B.SilkS")
        (effects (font (size 0.7 0.7) (thickness 0.15)) (justify right bottom mirror))
    )
    (fp_text value "C_100n_6V3_0402" (at 0 -1.4 90) (layer "B.Fab") hide
        (effects (font (size 0.7 0.7) (thickness 0.15)) (justify right bottom mirror))
    )
    (fp_text user "${REFERENCE}" (at -0.932 -3.168 90) (layer "B.Fab") hide
        (effects (font (size 0.7 0.7) (thickness 0.15)) (justify right bottom mirror))
    )
    (fp_text user "Author: Antmicro" (at -0.932 -4.17 90) (layer "B.Fab") hide
        (effects (font (size 0.7 0.7) (thickness 0.15)) (justify right bottom mirror))
    )
    (fp_text user "License: Apache-2.0" (at -0.932 -5.17 90) (layer "B.Fab") hide
        (effects (font (size 0.7 0.7) (thickness 0.15)) (justify right bottom mirror))
    )
    (fp_rect (start -0.94 0.47) (end 0.94 -0.47)
      (stroke (width 0.05) (type solid)) (fill none) (layer "B.CrtYd"))
    (fp_rect (start -0.499 0.249) (end 0.499 -0.249)
      (stroke (width 0.15) (type solid)) (fill none) (layer "B.Fab"))
    (pad "1" smd roundrect (at -0.484 0 90) (size 0.59 0.64) (layers "B.Cu" "B.Paste" "B.Mask") (roundrect_rratio 0.25)
      (net 1 "GNDREF") (pintype "passive"))
    (pad "2" smd roundrect (at 0.484 0 90) (size 0.59 0.64) (layers "B.Cu" "B.Paste" "B.Mask") (roundrect_rratio 0.25)
      (net 79 "VCC_IO") (pintype "passive"))
  )

  (footprint "sdi-mipi-bridge-footprints:C_0402_1005Metric" (layer "B.Cu")
    (at 146.41 113.49 180)
    (descr "Capacitor SMD 0402")
    (tags "capacitor SMD 0402")
    (property "Author" "Antmicro")
    (property "Dielectric" "")
    (property "License" "Apache-2.0")
    (property "MPN" "0402X104K6R3CT")
    (property "Manufacturer" "Walsin")
    (property "Sheetfile" "sdi-mipi-bridge.kicad_sch")
    (property "Sheetname" "")
    (property "Val" "100n")
    (property "Voltage" "")
    (property "ki_description" " ")
    (attr smd)
    (fp_text reference "C57" (at -9.99 -8.11) (layer "B.SilkS")
        (effects (font (size 0.7 0.7) (thickness 0.15)) (justify left bottom mirror))
    )
    (fp_text value "C_100n_6V3_0402" (at 0 -1.4) (layer "B.Fab") hide
        (effects (font (size 0.7 0.7) (thickness 0.15)) (justify left bottom mirror))
    )
    (fp_text user "${REFERENCE}" (at -0.932 -3.168) (layer "B.Fab") hide
        (effects (font (size 0.7 0.7) (thickness 0.15)) (justify left bottom mirror))
    )
    (fp_text user "License: Apache-2.0" (at -0.932 -5.17) (layer "B.Fab") hide
        (effects (font (size 0.7 0.7) (thickness 0.15)) (justify left bottom mirror))
    )
    (fp_text user "Author: Antmicro" (at -0.932 -4.17) (layer "B.Fab") hide
        (effects (font (size 0.7 0.7) (thickness 0.15)) (justify left bottom mirror))
    )
    (fp_rect (start -0.94 0.47) (end 0.94 -0.47)
      (stroke (width 0.05) (type solid)) (fill none) (layer "B.CrtYd"))
    (fp_rect (start -0.499 0.249) (end 0.499 -0.249)
      (stroke (width 0.15) (type solid)) (fill none) (layer "B.Fab"))
    (pad "1" smd roundrect (at -0.484 0 180) (size 0.59 0.64) (layers "B.Cu" "B.Paste" "B.Mask") (roundrect_rratio 0.25)
      (net 1 "GNDREF") (pintype "passive"))
    (pad "2" smd roundrect (at 0.484 0 180) (size 0.59 0.64) (layers "B.Cu" "B.Paste" "B.Mask") (roundrect_rratio 0.25)
      (net 79 "VCC_IO") (pintype "passive"))
  )

  (footprint "sdi-mipi-bridge-footprints:C_0402_1005Metric" (layer "B.Cu")
    (at 148.095 108 -90)
    (descr "Capacitor SMD 0402")
    (tags "capacitor SMD 0402")
    (property "Author" "Antmicro")
    (property "Dielectric" "")
    (property "License" "Apache-2.0")
    (property "MPN" "0402X104K6R3CT")
    (property "Manufacturer" "Walsin")
    (property "Sheetfile" "sdi-mipi-bridge.kicad_sch")
    (property "Sheetname" "")
    (property "Val" "100n")
    (property "Voltage" "")
    (property "ki_description" " ")
    (attr smd)
    (fp_text reference "C49" (at -3.2 -0.505 90) (layer "B.SilkS")
        (effects (font (size 0.7 0.7) (thickness 0.15)) (justify left bottom mirror))
    )
    (fp_text value "C_100n_6V3_0402" (at 0 -1.4 90) (layer "B.Fab") hide
        (effects (font (size 0.7 0.7) (thickness 0.15)) (justify left bottom mirror))
    )
    (fp_text user "License: Apache-2.0" (at -0.932 -5.17 90) (layer "B.Fab") hide
        (effects (font (size 0.7 0.7) (thickness 0.15)) (justify left bottom mirror))
    )
    (fp_text user "${REFERENCE}" (at -0.932 -3.168 90) (layer "B.Fab") hide
        (effects (font (size 0.7 0.7) (thickness 0.15)) (justify left bottom mirror))
    )
    (fp_text user "Author: Antmicro" (at -0.932 -4.17 90) (layer "B.Fab") hide
        (effects (font (size 0.7 0.7) (thickness 0.15)) (justify left bottom mirror))
    )
    (fp_rect (start -0.94 0.47) (end 0.94 -0.47)
      (stroke (width 0.05) (type solid)) (fill none) (layer "B.CrtYd"))
    (fp_rect (start -0.499 0.249) (end 0.499 -0.249)
      (stroke (width 0.15) (type solid)) (fill none) (layer "B.Fab"))
    (pad "1" smd roundrect (at -0.484 0 270) (size 0.59 0.64) (layers "B.Cu" "B.Paste" "B.Mask") (roundrect_rratio 0.25)
      (net 58 "/GNDPLL_DPHY") (pintype "passive"))
    (pad "2" smd roundrect (at 0.484 0 270) (size 0.59 0.64) (layers "B.Cu" "B.Paste" "B.Mask") (roundrect_rratio 0.25)
      (net 77 "VCCA_DPHY") (pintype "passive"))
  )

  (footprint "sdi-mipi-bridge-footprints:C_0402_1005Metric" (layer "B.Cu")
    (at 147.96 114.93 90)
    (descr "Capacitor SMD 0402")
    (tags "capacitor SMD 0402")
    (property "Author" "Antmicro")
    (property "Dielectric" "")
    (property "License" "Apache-2.0")
    (property "MPN" "0402X104K6R3CT")
    (property "Manufacturer" "Walsin")
    (property "Sheetfile" "sdi-mipi-bridge.kicad_sch")
    (property "Sheetname" "")
    (property "Val" "100n")
    (property "Voltage" "")
    (property "ki_description" " ")
    (attr smd)
    (fp_text reference "C40" (at -6.67 9.24 90) (layer "B.SilkS")
        (effects (font (size 0.7 0.7) (thickness 0.15)) (justify left bottom mirror))
    )
    (fp_text value "C_100n_6V3_0402" (at 0 -1.4 90) (layer "B.Fab") hide
        (effects (font (size 0.7 0.7) (thickness 0.15)) (justify right bottom mirror))
    )
    (fp_text user "Author: Antmicro" (at -0.932 -4.17 90) (layer "B.Fab") hide
        (effects (font (size 0.7 0.7) (thickness 0.15)) (justify right bottom mirror))
    )
    (fp_text user "License: Apache-2.0" (at -0.932 -5.17 90) (layer "B.Fab") hide
        (effects (font (size 0.7 0.7) (thickness 0.15)) (justify right bottom mirror))
    )
    (fp_text user "${REFERENCE}" (at -0.932 -3.168 90) (layer "B.Fab") hide
        (effects (font (size 0.7 0.7) (thickness 0.15)) (justify right bottom mirror))
    )
    (fp_rect (start -0.94 0.47) (end 0.94 -0.47)
      (stroke (width 0.05) (type solid)) (fill none) (layer "B.CrtYd"))
    (fp_rect (start -0.499 0.249) (end 0.499 -0.249)
      (stroke (width 0.15) (type solid)) (fill none) (layer "B.Fab"))
    (pad "1" smd roundrect (at -0.484 0 90) (size 0.59 0.64) (layers "B.Cu" "B.Paste" "B.Mask") (roundrect_rratio 0.25)
      (net 1 "GNDREF") (pintype "passive"))
    (pad "2" smd roundrect (at 0.484 0 90) (size 0.59 0.64) (layers "B.Cu" "B.Paste" "B.Mask") (roundrect_rratio 0.25)
      (net 77 "VCCA_DPHY") (pintype "passive"))
  )

  (footprint "sdi-mipi-bridge-footprints:C_0402_1005Metric" (layer "B.Cu")
    (at 147.97 116.91 -90)
    (descr "Capacitor SMD 0402")
    (tags "capacitor SMD 0402")
    (property "Author" "Antmicro")
    (property "Dielectric" "")
    (property "License" "Apache-2.0")
    (property "MPN" "0402X104K6R3CT")
    (property "Manufacturer" "Walsin")
    (property "Sheetfile" "sdi-mipi-bridge.kicad_sch")
    (property "Sheetname" "")
    (property "Val" "100n")
    (property "Voltage" "")
    (property "ki_description" " ")
    (attr smd)
    (fp_text reference "C53" (at 6.69 -9.23 90) (layer "B.SilkS")
        (effects (font (size 0.7 0.7) (thickness 0.15)) (justify left bottom mirror))
    )
    (fp_text value "C_100n_6V3_0402" (at 0 -1.4 90) (layer "B.Fab") hide
        (effects (font (size 0.7 0.7) (thickness 0.15)) (justify left bottom mirror))
    )
    (fp_text user "${REFERENCE}" (at -0.932 -3.168 90) (layer "B.Fab") hide
        (effects (font (size 0.7 0.7) (thickness 0.15)) (justify left bottom mirror))
    )
    (fp_text user "License: Apache-2.0" (at -0.932 -5.17 90) (layer "B.Fab") hide
        (effects (font (size 0.7 0.7) (thickness 0.15)) (justify left bottom mirror))
    )
    (fp_text user "Author: Antmicro" (at -0.932 -4.17 90) (layer "B.Fab") hide
        (effects (font (size 0.7 0.7) (thickness 0.15)) (justify left bottom mirror))
    )
    (fp_rect (start -0.94 0.47) (end 0.94 -0.47)
      (stroke (width 0.05) (type solid)) (fill none) (layer "B.CrtYd"))
    (fp_rect (start -0.499 0.249) (end 0.499 -0.249)
      (stroke (width 0.15) (type solid)) (fill none) (layer "B.Fab"))
    (pad "1" smd roundrect (at -0.484 0 270) (size 0.59 0.64) (layers "B.Cu" "B.Paste" "B.Mask") (roundrect_rratio 0.25)
      (net 58 "/GNDPLL_DPHY") (pintype "passive"))
    (pad "2" smd roundrect (at 0.484 0 270) (size 0.59 0.64) (layers "B.Cu" "B.Paste" "B.Mask") (roundrect_rratio 0.25)
      (net 77 "VCCA_DPHY") (pintype "passive"))
  )

  (footprint "sdi-mipi-bridge-footprints:C_0402_1005Metric" (layer "B.Cu")
    (at 146.4 112.46)
    (descr "Capacitor SMD 0402")
    (tags "capacitor SMD 0402")
    (property "Author" "Antmicro")
    (property "Dielectric" "")
    (property "License" "Apache-2.0")
    (property "MPN" "0402X104K6R3CT")
    (property "Manufacturer" "Walsin")
    (property "Sheetfile" "sdi-mipi-bridge.kicad_sch")
    (property "Sheetname" "")
    (property "Val" "100n")
    (property "Voltage" "")
    (property "ki_description" " ")
    (attr smd)
    (fp_text reference "C44" (at 10 8.14) (layer "B.SilkS")
        (effects (font (size 0.7 0.7) (thickness 0.15)) (justify left bottom mirror))
    )
    (fp_text value "C_100n_6V3_0402" (at 0 -1.4) (layer "B.Fab") hide
        (effects (font (size 0.7 0.7) (thickness 0.15)) (justify right bottom mirror))
    )
    (fp_text user "Author: Antmicro" (at -0.932 -4.17) (layer "B.Fab") hide
        (effects (font (size 0.7 0.7) (thickness 0.15)) (justify right bottom mirror))
    )
    (fp_text user "License: Apache-2.0" (at -0.932 -5.17) (layer "B.Fab") hide
        (effects (font (size 0.7 0.7) (thickness 0.15)) (justify right bottom mirror))
    )
    (fp_text user "${REFERENCE}" (at -0.932 -3.168) (layer "B.Fab") hide
        (effects (font (size 0.7 0.7) (thickness 0.15)) (justify right bottom mirror))
    )
    (fp_rect (start -0.94 0.47) (end 0.94 -0.47)
      (stroke (width 0.05) (type solid)) (fill none) (layer "B.CrtYd"))
    (fp_rect (start -0.499 0.249) (end 0.499 -0.249)
      (stroke (width 0.15) (type solid)) (fill none) (layer "B.Fab"))
    (pad "1" smd roundrect (at -0.484 0) (size 0.59 0.64) (layers "B.Cu" "B.Paste" "B.Mask") (roundrect_rratio 0.25)
      (net 1 "GNDREF") (pintype "passive"))
    (pad "2" smd roundrect (at 0.484 0) (size 0.59 0.64) (layers "B.Cu" "B.Paste" "B.Mask") (roundrect_rratio 0.25)
      (net 77 "VCCA_DPHY") (pintype "passive"))
  )

  (footprint "sdi-mipi-bridge-footprints:R_0402_1005Metric" (layer "B.Cu")
    (at 150.205 110)
    (descr "Resistor SMD 0402")
    (tags "resistor SMD 0402")
    (property "Author" "Antmicro")
    (property "Current" "1A")
    (property "License" "Apache-2.0")
    (property "MPN" "ERJ2GE0R00X")
    (property "Manufacturer" "Panasonic")
    (property "Sheetfile" "sdi-mipi-bridge.kicad_sch")
    (property "Sheetname" "")
    (property "Tolerance" "")
    (property "Val" "0R")
    (property "ki_description" "0R resistor in 0402 package with unspecified tolerance")
    (attr smd)
    (fp_text reference "R67" (at 0.995 -0.6 180) (layer "B.SilkS")
        (effects (font (size 0.7 0.7) (thickness 0.15)) (justify left bottom mirror))
    )
    (fp_text value "R_0R_0402" (at 0 -1.4 180) (layer "B.Fab") hide
        (effects (font (size 0.7 0.7) (thickness 0.15)) (justify left bottom mirror))
    )
    (fp_text user "${REFERENCE}" (at -0.95 -3.168 180) (layer "B.Fab") hide
        (effects (font (size 0.7 0.7) (thickness 0.15)) (justify left bottom mirror))
    )
    (fp_text user "License: Apache-2.0" (at -0.95 -5.169 180) (layer "B.Fab") hide
        (effects (font (size 0.7 0.7) (thickness 0.15)) (justify left bottom mirror))
    )
    (fp_text user "Author: Antmicro" (at -0.95 -4.169 180) (layer "B.Fab") hide
        (effects (font (size 0.7 0.7) (thickness 0.15)) (justify left bottom mirror))
    )
    (fp_rect (start -0.93 0.47) (end 0.93 -0.47)
      (stroke (width 0.05) (type solid)) (fill none) (layer "B.CrtYd"))
    (fp_rect (start -0.5 0.25) (end 0.5 -0.25)
      (stroke (width 0.15) (type solid)) (fill none) (layer "B.Fab"))
    (pad "1" smd roundrect (at -0.485 0) (size 0.59 0.64) (layers "B.Cu" "B.Paste" "B.Mask") (roundrect_rratio 0.25)
      (net 6 "+3V3") (pintype "passive"))
    (pad "2" smd roundrect (at 0.485 0) (size 0.59 0.64) (layers "B.Cu" "B.Paste" "B.Mask") (roundrect_rratio 0.25)
      (net 98 "Net-(R67-Pad2)") (pintype "passive"))
  )

  (footprint "sdi-mipi-bridge-footprints:R_0402_1005Metric" (layer "B.Cu")
    (at 144.99 105.475 -90)
    (descr "Resistor SMD 0402")
    (tags "resistor SMD 0402")
    (property "Author" "Antmicro")
    (property "Current" "1A")
    (property "License" "Apache-2.0")
    (property "MPN" "ERJ2GE0R00X")
    (property "Manufacturer" "Panasonic")
    (property "Sheetfile" "sdi-mipi-bridge.kicad_sch")
    (property "Sheetname" "")
    (property "Tolerance" "")
    (property "Val" "0R")
    (property "ki_description" "0R resistor in 0402 package with unspecified tolerance")
    (attr smd)
    (fp_text reference "R69" (at -3.075 -0.41 90) (layer "B.SilkS")
        (effects (font (size 0.7 0.7) (thickness 0.15)) (justify left bottom mirror))
    )
    (fp_text value "R_0R_0402" (at 0 -1.4 90) (layer "B.Fab") hide
        (effects (font (size 0.7 0.7) (thickness 0.15)) (justify left bottom mirror))
    )
    (fp_text user "Author: Antmicro" (at -0.95 -4.169 90) (layer "B.Fab") hide
        (effects (font (size 0.7 0.7) (thickness 0.15)) (justify left bottom mirror))
    )
    (fp_text user "${REFERENCE}" (at -0.95 -3.168 90) (layer "B.Fab") hide
        (effects (font (size 0.7 0.7) (thickness 0.15)) (justify left bottom mirror))
    )
    (fp_text user "License: Apache-2.0" (at -0.95 -5.169 90) (layer "B.Fab") hide
        (effects (font (size 0.7 0.7) (thickness 0.15)) (justify left bottom mirror))
    )
    (fp_rect (start -0.93 0.47) (end 0.93 -0.47)
      (stroke (width 0.05) (type solid)) (fill none) (layer "B.CrtYd"))
    (fp_rect (start -0.5 0.25) (end 0.5 -0.25)
      (stroke (width 0.15) (type solid)) (fill none) (layer "B.Fab"))
    (pad "1" smd roundrect (at -0.485 0 270) (size 0.59 0.64) (layers "B.Cu" "B.Paste" "B.Mask") (roundrect_rratio 0.25)
      (net 1 "GNDREF") (pintype "passive"))
    (pad "2" smd roundrect (at 0.485 0 270) (size 0.59 0.64) (layers "B.Cu" "B.Paste" "B.Mask") (roundrect_rratio 0.25)
      (net 59 "/GNDGPLL") (pintype "passive"))
  )

  (footprint "sdi-mipi-bridge-footprints:R_0402_1005Metric" (layer "B.Cu")
    (at 145.99 105.475 -90)
    (descr "Resistor SMD 0402")
    (tags "resistor SMD 0402")
    (property "Author" "Antmicro")
    (property "Current" "1A")
    (property "License" "Apache-2.0")
    (property "MPN" "ERJ2GE0R00X")
    (property "Manufacturer" "Panasonic")
    (property "Sheetfile" "sdi-mipi-bridge.kicad_sch")
    (property "Sheetname" "")
    (property "Tolerance" "")
    (property "Val" "0R")
    (property "ki_description" "0R resistor in 0402 package with unspecified tolerance")
    (attr smd)
    (fp_text reference "R70" (at -3.075 -0.41 90) (layer "B.SilkS")
        (effects (font (size 0.7 0.7) (thickness 0.15)) (justify left bottom mirror))
    )
    (fp_text value "R_0R_0402" (at 0 -1.4 90) (layer "B.Fab") hide
        (effects (font (size 0.7 0.7) (thickness 0.15)) (justify left bottom mirror))
    )
    (fp_text user "Author: Antmicro" (at -0.95 -4.169 90) (layer "B.Fab") hide
        (effects (font (size 0.7 0.7) (thickness 0.15)) (justify left bottom mirror))
    )
    (fp_text user "License: Apache-2.0" (at -0.95 -5.169 90) (layer "B.Fab") hide
        (effects (font (size 0.7 0.7) (thickness 0.15)) (justify left bottom mirror))
    )
    (fp_text user "${REFERENCE}" (at -0.95 -3.168 90) (layer "B.Fab") hide
        (effects (font (size 0.7 0.7) (thickness 0.15)) (justify left bottom mirror))
    )
    (fp_rect (start -0.93 0.47) (end 0.93 -0.47)
      (stroke (width 0.05) (type solid)) (fill none) (layer "B.CrtYd"))
    (fp_rect (start -0.5 0.25) (end 0.5 -0.25)
      (stroke (width 0.15) (type solid)) (fill none) (layer "B.Fab"))
    (pad "1" smd roundrect (at -0.485 0 270) (size 0.59 0.64) (layers "B.Cu" "B.Paste" "B.Mask") (roundrect_rratio 0.25)
      (net 1 "GNDREF") (pintype "passive"))
    (pad "2" smd roundrect (at 0.485 0 270) (size 0.59 0.64) (layers "B.Cu" "B.Paste" "B.Mask") (roundrect_rratio 0.25)
      (net 58 "/GNDPLL_DPHY") (pintype "passive"))
  )

  (footprint "sdi-mipi-bridge-footprints:C_0402_1005Metric" (layer "B.Cu")
    (at 131.8 132.93 90)
    (descr "Capacitor SMD 0402")
    (tags "capacitor SMD 0402")
    (property "Author" "Antmicro")
    (property "Dielectric" "X7R")
    (property "License" "Apache-2.0")
    (property "MPN" "GRM155R71H103KA88D")
    (property "Manufacturer" "Murata")
    (property "Sheetfile" "sdi-mipi-bridge.kicad_sch")
    (property "Sheetname" "")
    (property "Val" "10n")
    (property "Voltage" "50V")
    (property "ki_description" " ")
    (attr smd)
    (fp_text reference "C10" (at 0.93 0.4 90) (layer "B.SilkS")
        (effects (font (size 0.7 0.7) (thickness 0.15)) (justify right bottom mirror))
    )
    (fp_text value "C_10n_0402" (at 0 -1.4 90) (layer "B.Fab") hide
        (effects (font (size 0.7 0.7) (thickness 0.15)) (justify right bottom mirror))
    )
    (fp_text user "License: Apache-2.0" (at -0.932 -5.17 90) (layer "B.Fab") hide
        (effects (font (size 0.7 0.7) (thickness 0.15)) (justify right bottom mirror))
    )
    (fp_text user "Author: Antmicro" (at -0.932 -4.17 90) (layer "B.Fab") hide
        (effects (font (size 0.7 0.7) (thickness 0.15)) (justify right bottom mirror))
    )
    (fp_text user "${REFERENCE}" (at -0.932 -3.168 90) (layer "B.Fab") hide
        (effects (font (size 0.7 0.7) (thickness 0.15)) (justify right bottom mirror))
    )
    (fp_rect (start -0.94 0.47) (end 0.94 -0.47)
      (stroke (width 0.05) (type solid)) (fill none) (layer "B.CrtYd"))
    (fp_rect (start -0.499 0.249) (end 0.499 -0.249)
      (stroke (width 0.15) (type solid)) (fill none) (layer "B.Fab"))
    (pad "1" smd roundrect (at -0.484 0 90) (size 0.59 0.64) (layers "B.Cu" "B.Paste" "B.Mask") (roundrect_rratio 0.25)
      (net 25 "Net-(U1-BYP)") (pintype "passive"))
    (pad "2" smd roundrect (at 0.484 0 90) (size 0.59 0.64) (layers "B.Cu" "B.Paste" "B.Mask") (roundrect_rratio 0.25)
      (net 2 "+1V2") (pintype "passive"))
  )

  (footprint "sdi-mipi-bridge-footprints:R_0402_1005Metric" (layer "B.Cu")
    (at 147.925 112.925 -90)
    (descr "Resistor SMD 0402")
    (tags "resistor SMD 0402")
    (property "Author" "Antmicro")
    (property "Current" "1A")
    (property "License" "Apache-2.0")
    (property "MPN" "ERJ2GE0R00X")
    (property "Manufacturer" "Panasonic")
    (property "Sheetfile" "sdi-mipi-bridge.kicad_sch")
    (property "Sheetname" "")
    (property "Tolerance" "")
    (property "Val" "0R")
    (property "ki_description" "0R resistor in 0402 package with unspecified tolerance")
    (attr smd)
    (fp_text reference "R90" (at 6.675 -9.275 90) (layer "B.SilkS")
        (effects (font (size 0.7 0.7) (thickness 0.15)) (justify left bottom mirror))
    )
    (fp_text value "R_0R_0402" (at 0 -1.4 90) (layer "B.Fab") hide
        (effects (font (size 0.7 0.7) (thickness 0.15)) (justify left bottom mirror))
    )
    (fp_text user "Author: Antmicro" (at -0.95 -4.169 90) (layer "B.Fab") hide
        (effects (font (size 0.7 0.7) (thickness 0.15)) (justify left bottom mirror))
    )
    (fp_text user "License: Apache-2.0" (at -0.95 -5.169 90) (layer "B.Fab") hide
        (effects (font (size 0.7 0.7) (thickness 0.15)) (justify left bottom mirror))
    )
    (fp_text user "${REFERENCE}" (at -0.95 -3.168 90) (layer "B.Fab") hide
        (effects (font (size 0.7 0.7) (thickness 0.15)) (justify left bottom mirror))
    )
    (fp_rect (start -0.93 0.47) (end 0.93 -0.47)
      (stroke (width 0.05) (type solid)) (fill none) (layer "B.CrtYd"))
    (fp_rect (start -0.5 0.25) (end 0.5 -0.25)
      (stroke (width 0.15) (type solid)) (fill none) (layer "B.Fab"))
    (pad "1" smd roundrect (at -0.485 0 270) (size 0.59 0.64) (layers "B.Cu" "B.Paste" "B.Mask") (roundrect_rratio 0.25)
      (net 77 "VCCA_DPHY") (pintype "passive"))
    (pad "2" smd roundrect (at 0.485 0 270) (size 0.59 0.64) (layers "B.Cu" "B.Paste" "B.Mask") (roundrect_rratio 0.25)
      (net 85 "Net-(U4-VCCA_DPHY1)") (pintype "passive"))
  )

  (footprint "sdi-mipi-bridge-footprints:R_0402_1005Metric" (layer "B.Cu")
    (at 145.315 119.295)
    (descr "Resistor SMD 0402")
    (tags "resistor SMD 0402")
    (property "Author" "Antmicro")
    (property "Current" "1A")
    (property "License" "Apache-2.0")
    (property "MPN" "ERJ2GE0R00X")
    (property "Manufacturer" "Panasonic")
    (property "Sheetfile" "sdi-mipi-bridge.kicad_sch")
    (property "Sheetname" "")
    (property "Tolerance" "")
    (property "Val" "0R")
    (property "ki_description" "0R resistor in 0402 package with unspecified tolerance")
    (attr smd)
    (fp_text reference "R91" (at 7.685 8.105) (layer "B.SilkS")
        (effects (font (size 0.7 0.7) (thickness 0.15)) (justify right bottom mirror))
    )
    (fp_text value "R_0R_0402" (at 0 -1.4) (layer "B.Fab") hide
        (effects (font (size 0.7 0.7) (thickness 0.15)) (justify right bottom mirror))
    )
    (fp_text user "${REFERENCE}" (at -0.95 -3.168) (layer "B.Fab") hide
        (effects (font (size 0.7 0.7) (thickness 0.15)) (justify right bottom mirror))
    )
    (fp_text user "License: Apache-2.0" (at -0.95 -5.169) (layer "B.Fab") hide
        (effects (font (size 0.7 0.7) (thickness 0.15)) (justify right bottom mirror))
    )
    (fp_text user "Author: Antmicro" (at -0.95 -4.169) (layer "B.Fab") hide
        (effects (font (size 0.7 0.7) (thickness 0.15)) (justify right bottom mirror))
    )
    (fp_rect (start -0.93 0.47) (end 0.93 -0.47)
      (stroke (width 0.05) (type solid)) (fill none) (layer "B.CrtYd"))
    (fp_rect (start -0.5 0.25) (end 0.5 -0.25)
      (stroke (width 0.15) (type solid)) (fill none) (layer "B.Fab"))
    (pad "1" smd roundrect (at -0.485 0) (size 0.59 0.64) (layers "B.Cu" "B.Paste" "B.Mask") (roundrect_rratio 0.25)
      (net 77 "VCCA_DPHY") (pintype "passive"))
    (pad "2" smd roundrect (at 0.485 0) (size 0.59 0.64) (layers "B.Cu" "B.Paste" "B.Mask") (roundrect_rratio 0.25)
      (net 104 "Net-(U4-VCCA_DPHY0)") (pintype "passive"))
  )

  (footprint "sdi-mipi-bridge-footprints:C_0402_1005Metric" (layer "B.Cu")
    (at 118 110.9 -90)
    (descr "Capacitor SMD 0402")
    (tags "capacitor SMD 0402")
    (property "Author" "Antmicro")
    (property "Dielectric" "X7R")
    (property "License" "Apache-2.0")
    (property "MPN" "GRM155R71H103KA88D")
    (property "Manufacturer" "Murata")
    (property "Sheetfile" "sdi-mipi-bridge.kicad_sch")
    (property "Sheetname" "")
    (property "Val" "10n")
    (property "Voltage" "50V")
    (property "ki_description" " ")
    (attr smd)
    (fp_text reference "C11" (at -4.3 -0.4 90) (layer "B.SilkS")
        (effects (font (size 0.7 0.7) (thickness 0.15)) (justify left bottom mirror))
    )
    (fp_text value "C_10n_0402" (at 0 -1.4 90) (layer "B.Fab") hide
        (effects (font (size 0.7 0.7) (thickness 0.15)) (justify left bottom mirror))
    )
    (fp_text user "License: Apache-2.0" (at -0.932 -5.17 90) (layer "B.Fab") hide
        (effects (font (size 0.7 0.7) (thickness 0.15)) (justify left bottom mirror))
    )
    (fp_text user "${REFERENCE}" (at -0.932 -3.168 90) (layer "B.Fab") hide
        (effects (font (size 0.7 0.7) (thickness 0.15)) (justify left bottom mirror))
    )
    (fp_text user "Author: Antmicro" (at -0.932 -4.17 90) (layer "B.Fab") hide
        (effects (font (size 0.7 0.7) (thickness 0.15)) (justify left bottom mirror))
    )
    (fp_rect (start -0.94 0.47) (end 0.94 -0.47)
      (stroke (width 0.05) (type solid)) (fill none) (layer "B.CrtYd"))
    (fp_rect (start -0.499 0.249) (end 0.499 -0.249)
      (stroke (width 0.15) (type solid)) (fill none) (layer "B.Fab"))
    (pad "1" smd roundrect (at -0.484 0 270) (size 0.59 0.64) (layers "B.Cu" "B.Paste" "B.Mask") (roundrect_rratio 0.25)
      (net 3 "GNDA") (pintype "passive"))
    (pad "2" smd roundrect (at 0.484 0 270) (size 0.59 0.64) (layers "B.Cu" "B.Paste" "B.Mask") (roundrect_rratio 0.25)
      (net 4 "VPP") (pintype "passive"))
  )

  (footprint "sdi-mipi-bridge-footprints:C_0402_1005Metric" (layer "B.Cu")
    (at 119 110.9 -90)
    (descr "Capacitor SMD 0402")
    (tags "capacitor SMD 0402")
    (property "Author" "Antmicro")
    (property "Dielectric" "X7R")
    (property "License" "Apache-2.0")
    (property "MPN" "GRM155R71H103KA88D")
    (property "Manufacturer" "Murata")
    (property "Sheetfile" "sdi-mipi-bridge.kicad_sch")
    (property "Sheetname" "")
    (property "Val" "10n")
    (property "Voltage" "50V")
    (property "ki_description" " ")
    (attr smd)
    (fp_text reference "C13" (at -4.3 -0.4 90) (layer "B.SilkS")
        (effects (font (size 0.7 0.7) (thickness 0.15)) (justify left bottom mirror))
    )
    (fp_text value "C_10n_0402" (at 0 -1.4 90) (layer "B.Fab") hide
        (effects (font (size 0.7 0.7) (thickness 0.15)) (justify left bottom mirror))
    )
    (fp_text user "${REFERENCE}" (at -0.932 -3.168 90) (layer "B.Fab") hide
        (effects (font (size 0.7 0.7) (thickness 0.15)) (justify left bottom mirror))
    )
    (fp_text user "License: Apache-2.0" (at -0.932 -5.17 90) (layer "B.Fab") hide
        (effects (font (size 0.7 0.7) (thickness 0.15)) (justify left bottom mirror))
    )
    (fp_text user "Author: Antmicro" (at -0.932 -4.17 90) (layer "B.Fab") hide
        (effects (font (size 0.7 0.7) (thickness 0.15)) (justify left bottom mirror))
    )
    (fp_rect (start -0.94 0.47) (end 0.94 -0.47)
      (stroke (width 0.05) (type solid)) (fill none) (layer "B.CrtYd"))
    (fp_rect (start -0.499 0.249) (end 0.499 -0.249)
      (stroke (width 0.15) (type solid)) (fill none) (layer "B.Fab"))
    (pad "1" smd roundrect (at -0.484 0 270) (size 0.59 0.64) (layers "B.Cu" "B.Paste" "B.Mask") (roundrect_rratio 0.25)
      (net 3 "GNDA") (pintype "passive"))
    (pad "2" smd roundrect (at 0.484 0 270) (size 0.59 0.64) (layers "B.Cu" "B.Paste" "B.Mask") (roundrect_rratio 0.25)
      (net 4 "VPP") (pintype "passive"))
  )

  (footprint "sdi-mipi-bridge-footprints:C_0402_1005Metric" (layer "B.Cu")
    (at 117 110.9 -90)
    (descr "Capacitor SMD 0402")
    (tags "capacitor SMD 0402")
    (property "Author" "Antmicro")
    (property "Dielectric" "X7R")
    (property "License" "Apache-2.0")
    (property "MPN" "GRM155R71H103KA88D")
    (property "Manufacturer" "Murata")
    (property "Sheetfile" "sdi-mipi-bridge.kicad_sch")
    (property "Sheetname" "")
    (property "Val" "10n")
    (property "Voltage" "50V")
    (property "ki_description" " ")
    (attr smd)
    (fp_text reference "C16" (at -4.3 -0.4 90) (layer "B.SilkS")
        (effects (font (size 0.7 0.7) (thickness 0.15)) (justify left bottom mirror))
    )
    (fp_text value "C_10n_0402" (at 0 -1.4 90) (layer "B.Fab") hide
        (effects (font (size 0.7 0.7) (thickness 0.15)) (justify left bottom mirror))
    )
    (fp_text user "${REFERENCE}" (at -0.932 -3.168 90) (layer "B.Fab") hide
        (effects (font (size 0.7 0.7) (thickness 0.15)) (justify left bottom mirror))
    )
    (fp_text user "Author: Antmicro" (at -0.932 -4.17 90) (layer "B.Fab") hide
        (effects (font (size 0.7 0.7) (thickness 0.15)) (justify left bottom mirror))
    )
    (fp_text user "License: Apache-2.0" (at -0.932 -5.17 90) (layer "B.Fab") hide
        (effects (font (size 0.7 0.7) (thickness 0.15)) (justify left bottom mirror))
    )
    (fp_rect (start -0.94 0.47) (end 0.94 -0.47)
      (stroke (width 0.05) (type solid)) (fill none) (layer "B.CrtYd"))
    (fp_rect (start -0.499 0.249) (end 0.499 -0.249)
      (stroke (width 0.15) (type solid)) (fill none) (layer "B.Fab"))
    (pad "1" smd roundrect (at -0.484 0 270) (size 0.59 0.64) (layers "B.Cu" "B.Paste" "B.Mask") (roundrect_rratio 0.25)
      (net 3 "GNDA") (pintype "passive"))
    (pad "2" smd roundrect (at 0.484 0 270) (size 0.59 0.64) (layers "B.Cu" "B.Paste" "B.Mask") (roundrect_rratio 0.25)
      (net 4 "VPP") (pintype "passive"))
  )

  (footprint "sdi-mipi-bridge-footprints:C_0402_1005Metric" (layer "B.Cu")
    (at 120 115.4)
    (descr "Capacitor SMD 0402")
    (tags "capacitor SMD 0402")
    (property "Author" "Antmicro")
    (property "Dielectric" "X7R")
    (property "License" "Apache-2.0")
    (property "MPN" "GRM155R71H103KA88D")
    (property "Manufacturer" "Murata")
    (property "Sheetfile" "sdi-mipi-bridge.kicad_sch")
    (property "Sheetname" "")
    (property "Val" "10n")
    (property "Voltage" "50V")
    (property "ki_description" " ")
    (attr smd)
    (fp_text reference "C6" (at -2.2 0.4) (layer "B.SilkS")
        (effects (font (size 0.7 0.7) (thickness 0.15)) (justify right bottom mirror))
    )
    (fp_text value "C_10n_0402" (at 0 -1.4) (layer "B.Fab") hide
        (effects (font (size 0.7 0.7) (thickness 0.15)) (justify right bottom mirror))
    )
    (fp_text user "${REFERENCE}" (at -0.932 -3.168) (layer "B.Fab") hide
        (effects (font (size 0.7 0.7) (thickness 0.15)) (justify right bottom mirror))
    )
    (fp_text user "License: Apache-2.0" (at -0.932 -5.17) (layer "B.Fab") hide
        (effects (font (size 0.7 0.7) (thickness 0.15)) (justify right bottom mirror))
    )
    (fp_text user "Author: Antmicro" (at -0.932 -4.17) (layer "B.Fab") hide
        (effects (font (size 0.7 0.7) (thickness 0.15)) (justify right bottom mirror))
    )
    (fp_rect (start -0.94 0.47) (end 0.94 -0.47)
      (stroke (width 0.05) (type solid)) (fill none) (layer "B.CrtYd"))
    (fp_rect (start -0.499 0.249) (end 0.499 -0.249)
      (stroke (width 0.15) (type solid)) (fill none) (layer "B.Fab"))
    (pad "1" smd roundrect (at -0.484 0) (size 0.59 0.64) (layers "B.Cu" "B.Paste" "B.Mask") (roundrect_rratio 0.25)
      (net 1 "GNDREF") (pintype "passive"))
    (pad "2" smd roundrect (at 0.484 0) (size 0.59 0.64) (layers "B.Cu" "B.Paste" "B.Mask") (roundrect_rratio 0.25)
      (net 2 "+1V2") (pintype "passive"))
  )

  (footprint "sdi-mipi-bridge-footprints:C_0402_1005Metric" (layer "B.Cu")
    (at 122 115.4)
    (descr "Capacitor SMD 0402")
    (tags "capacitor SMD 0402")
    (property "Author" "Antmicro")
    (property "Dielectric" "X7R")
    (property "License" "Apache-2.0")
    (property "MPN" "GRM155R71H103KA88D")
    (property "Manufacturer" "Murata")
    (property "Sheetfile" "sdi-mipi-bridge.kicad_sch")
    (property "Sheetname" "")
    (property "Val" "10n")
    (property "Voltage" "50V")
    (property "ki_description" " ")
    (attr smd)
    (fp_text reference "C8" (at 0.8 0.4) (layer "B.SilkS")
        (effects (font (size 0.7 0.7) (thickness 0.15)) (justify right bottom mirror))
    )
    (fp_text value "C_10n_0402" (at 0 -1.4) (layer "B.Fab") hide
        (effects (font (size 0.7 0.7) (thickness 0.15)) (justify right bottom mirror))
    )
    (fp_text user "${REFERENCE}" (at -0.932 -3.168) (layer "B.Fab") hide
        (effects (font (size 0.7 0.7) (thickness 0.15)) (justify right bottom mirror))
    )
    (fp_text user "Author: Antmicro" (at -0.932 -4.17) (layer "B.Fab") hide
        (effects (font (size 0.7 0.7) (thickness 0.15)) (justify right bottom mirror))
    )
    (fp_text user "License: Apache-2.0" (at -0.932 -5.17) (layer "B.Fab") hide
        (effects (font (size 0.7 0.7) (thickness 0.15)) (justify right bottom mirror))
    )
    (fp_rect (start -0.94 0.47) (end 0.94 -0.47)
      (stroke (width 0.05) (type solid)) (fill none) (layer "B.CrtYd"))
    (fp_rect (start -0.499 0.249) (end 0.499 -0.249)
      (stroke (width 0.15) (type solid)) (fill none) (layer "B.Fab"))
    (pad "1" smd roundrect (at -0.484 0) (size 0.59 0.64) (layers "B.Cu" "B.Paste" "B.Mask") (roundrect_rratio 0.25)
      (net 1 "GNDREF") (pintype "passive"))
    (pad "2" smd roundrect (at 0.484 0) (size 0.59 0.64) (layers "B.Cu" "B.Paste" "B.Mask") (roundrect_rratio 0.25)
      (net 2 "+1V2") (pintype "passive"))
  )

  (footprint "sdi-mipi-bridge-footprints:C_0402_1005Metric" (layer "B.Cu")
    (at 126.5 110.9 -90)
    (descr "Capacitor SMD 0402")
    (tags "capacitor SMD 0402")
    (property "Author" "Antmicro")
    (property "Dielectric" "X7R")
    (property "License" "Apache-2.0")
    (property "MPN" "GRM155R71H103KA88D")
    (property "Manufacturer" "Murata")
    (property "Sheetfile" "sdi-mipi-bridge.kicad_sch")
    (property "Sheetname" "")
    (property "Val" "10n")
    (property "Voltage" "50V")
    (property "ki_description" " ")
    (attr smd)
    (fp_text reference "C7" (at 0.9 -0.3 90) (layer "B.SilkS")
        (effects (font (size 0.7 0.7) (thickness 0.15)) (justify left bottom mirror))
    )
    (fp_text value "C_10n_0402" (at 0 -1.4 90) (layer "B.Fab") hide
        (effects (font (size 0.7 0.7) (thickness 0.15)) (justify left bottom mirror))
    )
    (fp_text user "Author: Antmicro" (at -0.932 -4.17 90) (layer "B.Fab") hide
        (effects (font (size 0.7 0.7) (thickness 0.15)) (justify left bottom mirror))
    )
    (fp_text user "${REFERENCE}" (at -0.932 -3.168 90) (layer "B.Fab") hide
        (effects (font (size 0.7 0.7) (thickness 0.15)) (justify left bottom mirror))
    )
    (fp_text user "License: Apache-2.0" (at -0.932 -5.17 90) (layer "B.Fab") hide
        (effects (font (size 0.7 0.7) (thickness 0.15)) (justify left bottom mirror))
    )
    (fp_rect (start -0.94 0.47) (end 0.94 -0.47)
      (stroke (width 0.05) (type solid)) (fill none) (layer "B.CrtYd"))
    (fp_rect (start -0.499 0.249) (end 0.499 -0.249)
      (stroke (width 0.15) (type solid)) (fill none) (layer "B.Fab"))
    (pad "1" smd roundrect (at -0.484 0 270) (size 0.59 0.64) (layers "B.Cu" "B.Paste" "B.Mask") (roundrect_rratio 0.25)
      (net 1 "GNDREF") (pintype "passive"))
    (pad "2" smd roundrect (at 0.484 0 270) (size 0.59 0.64) (layers "B.Cu" "B.Paste" "B.Mask") (roundrect_rratio 0.25)
      (net 76 "IO_VDD") (pintype "passive"))
  )

  (footprint "sdi-mipi-bridge-footprints:C_0402_1005Metric" (layer "B.Cu")
    (at 134.05 134.08)
    (descr "Capacitor SMD 0402")
    (tags "capacitor SMD 0402")
    (property "Author" "Antmicro")
    (property "Dielectric" "X7R")
    (property "License" "Apache-2.0")
    (property "MPN" "GRM155R71H103KA88D")
    (property "Manufacturer" "Murata")
    (property "Sheetfile" "sdi-mipi-bridge.kicad_sch")
    (property "Sheetname" "")
    (property "Val" "10n")
    (property "Voltage" "50V")
    (property "ki_description" " ")
    (attr smd)
    (fp_text reference "C20" (at 2.15 0.32) (layer "B.SilkS")
        (effects (font (size 0.7 0.7) (thickness 0.15)) (justify right bottom mirror))
    )
    (fp_text value "C_10n_0402" (at 100 -1.423) (layer "B.Fab") hide
        (effects (font (size 0.7 0.7) (thickness 0.15)) (justify right bottom mirror))
    )
    (fp_text user "Author: Antmicro" (at -0.932 -4.17) (layer "B.Fab") hide
        (effects (font (size 0.7 0.7) (thickness 0.15)) (justify right bottom mirror))
    )
    (fp_text user "${REFERENCE}" (at -0.932 -3.168) (layer "B.Fab") hide
        (effects (font (size 0.7 0.7) (thickness 0.15)) (justify right bottom mirror))
    )
    (fp_text user "License: Apache-2.0" (at -0.932 -5.17) (layer "B.Fab") hide
        (effects (font (size 0.7 0.7) (thickness 0.15)) (justify right bottom mirror))
    )
    (fp_rect (start -0.94 0.47) (end 0.94 -0.47)
      (stroke (width 0.05) (type solid)) (fill none) (layer "B.CrtYd"))
    (fp_rect (start -0.499 0.249) (end 0.499 -0.249)
      (stroke (width 0.15) (type solid)) (fill none) (layer "B.Fab"))
    (pad "1" smd roundrect (at -0.484 0) (size 0.59 0.64) (layers "B.Cu" "B.Paste" "B.Mask") (roundrect_rratio 0.25)
      (net 1 "GNDREF") (pintype "passive"))
    (pad "2" smd roundrect (at 0.484 0) (size 0.59 0.64) (layers "B.Cu" "B.Paste" "B.Mask") (roundrect_rratio 0.25)
      (net 2 "+1V2") (pintype "passive"))
  )

  (footprint "sdi-mipi-bridge-footprints:C_0402_1005Metric" (layer "B.Cu")
    (at 134.05 133.08)
    (descr "Capacitor SMD 0402")
    (tags "capacitor SMD 0402")
    (property "Author" "Antmicro")
    (property "Dielectric" "")
    (property "License" "Apache-2.0")
    (property "MPN" "C1005X6S1A105K050BC")
    (property "Manufacturer" "TDK")
    (property "Sheetfile" "sdi-mipi-bridge.kicad_sch")
    (property "Sheetname" "")
    (property "Val" "1u")
    (property "Voltage" "")
    (property "ki_description" " ")
    (attr smd)
    (fp_text reference "C25" (at 2.15 0.32) (layer "B.SilkS")
        (effects (font (size 0.7 0.7) (thickness 0.15)) (justify right bottom mirror))
    )
    (fp_text value "C_1u_0402" (at 100 -1.423) (layer "B.Fab") hide
        (effects (font (size 0.7 0.7) (thickness 0.15)) (justify right bottom mirror))
    )
    (fp_text user "Author: Antmicro" (at -0.932 -4.17) (layer "B.Fab") hide
        (effects (font (size 0.7 0.7) (thickness 0.15)) (justify right bottom mirror))
    )
    (fp_text user "${REFERENCE}" (at -0.932 -3.168) (layer "B.Fab") hide
        (effects (font (size 0.7 0.7) (thickness 0.15)) (justify right bottom mirror))
    )
    (fp_text user "License: Apache-2.0" (at -0.932 -5.17) (layer "B.Fab") hide
        (effects (font (size 0.7 0.7) (thickness 0.15)) (justify right bottom mirror))
    )
    (fp_rect (start -0.94 0.47) (end 0.94 -0.47)
      (stroke (width 0.05) (type solid)) (fill none) (layer "B.CrtYd"))
    (fp_rect (start -0.499 0.249) (end 0.499 -0.249)
      (stroke (width 0.15) (type solid)) (fill none) (layer "B.Fab"))
    (pad "1" smd roundrect (at -0.484 0) (size 0.59 0.64) (layers "B.Cu" "B.Paste" "B.Mask") (roundrect_rratio 0.25)
      (net 1 "GNDREF") (pintype "passive"))
    (pad "2" smd roundrect (at 0.484 0) (size 0.59 0.64) (layers "B.Cu" "B.Paste" "B.Mask") (roundrect_rratio 0.25)
      (net 2 "+1V2") (pintype "passive"))
  )

  (footprint "sdi-mipi-bridge-footprints:C_0402_1005Metric" (layer "B.Cu")
    (at 134.05 132.08)
    (descr "Capacitor SMD 0402")
    (tags "capacitor SMD 0402")
    (property "Author" "Antmicro")
    (property "Dielectric" "")
    (property "License" "Apache-2.0")
    (property "MPN" "C1005X6S1A105K050BC")
    (property "Manufacturer" "TDK")
    (property "Sheetfile" "sdi-mipi-bridge.kicad_sch")
    (property "Sheetname" "")
    (property "Val" "1u")
    (property "Voltage" "")
    (property "ki_description" " ")
    (attr smd)
    (fp_text reference "C29" (at 2.15 0.32) (layer "B.SilkS")
        (effects (font (size 0.7 0.7) (thickness 0.15)) (justify right bottom mirror))
    )
    (fp_text value "C_1u_0402" (at 100 -1.423) (layer "B.Fab") hide
        (effects (font (size 0.7 0.7) (thickness 0.15)) (justify right bottom mirror))
    )
    (fp_text user "Author: Antmicro" (at -0.932 -4.17) (layer "B.Fab") hide
        (effects (font (size 0.7 0.7) (thickness 0.15)) (justify right bottom mirror))
    )
    (fp_text user "${REFERENCE}" (at -0.932 -3.168) (layer "B.Fab") hide
        (effects (font (size 0.7 0.7) (thickness 0.15)) (justify right bottom mirror))
    )
    (fp_text user "License: Apache-2.0" (at -0.932 -5.17) (layer "B.Fab") hide
        (effects (font (size 0.7 0.7) (thickness 0.15)) (justify right bottom mirror))
    )
    (fp_rect (start -0.94 0.47) (end 0.94 -0.47)
      (stroke (width 0.05) (type solid)) (fill none) (layer "B.CrtYd"))
    (fp_rect (start -0.499 0.249) (end 0.499 -0.249)
      (stroke (width 0.15) (type solid)) (fill none) (layer "B.Fab"))
    (pad "1" smd roundrect (at -0.484 0) (size 0.59 0.64) (layers "B.Cu" "B.Paste" "B.Mask") (roundrect_rratio 0.25)
      (net 3 "GNDA") (pintype "passive"))
    (pad "2" smd roundrect (at 0.484 0) (size 0.59 0.64) (layers "B.Cu" "B.Paste" "B.Mask") (roundrect_rratio 0.25)
      (net 4 "VPP") (pintype "passive"))
  )

  (footprint "sdi-mipi-bridge-footprints:C_0402_1005Metric" (layer "B.Cu")
    (at 134.05 131.08)
    (descr "Capacitor SMD 0402")
    (tags "capacitor SMD 0402")
    (property "Author" "Antmicro")
    (property "Dielectric" "X7R")
    (property "License" "Apache-2.0")
    (property "MPN" "GRM155R71H103KA88D")
    (property "Manufacturer" "Murata")
    (property "Sheetfile" "sdi-mipi-bridge.kicad_sch")
    (property "Sheetname" "")
    (property "Val" "10n")
    (property "Voltage" "50V")
    (property "ki_description" " ")
    (attr smd)
    (fp_text reference "C33" (at 2.15 0.32) (layer "B.SilkS")
        (effects (font (size 0.7 0.7) (thickness 0.15)) (justify right bottom mirror))
    )
    (fp_text value "C_10n_0402" (at 100 -1.423) (layer "B.Fab") hide
        (effects (font (size 0.7 0.7) (thickness 0.15)) (justify right bottom mirror))
    )
    (fp_text user "Author: Antmicro" (at -0.932 -4.17) (layer "B.Fab") hide
        (effects (font (size 0.7 0.7) (thickness 0.15)) (justify right bottom mirror))
    )
    (fp_text user "${REFERENCE}" (at -0.932 -3.168) (layer "B.Fab") hide
        (effects (font (size 0.7 0.7) (thickness 0.15)) (justify right bottom mirror))
    )
    (fp_text user "License: Apache-2.0" (at -0.932 -5.17) (layer "B.Fab") hide
        (effects (font (size 0.7 0.7) (thickness 0.15)) (justify right bottom mirror))
    )
    (fp_rect (start -0.94 0.47) (end 0.94 -0.47)
      (stroke (width 0.05) (type solid)) (fill none) (layer "B.CrtYd"))
    (fp_rect (start -0.499 0.249) (end 0.499 -0.249)
      (stroke (width 0.15) (type solid)) (fill none) (layer "B.Fab"))
    (pad "1" smd roundrect (at -0.484 0) (size 0.59 0.64) (layers "B.Cu" "B.Paste" "B.Mask") (roundrect_rratio 0.25)
      (net 3 "GNDA") (pintype "passive"))
    (pad "2" smd roundrect (at 0.484 0) (size 0.59 0.64) (layers "B.Cu" "B.Paste" "B.Mask") (roundrect_rratio 0.25)
      (net 4 "VPP") (pintype "passive"))
  )

  (footprint "sdi-mipi-bridge-footprints:R_0402_1005Metric" (layer "B.Cu")
    (at 134.05 135.08 180)
    (descr "Resistor SMD 0402")
    (tags "resistor SMD 0402")
    (property "Author" "Antmicro")
    (property "License" "Apache-2.0")
    (property "MPN" "CR0402-FX-1203GLF")
    (property "Manufacturer" "Bourns")
    (property "Sheetfile" "sdi-mipi-bridge.kicad_sch")
    (property "Sheetname" "")
    (property "Tolerance" "1%")
    (property "Val" "120k")
    (property "ki_description" "120k resistor in 0402 package with 1% tolerance")
    (attr smd)
    (fp_text reference "R5" (at -4.35 -0.32) (layer "B.SilkS")
        (effects (font (size 0.7 0.7) (thickness 0.15)) (justify left bottom mirror))
    )
    (fp_text value "R_120k_0402" (at 0 -1.4) (layer "B.Fab") hide
        (effects (font (size 0.7 0.7) (thickness 0.15)) (justify left bottom mirror))
    )
    (fp_text user "${REFERENCE}" (at -0.95 -3.168) (layer "B.Fab") hide
        (effects (font (size 0.7 0.7) (thickness 0.15)) (justify left bottom mirror))
    )
    (fp_text user "Author: Antmicro" (at -0.95 -4.169) (layer "B.Fab") hide
        (effects (font (size 0.7 0.7) (thickness 0.15)) (justify left bottom mirror))
    )
    (fp_text user "License: Apache-2.0" (at -0.95 -5.169) (layer "B.Fab") hide
        (effects (font (size 0.7 0.7) (thickness 0.15)) (justify left bottom mirror))
    )
    (fp_rect (start -0.93 0.47) (end 0.93 -0.47)
      (stroke (width 0.05) (type solid)) (fill none) (layer "B.CrtYd"))
    (fp_rect (start -0.5 0.25) (end 0.5 -0.25)
      (stroke (width 0.15) (type solid)) (fill none) (layer "B.Fab"))
    (pad "1" smd roundrect (at -0.485 0 180) (size 0.59 0.64) (layers "B.Cu" "B.Paste" "B.Mask") (roundrect_rratio 0.25)
      (net 2 "+1V2") (pintype "passive"))
    (pad "2" smd roundrect (at 0.485 0 180) (size 0.59 0.64) (layers "B.Cu" "B.Paste" "B.Mask") (roundrect_rratio 0.25)
      (net 71 "Net-(U1-FB)") (pintype "passive"))
  )

  (footprint "sdi-mipi-bridge-footprints:R_0402_1005Metric" (layer "B.Cu")
    (at 134.05 136.08)
    (descr "Resistor SMD 0402")
    (tags "resistor SMD 0402")
    (property "Author" "Antmicro")
    (property "License" "Apache-2.0")
    (property "MPN" "CR0402-FX-1203GLF")
    (property "Manufacturer" "Bourns")
    (property "Sheetfile" "sdi-mipi-bridge.kicad_sch")
    (property "Sheetname" "")
    (property "Tolerance" "1%")
    (property "Val" "120k")
    (property "ki_description" "120k resistor in 0402 package with 1% tolerance")
    (attr smd)
    (fp_text reference "R6" (at 4.35 0.32) (layer "B.SilkS")
        (effects (font (size 0.7 0.7) (thickness 0.15)) (justify left bottom mirror))
    )
    (fp_text value "R_120k_0402" (at -100 -1.377) (layer "B.Fab") hide
        (effects (font (size 0.7 0.7) (thickness 0.15)) (justify right bottom mirror))
    )
    (fp_text user "${REFERENCE}" (at -0.95 -3.168) (layer "B.Fab") hide
        (effects (font (size 0.7 0.7) (thickness 0.15)) (justify right bottom mirror))
    )
    (fp_text user "Author: Antmicro" (at -0.95 -4.169) (layer "B.Fab") hide
        (effects (font (size 0.7 0.7) (thickness 0.15)) (justify right bottom mirror))
    )
    (fp_text user "License: Apache-2.0" (at -0.95 -5.169) (layer "B.Fab") hide
        (effects (font (size 0.7 0.7) (thickness 0.15)) (justify right bottom mirror))
    )
    (fp_rect (start -0.93 0.47) (end 0.93 -0.47)
      (stroke (width 0.05) (type solid)) (fill none) (layer "B.CrtYd"))
    (fp_rect (start -0.5 0.25) (end 0.5 -0.25)
      (stroke (width 0.15) (type solid)) (fill none) (layer "B.Fab"))
    (pad "1" smd roundrect (at -0.485 0) (size 0.59 0.64) (layers "B.Cu" "B.Paste" "B.Mask") (roundrect_rratio 0.25)
      (net 71 "Net-(U1-FB)") (pintype "passive"))
    (pad "2" smd roundrect (at 0.485 0) (size 0.59 0.64) (layers "B.Cu" "B.Paste" "B.Mask") (roundrect_rratio 0.25)
      (net 1 "GNDREF") (pintype "passive"))
  )

  (footprint "sdi-mipi-bridge-footprints:C_0402_1005Metric" (layer "B.Cu")
    (at 109.75 134.25 -90)
    (descr "Capacitor SMD 0402")
    (tags "capacitor SMD 0402")
    (property "Author" "Antmicro")
    (property "Dielectric" "X7R")
    (property "License" "Apache-2.0")
    (property "MPN" "GRM155R71H103KA88D")
    (property "Manufacturer" "Murata")
    (property "Sheetfile" "sdi-mipi-bridge.kicad_sch")
    (property "Sheetname" "")
    (property "Val" "10n")
    (property "Voltage" "50V")
    (property "ki_description" " ")
    (attr smd)
    (fp_text reference "C21" (at -3.65 -0.45 90) (layer "B.SilkS")
        (effects (font (size 0.7 0.7) (thickness 0.15)) (justify left bottom mirror))
    )
    (fp_text value "C_10n_0402" (at 0 -1.4 90) (layer "B.Fab") hide
        (effects (font (size 0.7 0.7) (thickness 0.15)) (justify left bottom mirror))
    )
    (fp_text user "${REFERENCE}" (at -0.932 -3.168 90) (layer "B.Fab") hide
        (effects (font (size 0.7 0.7) (thickness 0.15)) (justify left bottom mirror))
    )
    (fp_text user "Author: Antmicro" (at -0.932 -4.17 90) (layer "B.Fab") hide
        (effects (font (size 0.7 0.7) (thickness 0.15)) (justify left bottom mirror))
    )
    (fp_text user "License: Apache-2.0" (at -0.932 -5.17 90) (layer "B.Fab") hide
        (effects (font (size 0.7 0.7) (thickness 0.15)) (justify left bottom mirror))
    )
    (fp_rect (start -0.94 0.47) (end 0.94 -0.47)
      (stroke (width 0.05) (type solid)) (fill none) (layer "B.CrtYd"))
    (fp_rect (start -0.499 0.249) (end 0.499 -0.249)
      (stroke (width 0.15) (type solid)) (fill none) (layer "B.Fab"))
    (pad "1" smd roundrect (at -0.484 0 270) (size 0.59 0.64) (layers "B.Cu" "B.Paste" "B.Mask") (roundrect_rratio 0.25)
      (net 1 "GNDREF") (pintype "passive"))
    (pad "2" smd roundrect (at 0.484 0 270) (size 0.59 0.64) (layers "B.Cu" "B.Paste" "B.Mask") (roundrect_rratio 0.25)
      (net 6 "+3V3") (pintype "passive"))
  )

  (footprint "sdi-mipi-bridge-footprints:C_0402_1005Metric" (layer "B.Cu")
    (at 110.75 134.25 -90)
    (descr "Capacitor SMD 0402")
    (tags "capacitor SMD 0402")
    (property "Author" "Antmicro")
    (property "Dielectric" "")
    (property "License" "Apache-2.0")
    (property "MPN" "C1005X6S1A105K050BC")
    (property "Manufacturer" "TDK")
    (property "Sheetfile" "sdi-mipi-bridge.kicad_sch")
    (property "Sheetname" "")
    (property "Val" "1u")
    (property "Voltage" "")
    (property "ki_description" " ")
    (attr smd)
    (fp_text reference "C26" (at -3.65 -0.45 90) (layer "B.SilkS")
        (effects (font (size 0.7 0.7) (thickness 0.15)) (justify left bottom mirror))
    )
    (fp_text value "C_1u_0402" (at 0 -1.4 90) (layer "B.Fab") hide
        (effects (font (size 0.7 0.7) (thickness 0.15)) (justify left bottom mirror))
    )
    (fp_text user "Author: Antmicro" (at -0.932 -4.17 90) (layer "B.Fab") hide
        (effects (font (size 0.7 0.7) (thickness 0.15)) (justify left bottom mirror))
    )
    (fp_text user "${REFERENCE}" (at -0.932 -3.168 90) (layer "B.Fab") hide
        (effects (font (size 0.7 0.7) (thickness 0.15)) (justify left bottom mirror))
    )
    (fp_text user "License: Apache-2.0" (at -0.932 -5.17 90) (layer "B.Fab") hide
        (effects (font (size 0.7 0.7) (thickness 0.15)) (justify left bottom mirror))
    )
    (fp_rect (start -0.94 0.47) (end 0.94 -0.47)
      (stroke (width 0.05) (type solid)) (fill none) (layer "B.CrtYd"))
    (fp_rect (start -0.499 0.249) (end 0.499 -0.249)
      (stroke (width 0.15) (type solid)) (fill none) (layer "B.Fab"))
    (pad "1" smd roundrect (at -0.484 0 270) (size 0.59 0.64) (layers "B.Cu" "B.Paste" "B.Mask") (roundrect_rratio 0.25)
      (net 1 "GNDREF") (pintype "passive"))
    (pad "2" smd roundrect (at 0.484 0 270) (size 0.59 0.64) (layers "B.Cu" "B.Paste" "B.Mask") (roundrect_rratio 0.25)
      (net 6 "+3V3") (pintype "passive"))
  )

  (footprint "sdi-mipi-bridge-footprints:C_0402_1005Metric" (layer "B.Cu")
    (at 112.75 134.25 90)
    (descr "Capacitor SMD 0402")
    (tags "capacitor SMD 0402")
    (property "Author" "Antmicro")
    (property "Dielectric" "")
    (property "License" "Apache-2.0")
    (property "MPN" "C1005X6S1A105K050BC")
    (property "Manufacturer" "TDK")
    (property "Sheetfile" "sdi-mipi-bridge.kicad_sch")
    (property "Sheetname" "")
    (property "Val" "1u")
    (property "Voltage" "")
    (property "ki_description" " ")
    (attr smd)
    (fp_text reference "C30" (at 1.45 0.45 90) (layer "B.SilkS")
        (effects (font (size 0.7 0.7) (thickness 0.15)) (justify right bottom mirror))
    )
    (fp_text value "C_1u_0402" (at 0 -1.4 90) (layer "B.Fab") hide
        (effects (font (size 0.7 0.7) (thickness 0.15)) (justify right bottom mirror))
    )
    (fp_text user "Author: Antmicro" (at -0.932 -4.17 90) (layer "B.Fab") hide
        (effects (font (size 0.7 0.7) (thickness 0.15)) (justify right bottom mirror))
    )
    (fp_text user "${REFERENCE}" (at -0.932 -3.168 90) (layer "B.Fab") hide
        (effects (font (size 0.7 0.7) (thickness 0.15)) (justify right bottom mirror))
    )
    (fp_text user "License: Apache-2.0" (at -0.932 -5.17 90) (layer "B.Fab") hide
        (effects (font (size 0.7 0.7) (thickness 0.15)) (justify right bottom mirror))
    )
    (fp_rect (start -0.94 0.47) (end 0.94 -0.47)
      (stroke (width 0.05) (type solid)) (fill none) (layer "B.CrtYd"))
    (fp_rect (start -0.499 0.249) (end 0.499 -0.249)
      (stroke (width 0.15) (type solid)) (fill none) (layer "B.Fab"))
    (pad "1" smd roundrect (at -0.484 0 90) (size 0.59 0.64) (layers "B.Cu" "B.Paste" "B.Mask") (roundrect_rratio 0.25)
      (net 3 "GNDA") (pintype "passive"))
    (pad "2" smd roundrect (at 0.484 0 90) (size 0.59 0.64) (layers "B.Cu" "B.Paste" "B.Mask") (roundrect_rratio 0.25)
      (net 57 "VDD") (pintype "passive"))
  )

  (footprint "sdi-mipi-bridge-footprints:C_0402_1005Metric" (layer "B.Cu")
    (at 113.75 134.25 90)
    (descr "Capacitor SMD 0402")
    (tags "capacitor SMD 0402")
    (property "Author" "Antmicro")
    (property "Dielectric" "X7R")
    (property "License" "Apache-2.0")
    (property "MPN" "GRM155R71H103KA88D")
    (property "Manufacturer" "Murata")
    (property "Sheetfile" "sdi-mipi-bridge.kicad_sch")
    (property "Sheetname" "")
    (property "Val" "10n")
    (property "Voltage" "50V")
    (property "ki_description" " ")
    (attr smd)
    (fp_text reference "C34" (at 1.45 0.45 90) (layer "B.SilkS")
        (effects (font (size 0.7 0.7) (thickness 0.15)) (justify right bottom mirror))
    )
    (fp_text value "C_10n_0402" (at 0 -1.4 90) (layer "B.Fab") hide
        (effects (font (size 0.7 0.7) (thickness 0.15)) (justify right bottom mirror))
    )
    (fp_text user "${REFERENCE}" (at -0.932 -3.168 90) (layer "B.Fab") hide
        (effects (font (size 0.7 0.7) (thickness 0.15)) (justify right bottom mirror))
    )
    (fp_text user "Author: Antmicro" (at -0.932 -4.17 90) (layer "B.Fab") hide
        (effects (font (size 0.7 0.7) (thickness 0.15)) (justify right bottom mirror))
    )
    (fp_text user "License: Apache-2.0" (at -0.932 -5.17 90) (layer "B.Fab") hide
        (effects (font (size 0.7 0.7) (thickness 0.15)) (justify right bottom mirror))
    )
    (fp_rect (start -0.94 0.47) (end 0.94 -0.47)
      (stroke (width 0.05) (type solid)) (fill none) (layer "B.CrtYd"))
    (fp_rect (start -0.499 0.249) (end 0.499 -0.249)
      (stroke (width 0.15) (type solid)) (fill none) (layer "B.Fab"))
    (pad "1" smd roundrect (at -0.484 0 90) (size 0.59 0.64) (layers "B.Cu" "B.Paste" "B.Mask") (roundrect_rratio 0.25)
      (net 3 "GNDA") (pintype "passive"))
    (pad "2" smd roundrect (at 0.484 0 90) (size 0.59 0.64) (layers "B.Cu" "B.Paste" "B.Mask") (roundrect_rratio 0.25)
      (net 57 "VDD") (pintype "passive"))
  )

  (footprint "sdi-mipi-bridge-footprints:R_0402_1005Metric" (layer "B.Cu")
    (at 113.96 119.41 -90)
    (descr "Resistor SMD 0402")
    (tags "resistor SMD 0402")
    (property "Author" "Antmicro")
    (property "License" "Apache-2.0")
    (property "MPN" "CR0402-FX-7500GLF")
    (property "Manufacturer" "Bourns")
    (property "Sheetfile" "sdi-mipi-bridge.kicad_sch")
    (property "Sheetname" "")
    (property "Tolerance" "1%")
    (property "Val" "750R")
    (property "ki_description" "750R resistor in 0402 package with 1% tolerance")
    (attr smd)
    (fp_text reference "R4" (at -0.81 0.76 90) (layer "B.SilkS")
        (effects (font (size 0.7 0.7) (thickness 0.15)) (justify left bottom mirror))
    )
    (fp_text value "R_750R_0402" (at 0 -1.4 90) (layer "B.Fab") hide
        (effects (font (size 0.7 0.7) (thickness 0.15)) (justify left bottom mirror))
    )
    (fp_text user "Author: Antmicro" (at -0.95 -4.169 90) (layer "B.Fab") hide
        (effects (font (size 0.7 0.7) (thickness 0.15)) (justify left bottom mirror))
    )
    (fp_text user "License: Apache-2.0" (at -0.95 -5.169 90) (layer "B.Fab") hide
        (effects (font (size 0.7 0.7) (thickness 0.15)) (justify left bottom mirror))
    )
    (fp_text user "${REFERENCE}" (at -0.95 -3.168 90) (layer "B.Fab") hide
        (effects (font (size 0.7 0.7) (thickness 0.15)) (justify left bottom mirror))
    )
    (fp_rect (start -0.93 0.47) (end 0.93 -0.47)
      (stroke (width 0.05) (type solid)) (fill none) (layer "B.CrtYd"))
    (fp_rect (start -0.5 0.25) (end 0.5 -0.25)
      (stroke (width 0.15) (type solid)) (fill none) (layer "B.Fab"))
    (pad "1" smd roundrect (at -0.485 0 270) (size 0.59 0.64) (layers "B.Cu" "B.Paste" "B.Mask") (roundrect_rratio 0.25)
      (net 57 "VDD") (pintype "passive"))
    (pad "2" smd roundrect (at 0.485 0 270) (size 0.59 0.64) (layers "B.Cu" "B.Paste" "B.Mask") (roundrect_rratio 0.25)
      (net 67 "Net-(U3-RSET)") (pintype "passive"))
  )

  (footprint "sdi-mipi-bridge-footprints:R_0402_1005Metric" (layer "B.Cu")
    (at 144.775 107.87 180)
    (descr "Resistor SMD 0402")
    (tags "resistor SMD 0402")
    (property "Author" "Antmicro")
    (property "Current" "1A")
    (property "DNP" "DNP")
    (property "License" "Apache-2.0")
    (property "MPN" "ERJ2GE0R00X")
    (property "Manufacturer" "Panasonic")
    (property "Sheetfile" "sdi-mipi-bridge.kicad_sch")
    (property "Sheetname" "")
    (property "Tolerance" "")
    (property "Val" "0R")
    (property "ki_description" "0R resistor in 0402 package with unspecified tolerance")
    (attr exclude_from_pos_files)
    (fp_text reference "R89" (at 0.975 -0.13) (layer "B.SilkS")
        (effects (font (size 0.7 0.7) (thickness 0.15)) (justify left bottom mirror))
    )
    (fp_text value "R_0R_0402" (at 0 -1.4) (layer "B.Fab") hide
        (effects (font (size 0.7 0.7) (thickness 0.15)) (justify left bottom mirror))
    )
    (fp_text user "License: Apache-2.0" (at -0.95 -5.169) (layer "B.Fab") hide
        (effects (font (size 0.7 0.7) (thickness 0.15)) (justify left bottom mirror))
    )
    (fp_text user "${REFERENCE}" (at -0.95 -3.168) (layer "B.Fab") hide
        (effects (font (size 0.7 0.7) (thickness 0.15)) (justify left bottom mirror))
    )
    (fp_text user "Author: Antmicro" (at -0.95 -4.169) (layer "B.Fab") hide
        (effects (font (size 0.7 0.7) (thickness 0.15)) (justify left bottom mirror))
    )
    (fp_rect (start -0.93 0.47) (end 0.93 -0.47)
      (stroke (width 0.05) (type solid)) (fill none) (layer "B.CrtYd"))
    (fp_rect (start -0.5 0.25) (end 0.5 -0.25)
      (stroke (width 0.15) (type solid)) (fill none) (layer "B.Fab"))
    (pad "1" smd roundrect (at -0.485 0 180) (size 0.59 0.64) (layers "B.Cu" "B.Paste" "B.Mask") (roundrect_rratio 0.25)
      (net 1 "GNDREF") (pintype "passive"))
    (pad "2" smd roundrect (at 0.485 0 180) (size 0.59 0.64) (layers "B.Cu" "B.Paste" "B.Mask") (roundrect_rratio 0.25)
      (net 100 "/CRESET_B") (pintype "passive"))
  )

  (footprint "sdi-mipi-bridge-footprints:C_0603_1608Metric" (layer "B.Cu")
    (at 128.7 133.253 90)
    (descr "Capacitor SMD 0603")
    (tags "capacitor 0603")
    (property "Author" "Antmicro")
    (property "License" "Apache-2.0")
    (property "MPN" "GRM188R61A106KE69D")
    (property "Manufacturer" "Murata")
    (property "Sheetfile" "sdi-mipi-bridge.kicad_sch")
    (property "Sheetname" "")
    (property "Val" "10u")
    (property "Voltage" "")
    (property "ki_description" " ")
    (attr smd)
    (fp_text reference "C1" (at 1.853 0.5 90) (layer "B.SilkS")
        (effects (font (size 0.7 0.7) (thickness 0.15)) (justify right bottom mirror))
    )
    (fp_text value "C_10u_0603" (at 0 -1.6 90) (layer "B.Fab") hide
        (effects (font (size 0.7 0.7) (thickness 0.15)) (justify right bottom mirror))
    )
    (fp_text user "${REFERENCE}" (at -1.682 -3.895 90) (layer "B.Fab") hide
        (effects (font (size 0.7 0.7) (thickness 0.15)) (justify right bottom mirror))
    )
    (fp_text user "Author: Antmicro" (at -1.682 -4.894 90) (layer "B.Fab") hide
        (effects (font (size 0.7 0.7) (thickness 0.15)) (justify right bottom mirror))
    )
    (fp_text user "License: Apache-2.0" (at -1.682 -5.895 90) (layer "B.Fab") hide
        (effects (font (size 0.7 0.7) (thickness 0.15)) (justify right bottom mirror))
    )
    (fp_line (start -0.3 -0.3) (end 0.3 -0.3)
      (stroke (width 0.15) (type solid)) (layer "B.SilkS"))
    (fp_line (start -0.3 0.3) (end 0.3 0.3)
      (stroke (width 0.15) (type solid)) (layer "B.SilkS"))
    (fp_rect (start -1.24 0.7) (end 1.24 -0.7)
      (stroke (width 0.05) (type solid)) (fill none) (layer "B.CrtYd"))
    (fp_rect (start -0.8 0.4) (end 0.8 -0.4)
      (stroke (width 0.15) (type solid)) (fill none) (layer "B.Fab"))
    (pad "1" smd roundrect (at -0.7 0 90) (size 0.6 0.8) (layers "B.Cu" "B.Paste" "B.Mask") (roundrect_rratio 0.2)
      (net 1 "GNDREF") (pintype "passive"))
    (pad "2" smd roundrect (at 0.7 0 90) (size 0.6 0.8) (layers "B.Cu" "B.Paste" "B.Mask") (roundrect_rratio 0.2)
      (net 6 "+3V3") (pintype "passive"))
  )

  (footprint "sdi-mipi-bridge-footprints:R_0402_1005Metric" (layer "B.Cu")
    (at 135.6 131.58 -90)
    (descr "Resistor SMD 0402")
    (tags "resistor SMD 0402")
    (property "Author" "Antmicro")
    (property "Current" "1A")
    (property "License" "Apache-2.0")
    (property "MPN" "ERJ2GE0R00X")
    (property "Manufacturer" "Panasonic")
    (property "Sheetfile" "sdi-mipi-bridge.kicad_sch")
    (property "Sheetname" "")
    (property "Tolerance" "")
    (property "Val" "0R")
    (property "ki_description" "0R resistor in 0402 package with unspecified tolerance")
    (attr smd)
    (fp_text reference "R23" (at -1.18 -3.6 90) (layer "B.SilkS")
        (effects (font (size 0.7 0.7) (thickness 0.15)) (justify left bottom mirror))
    )
    (fp_text value "R_0R_0402" (at 0 -1.4 90) (layer "B.Fab") hide
        (effects (font (size 0.7 0.7) (thickness 0.15)) (justify left bottom mirror))
    )
    (fp_text user "Author: Antmicro" (at -0.95 -4.169 90) (layer "B.Fab") hide
        (effects (font (size 0.7 0.7) (thickness 0.15)) (justify left bottom mirror))
    )
    (fp_text user "License: Apache-2.0" (at -0.95 -5.169 90) (layer "B.Fab") hide
        (effects (font (size 0.7 0.7) (thickness 0.15)) (justify left bottom mirror))
    )
    (fp_text user "${REFERENCE}" (at -0.95 -3.168 90) (layer "B.Fab") hide
        (effects (font (size 0.7 0.7) (thickness 0.15)) (justify left bottom mirror))
    )
    (fp_rect (start -0.93 0.47) (end 0.93 -0.47)
      (stroke (width 0.05) (type solid)) (fill none) (layer "B.CrtYd"))
    (fp_rect (start -0.5 0.25) (end 0.5 -0.25)
      (stroke (width 0.15) (type solid)) (fill none) (layer "B.Fab"))
    (pad "1" smd roundrect (at -0.485 0 270) (size 0.59 0.64) (layers "B.Cu" "B.Paste" "B.Mask") (roundrect_rratio 0.25)
      (net 2 "+1V2") (pintype "passive"))
    (pad "2" smd roundrect (at 0.485 0 270) (size 0.59 0.64) (layers "B.Cu" "B.Paste" "B.Mask") (roundrect_rratio 0.25)
      (net 4 "VPP") (pintype "passive"))
  )

  (footprint "sdi-mipi-bridge-footprints:C_0402_1005Metric" (layer "B.Cu")
    (at 145.335 118.275 180)
    (descr "Capacitor SMD 0402")
    (tags "capacitor SMD 0402")
    (property "Author" "Antmicro")
    (property "Dielectric" "")
    (property "License" "Apache-2.0")
    (property "MPN" "0402X104K6R3CT")
    (property "Manufacturer" "Walsin")
    (property "Sheetfile" "sdi-mipi-bridge.kicad_sch")
    (property "Sheetname" "")
    (property "Val" "100n")
    (property "Voltage" "")
    (property "ki_description" " ")
    (attr smd)
    (fp_text reference "C54" (at -9.865 -8.125) (layer "B.SilkS")
        (effects (font (size 0.7 0.7) (thickness 0.15)) (justify left bottom mirror))
    )
    (fp_text value "C_100n_6V3_0402" (at 0 -1.4) (layer "B.Fab") hide
        (effects (font (size 0.7 0.7) (thickness 0.15)) (justify left bottom mirror))
    )
    (fp_text user "${REFERENCE}" (at -0.932 -3.168) (layer "B.Fab") hide
        (effects (font (size 0.7 0.7) (thickness 0.15)) (justify left bottom mirror))
    )
    (fp_text user "License: Apache-2.0" (at -0.932 -5.17) (layer "B.Fab") hide
        (effects (font (size 0.7 0.7) (thickness 0.15)) (justify left bottom mirror))
    )
    (fp_text user "Author: Antmicro" (at -0.932 -4.17) (layer "B.Fab") hide
        (effects (font (size 0.7 0.7) (thickness 0.15)) (justify left bottom mirror))
    )
    (fp_rect (start -0.94 0.47) (end 0.94 -0.47)
      (stroke (width 0.05) (type solid)) (fill none) (layer "B.CrtYd"))
    (fp_rect (start -0.499 0.249) (end 0.499 -0.249)
      (stroke (width 0.15) (type solid)) (fill none) (layer "B.Fab"))
    (pad "1" smd roundrect (at -0.484 0 180) (size 0.59 0.64) (layers "B.Cu" "B.Paste" "B.Mask") (roundrect_rratio 0.25)
      (net 1 "GNDREF") (pintype "passive"))
    (pad "2" smd roundrect (at 0.484 0 180) (size 0.59 0.64) (layers "B.Cu" "B.Paste" "B.Mask") (roundrect_rratio 0.25)
      (net 79 "VCC_IO") (pintype "passive"))
  )

  (footprint "sdi-mipi-bridge-footprints:C_0402_1005Metric" (layer "B.Cu")
    (at 147.96 118.87 90)
    (descr "Capacitor SMD 0402")
    (tags "capacitor SMD 0402")
    (property "Author" "Antmicro")
    (property "Dielectric" "")
    (property "License" "Apache-2.0")
    (property "MPN" "GRM155R61A475MEAAD")
    (property "Manufacturer" "Murata")
    (property "Sheetfile" "sdi-mipi-bridge.kicad_sch")
    (property "Sheetname" "")
    (property "Val" "4u7")
    (property "Voltage" "")
    (property "ki_description" " ")
    (attr smd)
    (fp_text reference "C42" (at -8.93 9.24 90) (layer "B.SilkS")
        (effects (font (size 0.7 0.7) (thickness 0.15)) (justify right bottom mirror))
    )
    (fp_text value "C_4u7_0402" (at 0 -1.4 90) (layer "B.Fab") hide
        (effects (font (size 0.7 0.7) (thickness 0.15)) (justify right bottom mirror))
    )
    (fp_text user "Author: Antmicro" (at -0.932 -4.17 90) (layer "B.Fab") hide
        (effects (font (size 0.7 0.7) (thickness 0.15)) (justify right bottom mirror))
    )
    (fp_text user "License: Apache-2.0" (at -0.932 -5.17 90) (layer "B.Fab") hide
        (effects (font (size 0.7 0.7) (thickness 0.15)) (justify right bottom mirror))
    )
    (fp_text user "${REFERENCE}" (at -0.932 -3.168 90) (layer "B.Fab") hide
        (effects (font (size 0.7 0.7) (thickness 0.15)) (justify right bottom mirror))
    )
    (fp_rect (start -0.94 0.47) (end 0.94 -0.47)
      (stroke (width 0.05) (type solid)) (fill none) (layer "B.CrtYd"))
    (fp_rect (start -0.499 0.249) (end 0.499 -0.249)
      (stroke (width 0.15) (type solid)) (fill none) (layer "B.Fab"))
    (pad "1" smd roundrect (at -0.484 0 90) (size 0.59 0.64) (layers "B.Cu" "B.Paste" "B.Mask") (roundrect_rratio 0.25)
      (net 1 "GNDREF") (pintype "passive"))
    (pad "2" smd roundrect (at 0.484 0 90) (size 0.59 0.64) (layers "B.Cu" "B.Paste" "B.Mask") (roundrect_rratio 0.25)
      (net 2 "+1V2") (pintype "passive"))
  )

  (footprint "sdi-mipi-bridge-footprints:FB_0603_1608Metric" (layer "B.Cu")
    (at 143.875 112.95 180)
    (property "Author" "Antmicro")
    (property "License" "Apache-2.0")
    (property "MPN" "BLM18PG121SN1D")
    (property "Manufacturer" "Murata")
    (property "Sheetfile" "sdi-mipi-bridge.kicad_sch")
    (property "Sheetname" "")
    (property "ki_description" "Ferrite Beads WE-TMSB Suppression 240Ohm 200mA ")
    (property "ki_keywords" " Multilayer Suppression Beads ")
    (attr smd)
    (fp_text reference "FB1" (at -0.725 0.8) (layer "B.SilkS")
        (effects (font (size 0.7 0.7) (thickness 0.15)) (justify left bottom mirror))
    )
    (fp_text value "BLM18PG121SH1D" (at 0 -1.5) (layer "B.Fab") hide
        (effects (font (size 0.7 0.7) (thickness 0.15)) (justify left bottom mirror))
    )
    (fp_text user "License: Apache-2.0" (at -1.653 -5.9) (layer "B.Fab") hide
        (effects (font (size 0.7 0.7) (thickness 0.15)) (justify left bottom mirror))
    )
    (fp_text user "${REFERENCE}" (at -1.653 -4.6) (layer "B.Fab") hide
        (effects (font (size 0.7 0.7) (thickness 0.15)) (justify left bottom mirror))
    )
    (fp_text user "Author: Antmicro" (at -1.653 -3.162) (layer "B.Fab") hide
        (effects (font (size 0.7 0.7) (thickness 0.15)) (justify left bottom mirror))
    )
    (fp_line (start -0.196 -0.406) (end 0.193 -0.406)
      (stroke (width 0.15) (type solid)) (layer "B.SilkS"))
    (fp_line (start -0.196 0.408) (end 0.193 0.408)
      (stroke (width 0.15) (type solid)) (layer "B.SilkS"))
    (fp_rect (start -1.3 0.6) (end 1.3 -0.6)
      (stroke (width 0.05) (type solid)) (fill none) (layer "B.CrtYd"))
    (fp_line (start -0.803 -0.406) (end -0.803 0.408)
      (stroke (width 0.15) (type solid)) (layer "B.Fab"))
    (fp_line (start 0.8 -0.406) (end -0.803 -0.406)
      (stroke (width 0.15) (type solid)) (layer "B.Fab"))
    (fp_line (start 0.8 0.408) (end -0.803 0.408)
      (stroke (width 0.15) (type solid)) (layer "B.Fab"))
    (fp_line (start 0.8 0.408) (end 0.8 -0.406)
      (stroke (width 0.15) (type solid)) (layer "B.Fab"))
    (pad "1" smd roundrect (at -0.891 0 180) (size 0.762 1.09) (layers "B.Cu" "B.Paste" "B.Mask") (roundrect_rratio 0.15)
      (net 6 "+3V3") (pintype "passive"))
    (pad "2" smd roundrect (at 0.888 0 180) (size 0.762 1.09) (layers "B.Cu" "B.Paste" "B.Mask") (roundrect_rratio 0.15)
      (net 79 "VCC_IO") (pintype "passive"))
  )

  (footprint "sdi-mipi-bridge-footprints:C_0402_1005Metric" (layer "B.Cu")
    (at 121 113.4 90)
    (descr "Capacitor SMD 0402")
    (tags "capacitor SMD 0402")
    (property "Author" "Antmicro")
    (property "Dielectric" "X7R")
    (property "License" "Apache-2.0")
    (property "MPN" "GRM155R71H103KA88D")
    (property "Manufacturer" "Murata")
    (property "Sheetfile" "sdi-mipi-bridge.kicad_sch")
    (property "Sheetname" "")
    (property "Val" "10n")
    (property "Voltage" "50V")
    (property "ki_description" " ")
    (attr smd)
    (fp_text reference "C2" (at -0.8 -0.6 90) (layer "B.SilkS")
        (effects (font (size 0.7 0.7) (thickness 0.15)) (justify right bottom mirror))
    )
    (fp_text value "C_10n_0402" (at 0 -1.4 90) (layer "B.Fab") hide
        (effects (font (size 0.7 0.7) (thickness 0.15)) (justify right bottom mirror))
    )
    (fp_text user "Author: Antmicro" (at -0.932 -4.17 90) (layer "B.Fab") hide
        (effects (font (size 0.7 0.7) (thickness 0.15)) (justify right bottom mirror))
    )
    (fp_text user "License: Apache-2.0" (at -0.932 -5.17 90) (layer "B.Fab") hide
        (effects (font (size 0.7 0.7) (thickness 0.15)) (justify right bottom mirror))
    )
    (fp_text user "${REFERENCE}" (at -0.932 -3.168 90) (layer "B.Fab") hide
        (effects (font (size 0.7 0.7) (thickness 0.15)) (justify right bottom mirror))
    )
    (fp_rect (start -0.94 0.47) (end 0.94 -0.47)
      (stroke (width 0.05) (type solid)) (fill none) (layer "B.CrtYd"))
    (fp_rect (start -0.499 0.249) (end 0.499 -0.249)
      (stroke (width 0.15) (type solid)) (fill none) (layer "B.Fab"))
    (pad "1" smd roundrect (at -0.484 0 90) (size 0.59 0.64) (layers "B.Cu" "B.Paste" "B.Mask") (roundrect_rratio 0.25)
      (net 1 "GNDREF") (pintype "passive"))
    (pad "2" smd roundrect (at 0.484 0 90) (size 0.59 0.64) (layers "B.Cu" "B.Paste" "B.Mask") (roundrect_rratio 0.25)
      (net 2 "+1V2") (pintype "passive"))
  )

  (footprint "sdi-mipi-bridge-footprints:R_0402_1005Metric" (layer "B.Cu")
    (at 133.5 107.16)
    (descr "Resistor SMD 0402")
    (tags "resistor SMD 0402")
    (property "Author" "Antmicro")
    (property "License" "Apache-2.0")
    (property "MPN" "CR0402-FX-1000GLF")
    (property "Manufacturer" "Bourns")
    (property "Sheetfile" "sdi-mipi-bridge.kicad_sch")
    (property "Sheetname" "")
    (property "Tolerance" "1%")
    (property "Val" "100R")
    (property "ki_description" "100R resistor in 0402 package with 1% tolerance")
    (attr smd)
    (fp_text reference "R64" (at 1.1 1.44 180) (layer "B.SilkS")
        (effects (font (size 0.7 0.7) (thickness 0.15)) (justify left bottom mirror))
    )
    (fp_text value "R_100R_0402" (at 0 -1.4 180) (layer "B.Fab") hide
        (effects (font (size 0.7 0.7) (thickness 0.15)) (justify left bottom mirror))
    )
    (fp_text user "License: Apache-2.0" (at -0.95 -5.169 180) (layer "B.Fab") hide
        (effects (font (size 0.7 0.7) (thickness 0.15)) (justify left bottom mirror))
    )
    (fp_text user "${REFERENCE}" (at -0.95 -3.168 180) (layer "B.Fab") hide
        (effects (font (size 0.7 0.7) (thickness 0.15)) (justify left bottom mirror))
    )
    (fp_text user "Author: Antmicro" (at -0.95 -4.169 180) (layer "B.Fab") hide
        (effects (font (size 0.7 0.7) (thickness 0.15)) (justify left bottom mirror))
    )
    (fp_rect (start -0.93 0.47) (end 0.93 -0.47)
      (stroke (width 0.05) (type solid)) (fill none) (layer "B.CrtYd"))
    (fp_rect (start -0.5 0.25) (end 0.5 -0.25)
      (stroke (width 0.15) (type solid)) (fill none) (layer "B.Fab"))
    (pad "1" smd roundrect (at -0.485 0) (size 0.59 0.64) (layers "B.Cu" "B.Paste" "B.Mask") (roundrect_rratio 0.25)
      (net 95 "Net-(D5-Pad1)") (pintype "passive"))
    (pad "2" smd roundrect (at 0.485 0) (size 0.59 0.64) (layers "B.Cu" "B.Paste" "B.Mask") (roundrect_rratio 0.25)
      (net 22 "/~{DATA_ERROR}") (pintype "passive"))
  )

  (footprint "sdi-mipi-bridge-footprints:R_0402_1005Metric" (layer "B.Cu")
    (at 127.5 110.9 90)
    (descr "Resistor SMD 0402")
    (tags "resistor SMD 0402")
    (property "Author" "Antmicro")
    (property "DNP" "DNP")
    (property "License" "Apache-2.0")
    (property "MPN" "CR0402-FX-1002GLF")
    (property "Manufacturer" "Bourns")
    (property "Sheetfile" "sdi-mipi-bridge.kicad_sch")
    (property "Sheetname" "")
    (property "Tolerance" "1%")
    (property "Val" "10k")
    (property "ki_description" "10k resistor in 0402 package with 1% tolerance")
    (attr exclude_from_pos_files)
    (fp_text reference "R84" (at -3.1 0.3 90) (layer "B.SilkS")
        (effects (font (size 0.7 0.7) (thickness 0.15)) (justify right bottom mirror))
    )
    (fp_text value "R_10k_0402" (at 0 -1.4 90) (layer "B.Fab") hide
        (effects (font (size 0.7 0.7) (thickness 0.15)) (justify right bottom mirror))
    )
    (fp_text user "Author: Antmicro" (at -0.95 -4.169 90) (layer "B.Fab") hide
        (effects (font (size 0.7 0.7) (thickness 0.15)) (justify right bottom mirror))
    )
    (fp_text user "License: Apache-2.0" (at -0.95 -5.169 90) (layer "B.Fab") hide
        (effects (font (size 0.7 0.7) (thickness 0.15)) (justify right bottom mirror))
    )
    (fp_text user "${REFERENCE}" (at -0.95 -3.168 90) (layer "B.Fab") hide
        (effects (font (size 0.7 0.7) (thickness 0.15)) (justify right bottom mirror))
    )
    (fp_rect (start -0.93 0.47) (end 0.93 -0.47)
      (stroke (width 0.05) (type solid)) (fill none) (layer "B.CrtYd"))
    (fp_rect (start -0.5 0.25) (end 0.5 -0.25)
      (stroke (width 0.15) (type solid)) (fill none) (layer "B.Fab"))
    (pad "1" smd roundrect (at -0.485 0 90) (size 0.59 0.64) (layers "B.Cu" "B.Paste" "B.Mask") (roundrect_rratio 0.25)
      (net 126 "/~{RST_TRST}") (pintype "passive"))
    (pad "2" smd roundrect (at 0.485 0 90) (size 0.59 0.64) (layers "B.Cu" "B.Paste" "B.Mask") (roundrect_rratio 0.25)
      (net 76 "IO_VDD") (pintype "passive"))
  )

  (footprint "sdi-mipi-bridge-footprints:R_0402_1005Metric" (layer "B.Cu")
    (at 152.795 106.41)
    (descr "Resistor SMD 0402")
    (tags "resistor SMD 0402")
    (property "Author" "Antmicro")
    (property "DNP" "DNP")
    (property "License" "Apache-2.0")
    (property "MPN" "CR0402-FX-2201GLF")
    (property "Manufacturer" "Bourns")
    (property "Sheetfile" "sdi-mipi-bridge.kicad_sch")
    (property "Sheetname" "")
    (property "Tolerance" "1%")
    (property "Val" "2k2")
    (property "ki_description" "2k2 resistor in 0402 package with 1% tolerance")
    (attr exclude_from_pos_files)
    (fp_text reference "R85" (at 3.005 -4.81 180) (layer "B.SilkS")
        (effects (font (size 0.7 0.7) (thickness 0.15)) (justify left bottom mirror))
    )
    (fp_text value "R_2k2_0402" (at 0 -1.4 180) (layer "B.Fab") hide
        (effects (font (size 0.7 0.7) (thickness 0.15)) (justify left bottom mirror))
    )
    (fp_text user "Author: Antmicro" (at -0.95 -4.169 180) (layer "B.Fab") hide
        (effects (font (size 0.7 0.7) (thickness 0.15)) (justify left bottom mirror))
    )
    (fp_text user "License: Apache-2.0" (at -0.95 -5.169 180) (layer "B.Fab") hide
        (effects (font (size 0.7 0.7) (thickness 0.15)) (justify left bottom mirror))
    )
    (fp_text user "${REFERENCE}" (at -0.95 -3.168 180) (layer "B.Fab") hide
        (effects (font (size 0.7 0.7) (thickness 0.15)) (justify left bottom mirror))
    )
    (fp_rect (start -0.93 0.47) (end 0.93 -0.47)
      (stroke (width 0.05) (type solid)) (fill none) (layer "B.CrtYd"))
    (fp_rect (start -0.5 0.25) (end 0.5 -0.25)
      (stroke (width 0.15) (type solid)) (fill none) (layer "B.Fab"))
    (pad "1" smd roundrect (at -0.485 0) (size 0.59 0.64) (layers "B.Cu" "B.Paste" "B.Mask") (roundrect_rratio 0.25)
      (net 98 "Net-(R67-Pad2)") (pintype "passive"))
    (pad "2" smd roundrect (at 0.485 0) (size 0.59 0.64) (layers "B.Cu" "B.Paste" "B.Mask") (roundrect_rratio 0.25)
      (net 99 "/SPI_SS(SCL)") (pintype "passive"))
  )

  (footprint "sdi-mipi-bridge-footprints:R_0402_1005Metric" (layer "B.Cu")
    (at 152.795 107.61)
    (descr "Resistor SMD 0402")
    (tags "resistor SMD 0402")
    (property "Author" "Antmicro")
    (property "DNP" "DNP")
    (property "License" "Apache-2.0")
    (property "MPN" "CR0402-FX-2201GLF")
    (property "Manufacturer" "Bourns")
    (property "Sheetfile" "sdi-mipi-bridge.kicad_sch")
    (property "Sheetname" "")
    (property "Tolerance" "1%")
    (property "Val" "2k2")
    (property "ki_description" "2k2 resistor in 0402 package with 1% tolerance")
    (attr exclude_from_pos_files)
    (fp_text reference "R86" (at 3.005 -4.81 180) (layer "B.SilkS")
        (effects (font (size 0.7 0.7) (thickness 0.15)) (justify left bottom mirror))
    )
    (fp_text value "R_2k2_0402" (at 0 -1.4 180) (layer "B.Fab") hide
        (effects (font (size 0.7 0.7) (thickness 0.15)) (justify left bottom mirror))
    )
    (fp_text user "${REFERENCE}" (at -0.95 -3.168 180) (layer "B.Fab") hide
        (effects (font (size 0.7 0.7) (thickness 0.15)) (justify left bottom mirror))
    )
    (fp_text user "Author: Antmicro" (at -0.95 -4.169 180) (layer "B.Fab") hide
        (effects (font (size 0.7 0.7) (thickness 0.15)) (justify left bottom mirror))
    )
    (fp_text user "License: Apache-2.0" (at -0.95 -5.169 180) (layer "B.Fab") hide
        (effects (font (size 0.7 0.7) (thickness 0.15)) (justify left bottom mirror))
    )
    (fp_rect (start -0.93 0.47) (end 0.93 -0.47)
      (stroke (width 0.05) (type solid)) (fill none) (layer "B.CrtYd"))
    (fp_rect (start -0.5 0.25) (end 0.5 -0.25)
      (stroke (width 0.15) (type solid)) (fill none) (layer "B.Fab"))
    (pad "1" smd roundrect (at -0.485 0) (size 0.59 0.64) (layers "B.Cu" "B.Paste" "B.Mask") (roundrect_rratio 0.25)
      (net 98 "Net-(R67-Pad2)") (pintype "passive"))
    (pad "2" smd roundrect (at 0.485 0) (size 0.59 0.64) (layers "B.Cu" "B.Paste" "B.Mask") (roundrect_rratio 0.25)
      (net 102 "/SPI_SCK(SDA)") (pintype "passive"))
  )

  (footprint "sdi-mipi-bridge-footprints:R_0402_1005Metric" (layer "B.Cu")
    (at 152.795 108.81)
    (descr "Resistor SMD 0402")
    (tags "resistor SMD 0402")
    (property "Author" "Antmicro")
    (property "DNP" "DNP")
    (property "License" "Apache-2.0")
    (property "MPN" "CR0402-FX-2201GLF")
    (property "Manufacturer" "Bourns")
    (property "Sheetfile" "sdi-mipi-bridge.kicad_sch")
    (property "Sheetname" "")
    (property "Tolerance" "1%")
    (property "Val" "2k2")
    (property "ki_description" "2k2 resistor in 0402 package with 1% tolerance")
    (attr exclude_from_pos_files)
    (fp_text reference "R87" (at 3.005 -4.81 180) (layer "B.SilkS")
        (effects (font (size 0.7 0.7) (thickness 0.15)) (justify left bottom mirror))
    )
    (fp_text value "R_2k2_0402" (at 0 -1.4 180) (layer "B.Fab") hide
        (effects (font (size 0.7 0.7) (thickness 0.15)) (justify left bottom mirror))
    )
    (fp_text user "Author: Antmicro" (at -0.95 -4.169 180) (layer "B.Fab") hide
        (effects (font (size 0.7 0.7) (thickness 0.15)) (justify left bottom mirror))
    )
    (fp_text user "${REFERENCE}" (at -0.95 -3.168 180) (layer "B.Fab") hide
        (effects (font (size 0.7 0.7) (thickness 0.15)) (justify left bottom mirror))
    )
    (fp_text user "License: Apache-2.0" (at -0.95 -5.169 180) (layer "B.Fab") hide
        (effects (font (size 0.7 0.7) (thickness 0.15)) (justify left bottom mirror))
    )
    (fp_rect (start -0.93 0.47) (end 0.93 -0.47)
      (stroke (width 0.05) (type solid)) (fill none) (layer "B.CrtYd"))
    (fp_rect (start -0.5 0.25) (end 0.5 -0.25)
      (stroke (width 0.15) (type solid)) (fill none) (layer "B.Fab"))
    (pad "1" smd roundrect (at -0.485 0) (size 0.59 0.64) (layers "B.Cu" "B.Paste" "B.Mask") (roundrect_rratio 0.25)
      (net 98 "Net-(R67-Pad2)") (pintype "passive"))
    (pad "2" smd roundrect (at 0.485 0) (size 0.59 0.64) (layers "B.Cu" "B.Paste" "B.Mask") (roundrect_rratio 0.25)
      (net 61 "/SCL_GS") (pintype "passive"))
  )

  (footprint "sdi-mipi-bridge-footprints:R_0402_1005Metric" (layer "B.Cu")
    (at 152.795 110.01)
    (descr "Resistor SMD 0402")
    (tags "resistor SMD 0402")
    (property "Author" "Antmicro")
    (property "DNP" "DNP")
    (property "License" "Apache-2.0")
    (property "MPN" "CR0402-FX-2201GLF")
    (property "Manufacturer" "Bourns")
    (property "Sheetfile" "sdi-mipi-bridge.kicad_sch")
    (property "Sheetname" "")
    (property "Tolerance" "1%")
    (property "Val" "2k2")
    (property "ki_description" "2k2 resistor in 0402 package with 1% tolerance")
    (attr exclude_from_pos_files)
    (fp_text reference "R94" (at 3.005 -4.81 180) (layer "B.SilkS")
        (effects (font (size 0.7 0.7) (thickness 0.15)) (justify left bottom mirror))
    )
    (fp_text value "R_2k2_0402" (at 0 -1.4 180) (layer "B.Fab") hide
        (effects (font (size 0.7 0.7) (thickness 0.15)) (justify left bottom mirror))
    )
    (fp_text user "Author: Antmicro" (at -0.95 -4.169 180) (layer "B.Fab") hide
        (effects (font (size 0.7 0.7) (thickness 0.15)) (justify left bottom mirror))
    )
    (fp_text user "License: Apache-2.0" (at -0.95 -5.169 180) (layer "B.Fab") hide
        (effects (font (size 0.7 0.7) (thickness 0.15)) (justify left bottom mirror))
    )
    (fp_text user "${REFERENCE}" (at -0.95 -3.168 180) (layer "B.Fab") hide
        (effects (font (size 0.7 0.7) (thickness 0.15)) (justify left bottom mirror))
    )
    (fp_rect (start -0.93 0.47) (end 0.93 -0.47)
      (stroke (width 0.05) (type solid)) (fill none) (layer "B.CrtYd"))
    (fp_rect (start -0.5 0.25) (end 0.5 -0.25)
      (stroke (width 0.15) (type solid)) (fill none) (layer "B.Fab"))
    (pad "1" smd roundrect (at -0.485 0) (size 0.59 0.64) (layers "B.Cu" "B.Paste" "B.Mask") (roundrect_rratio 0.25)
      (net 98 "Net-(R67-Pad2)") (pintype "passive"))
    (pad "2" smd roundrect (at 0.485 0) (size 0.59 0.64) (layers "B.Cu" "B.Paste" "B.Mask") (roundrect_rratio 0.25)
      (net 62 "/SDA_GS") (pintype "passive"))
  )

  (footprint "sdi-mipi-bridge-footprints:C_0402_1005Metric" (layer "B.Cu")
    (at 126.1 134.53 180)
    (descr "Capacitor SMD 0402")
    (tags "capacitor SMD 0402")
    (property "Author" "Antmicro")
    (property "Dielectric" "X7R")
    (property "License" "Apache-2.0")
    (property "MPN" "GRM155R71H103KA88D")
    (property "Manufacturer" "Murata")
    (property "Sheetfile" "sdi-mipi-bridge.kicad_sch")
    (property "Sheetname" "")
    (property "Val" "10n")
    (property "Voltage" "50V")
    (property "ki_description" " ")
    (attr smd)
    (fp_text reference "C19" (at 1.301 -0.35) (layer "B.SilkS")
        (effects (font (size 0.7 0.7) (thickness 0.15)) (justify left bottom mirror))
    )
    (fp_text value "C_10n_0402" (at 0 -1.4) (layer "B.Fab") hide
        (effects (font (size 0.7 0.7) (thickness 0.15)) (justify left bottom mirror))
    )
    (fp_text user "${REFERENCE}" (at -0.932 -3.168) (layer "B.Fab") hide
        (effects (font (size 0.7 0.7) (thickness 0.15)) (justify left bottom mirror))
    )
    (fp_text user "License: Apache-2.0" (at -0.932 -5.17) (layer "B.Fab") hide
        (effects (font (size 0.7 0.7) (thickness 0.15)) (justify left bottom mirror))
    )
    (fp_text user "Author: Antmicro" (at -0.932 -4.17) (layer "B.Fab") hide
        (effects (font (size 0.7 0.7) (thickness 0.15)) (justify left bottom mirror))
    )
    (fp_rect (start -0.94 0.47) (end 0.94 -0.47)
      (stroke (width 0.05) (type solid)) (fill none) (layer "B.CrtYd"))
    (fp_rect (start -0.499 0.249) (end 0.499 -0.249)
      (stroke (width 0.15) (type solid)) (fill none) (layer "B.Fab"))
    (pad "1" smd roundrect (at -0.484 0 180) (size 0.59 0.64) (layers "B.Cu" "B.Paste" "B.Mask") (roundrect_rratio 0.25)
      (net 1 "GNDREF") (pintype "passive"))
    (pad "2" smd roundrect (at 0.484 0 180) (size 0.59 0.64) (layers "B.Cu" "B.Paste" "B.Mask") (roundrect_rratio 0.25)
      (net 6 "+3V3") (pintype "passive"))
  )

  (footprint "sdi-mipi-bridge-footprints:R_0402_1005Metric" (layer "B.Cu")
    (at 126.1 135.55 180)
    (descr "Resistor SMD 0402")
    (tags "resistor SMD 0402")
    (property "Author" "Antmicro")
    (property "Current" "1A")
    (property "License" "Apache-2.0")
    (property "MPN" "ERJ2GE0R00X")
    (property "Manufacturer" "Panasonic")
    (property "Sheetfile" "sdi-mipi-bridge.kicad_sch")
    (property "Sheetname" "")
    (property "Tolerance" "")
    (property "Val" "0R")
    (property "ki_description" "0R resistor in 0402 package with unspecified tolerance")
    (attr smd)
    (fp_text reference "R22" (at 1.3 -0.35) (layer "B.SilkS")
        (effects (font (size 0.7 0.7) (thickness 0.15)) (justify left bottom mirror))
    )
    (fp_text value "R_0R_0402" (at 0 -1.4) (layer "B.Fab") hide
        (effects (font (size 0.7 0.7) (thickness 0.15)) (justify left bottom mirror))
    )
    (fp_text user "Author: Antmicro" (at -0.95 -4.169) (layer "B.Fab") hide
        (effects (font (size 0.7 0.7) (thickness 0.15)) (justify left bottom mirror))
    )
    (fp_text user "${REFERENCE}" (at -0.95 -3.168) (layer "B.Fab") hide
        (effects (font (size 0.7 0.7) (thickness 0.15)) (justify left bottom mirror))
    )
    (fp_text user "License: Apache-2.0" (at -0.95 -5.169) (layer "B.Fab") hide
        (effects (font (size 0.7 0.7) (thickness 0.15)) (justify left bottom mirror))
    )
    (fp_rect (start -0.93 0.47) (end 0.93 -0.47)
      (stroke (width 0.05) (type solid)) (fill none) (layer "B.CrtYd"))
    (fp_rect (start -0.5 0.25) (end 0.5 -0.25)
      (stroke (width 0.15) (type solid)) (fill none) (layer "B.Fab"))
    (pad "1" smd roundrect (at -0.485 0 180) (size 0.59 0.64) (layers "B.Cu" "B.Paste" "B.Mask") (roundrect_rratio 0.25)
      (net 1 "GNDREF") (pintype "passive"))
    (pad "2" smd roundrect (at 0.485 0 180) (size 0.59 0.64) (layers "B.Cu" "B.Paste" "B.Mask") (roundrect_rratio 0.25)
      (net 3 "GNDA") (pintype "passive"))
  )

  (footprint "sdi-mipi-bridge-footprints:R_0402_1005Metric" (layer "B.Cu")
    (at 133.645001 122.932)
    (descr "Resistor SMD 0402")
    (tags "resistor SMD 0402")
    (property "Author" "Antmicro")
    (property "Current" "1A")
    (property "License" "Apache-2.0")
    (property "MPN" "ERJ2GE0R00X")
    (property "Manufacturer" "Panasonic")
    (property "Sheetfile" "sdi-mipi-bridge.kicad_sch")
    (property "Sheetname" "")
    (property "Tolerance" "")
    (property "Val" "0R")
    (property "ki_description" "0R resistor in 0402 package with unspecified tolerance")
    (attr smd)
    (fp_text reference "R74" (at 1.154999 3.468 180) (layer "B.SilkS")
        (effects (font (size 0.7 0.7) (thickness 0.15)) (justify left bottom mirror))
    )
    (fp_text value "R_0R_0402" (at 0 -1.4) (layer "B.Fab") hide
        (effects (font (size 0.7 0.7) (thickness 0.15)) (justify right bottom mirror))
    )
    (fp_text user "License: Apache-2.0" (at -0.95 -5.169) (layer "B.Fab") hide
        (effects (font (size 0.7 0.7) (thickness 0.15)) (justify right bottom mirror))
    )
    (fp_text user "Author: Antmicro" (at -0.95 -4.169) (layer "B.Fab") hide
        (effects (font (size 0.7 0.7) (thickness 0.15)) (justify right bottom mirror))
    )
    (fp_text user "${REFERENCE}" (at -0.95 -3.168) (layer "B.Fab") hide
        (effects (font (size 0.7 0.7) (thickness 0.15)) (justify right bottom mirror))
    )
    (fp_rect (start -0.93 0.47) (end 0.93 -0.47)
      (stroke (width 0.05) (type solid)) (fill none) (layer "B.CrtYd"))
    (fp_rect (start -0.5 0.25) (end 0.5 -0.25)
      (stroke (width 0.15) (type solid)) (fill none) (layer "B.Fab"))
    (pad "1" smd roundrect (at -0.485 0) (size 0.59 0.64) (layers "B.Cu" "B.Paste" "B.Mask") (roundrect_rratio 0.25)
      (net 84 "Net-(U5-A2)") (pintype "passive"))
    (pad "2" smd roundrect (at 0.485 0) (size 0.59 0.64) (layers "B.Cu" "B.Paste" "B.Mask") (roundrect_rratio 0.25)
      (net 1 "GNDREF") (pintype "passive"))
  )

  (footprint "sdi-mipi-bridge-footprints:R_0402_1005Metric" (layer "B.Cu")
    (at 133.645001 123.932 180)
    (descr "Resistor SMD 0402")
    (tags "resistor SMD 0402")
    (property "Author" "Antmicro")
    (property "Current" "1A")
    (property "License" "Apache-2.0")
    (property "MPN" "ERJ2GE0R00X")
    (property "Manufacturer" "Panasonic")
    (property "Sheetfile" "sdi-mipi-bridge.kicad_sch")
    (property "Sheetname" "")
    (property "Tolerance" "")
    (property "Val" "0R")
    (property "ki_description" "0R resistor in 0402 package with unspecified tolerance")
    (attr smd)
    (fp_text reference "R73" (at -1.154999 -3.468) (layer "B.SilkS")
        (effects (font (size 0.7 0.7) (thickness 0.15)) (justify left bottom mirror))
    )
    (fp_text value "R_0R_0402" (at 0 -1.4) (layer "B.Fab") hide
        (effects (font (size 0.7 0.7) (thickness 0.15)) (justify left bottom mirror))
    )
    (fp_text user "License: Apache-2.0" (at -0.95 -5.169) (layer "B.Fab") hide
        (effects (font (size 0.7 0.7) (thickness 0.15)) (justify left bottom mirror))
    )
    (fp_text user "Author: Antmicro" (at -0.95 -4.169) (layer "B.Fab") hide
        (effects (font (size 0.7 0.7) (thickness 0.15)) (justify left bottom mirror))
    )
    (fp_text user "${REFERENCE}" (at -0.95 -3.168) (layer "B.Fab") hide
        (effects (font (size 0.7 0.7) (thickness 0.15)) (justify left bottom mirror))
    )
    (fp_rect (start -0.93 0.47) (end 0.93 -0.47)
      (stroke (width 0.05) (type solid)) (fill none) (layer "B.CrtYd"))
    (fp_rect (start -0.5 0.25) (end 0.5 -0.25)
      (stroke (width 0.15) (type solid)) (fill none) (layer "B.Fab"))
    (pad "1" smd roundrect (at -0.485 0 180) (size 0.59 0.64) (layers "B.Cu" "B.Paste" "B.Mask") (roundrect_rratio 0.25)
      (net 75 "Net-(U5-A1)") (pintype "passive"))
    (pad "2" smd roundrect (at 0.485 0 180) (size 0.59 0.64) (layers "B.Cu" "B.Paste" "B.Mask") (roundrect_rratio 0.25)
      (net 1 "GNDREF") (pintype "passive"))
  )

  (footprint "sdi-mipi-bridge-footprints:R_0402_1005Metric" (layer "B.Cu")
    (at 133.645001 124.932 180)
    (descr "Resistor SMD 0402")
    (tags "resistor SMD 0402")
    (property "Author" "Antmicro")
    (property "Current" "1A")
    (property "License" "Apache-2.0")
    (property "MPN" "ERJ2GE0R00X")
    (property "Manufacturer" "Panasonic")
    (property "Sheetfile" "sdi-mipi-bridge.kicad_sch")
    (property "Sheetname" "")
    (property "Tolerance" "")
    (property "Val" "0R")
    (property "ki_description" "0R resistor in 0402 package with unspecified tolerance")
    (attr smd)
    (fp_text reference "R72" (at -1.154999 -3.468) (layer "B.SilkS")
        (effects (font (size 0.7 0.7) (thickness 0.15)) (justify left bottom mirror))
    )
    (fp_text value "R_0R_0402" (at 0 -1.4) (layer "B.Fab") hide
        (effects (font (size 0.7 0.7) (thickness 0.15)) (justify left bottom mirror))
    )
    (fp_text user "${REFERENCE}" (at -0.95 -3.168) (layer "B.Fab") hide
        (effects (font (size 0.7 0.7) (thickness 0.15)) (justify left bottom mirror))
    )
    (fp_text user "License: Apache-2.0" (at -0.95 -5.169) (layer "B.Fab") hide
        (effects (font (size 0.7 0.7) (thickness 0.15)) (justify left bottom mirror))
    )
    (fp_text user "Author: Antmicro" (at -0.95 -4.169) (layer "B.Fab") hide
        (effects (font (size 0.7 0.7) (thickness 0.15)) (justify left bottom mirror))
    )
    (fp_rect (start -0.93 0.47) (end 0.93 -0.47)
      (stroke (width 0.05) (type solid)) (fill none) (layer "B.CrtYd"))
    (fp_rect (start -0.5 0.25) (end 0.5 -0.25)
      (stroke (width 0.15) (type solid)) (fill none) (layer "B.Fab"))
    (pad "1" smd roundrect (at -0.485 0 180) (size 0.59 0.64) (layers "B.Cu" "B.Paste" "B.Mask") (roundrect_rratio 0.25)
      (net 74 "Net-(U5-A0)") (pintype "passive"))
    (pad "2" smd roundrect (at 0.485 0 180) (size 0.59 0.64) (layers "B.Cu" "B.Paste" "B.Mask") (roundrect_rratio 0.25)
      (net 1 "GNDREF") (pintype "passive"))
  )

  (footprint "sdi-mipi-bridge-footprints:R_0402_1005Metric" (layer "B.Cu")
    (at 126.1 130.45 180)
    (descr "Resistor SMD 0402")
    (tags "resistor SMD 0402")
    (property "Author" "Antmicro")
    (property "Current" "1A")
    (property "License" "Apache-2.0")
    (property "MPN" "ERJ2GE0R00X")
    (property "Manufacturer" "Panasonic")
    (property "Sheetfile" "sdi-mipi-bridge.kicad_sch")
    (property "Sheetname" "")
    (property "Tolerance" "")
    (property "Val" "0R")
    (property "ki_description" "0R resistor in 0402 package with unspecified tolerance")
    (attr smd)
    (fp_text reference "R21" (at 1.3 -0.35) (layer "B.SilkS")
        (effects (font (size 0.7 0.7) (thickness 0.15)) (justify left bottom mirror))
    )
    (fp_text value "R_0R_0402" (at 0 -1.4) (layer "B.Fab") hide
        (effects (font (size 0.7 0.7) (thickness 0.15)) (justify left bottom mirror))
    )
    (fp_text user "Author: Antmicro" (at -0.95 -4.169) (layer "B.Fab") hide
        (effects (font (size 0.7 0.7) (thickness 0.15)) (justify left bottom mirror))
    )
    (fp_text user "${REFERENCE}" (at -0.95 -3.168) (layer "B.Fab") hide
        (effects (font (size 0.7 0.7) (thickness 0.15)) (justify left bottom mirror))
    )
    (fp_text user "License: Apache-2.0" (at -0.95 -5.169) (layer "B.Fab") hide
        (effects (font (size 0.7 0.7) (thickness 0.15)) (justify left bottom mirror))
    )
    (fp_rect (start -0.93 0.47) (end 0.93 -0.47)
      (stroke (width 0.05) (type solid)) (fill none) (layer "B.CrtYd"))
    (fp_rect (start -0.5 0.25) (end 0.5 -0.25)
      (stroke (width 0.15) (type solid)) (fill none) (layer "B.Fab"))
    (pad "1" smd roundrect (at -0.485 0 180) (size 0.59 0.64) (layers "B.Cu" "B.Paste" "B.Mask") (roundrect_rratio 0.25)
      (net 6 "+3V3") (pintype "passive"))
    (pad "2" smd roundrect (at 0.485 0 180) (size 0.59 0.64) (layers "B.Cu" "B.Paste" "B.Mask") (roundrect_rratio 0.25)
      (net 5 "+3.3VA") (pintype "passive"))
  )

  (footprint "sdi-mipi-bridge-footprints:R_0402_1005Metric" (layer "B.Cu")
    (at 130.4 127.9)
    (descr "Resistor SMD 0402")
    (tags "resistor SMD 0402")
    (property "Author" "Antmicro")
    (property "Current" "1A")
    (property "License" "Apache-2.0")
    (property "MPN" "ERJ2GE0R00X")
    (property "Manufacturer" "Panasonic")
    (property "Sheetfile" "sdi-mipi-bridge.kicad_sch")
    (property "Sheetname" "")
    (property "Tolerance" "")
    (property "Val" "0R")
    (property "ki_description" "0R resistor in 0402 package with unspecified tolerance")
    (attr smd)
    (fp_text reference "R43" (at -1 0.3 180) (layer "B.SilkS")
        (effects (font (size 0.7 0.7) (thickness 0.15)) (justify left bottom mirror))
    )
    (fp_text value "R_0R_0402" (at 0 -1.4 180) (layer "B.Fab") hide
        (effects (font (size 0.7 0.7) (thickness 0.15)) (justify left bottom mirror))
    )
    (fp_text user "Author: Antmicro" (at -0.95 -4.169 180) (layer "B.Fab") hide
        (effects (font (size 0.7 0.7) (thickness 0.15)) (justify left bottom mirror))
    )
    (fp_text user "${REFERENCE}" (at -0.95 -3.168 180) (layer "B.Fab") hide
        (effects (font (size 0.7 0.7) (thickness 0.15)) (justify left bottom mirror))
    )
    (fp_text user "License: Apache-2.0" (at -0.95 -5.169 180) (layer "B.Fab") hide
        (effects (font (size 0.7 0.7) (thickness 0.15)) (justify left bottom mirror))
    )
    (fp_rect (start -0.93 0.47) (end 0.93 -0.47)
      (stroke (width 0.05) (type solid)) (fill none) (layer "B.CrtYd"))
    (fp_rect (start -0.5 0.25) (end 0.5 -0.25)
      (stroke (width 0.15) (type solid)) (fill none) (layer "B.Fab"))
    (pad "1" smd roundrect (at -0.485 0) (size 0.59 0.64) (layers "B.Cu" "B.Paste" "B.Mask") (roundrect_rratio 0.25)
      (net 6 "+3V3") (pintype "passive"))
    (pad "2" smd roundrect (at 0.485 0) (size 0.59 0.64) (layers "B.Cu" "B.Paste" "B.Mask") (roundrect_rratio 0.25)
      (net 72 "Net-(U5-~{RESET})") (pintype "passive"))
  )

  (footprint "sdi-mipi-bridge-footprints:R_0402_1005Metric" (layer "B.Cu")
    (at 141.85 109.525 -90)
    (descr "Resistor SMD 0402")
    (tags "resistor SMD 0402")
    (property "Author" "Antmicro")
    (property "License" "Apache-2.0")
    (property "MPN" "CR0402-FX-4701GLF")
    (property "Manufacturer" "Bourns")
    (property "Sheetfile" "sdi-mipi-bridge.kicad_sch")
    (property "Sheetname" "")
    (property "Tolerance" "1%")
    (property "Val" "4k7")
    (property "ki_description" "4k7 resistor in 0402 package with 1% tolerance")
    (attr smd)
    (fp_text reference "R95" (at -5.125 2.7675 90) (layer "B.SilkS")
        (effects (font (size 0.7 0.7) (thickness 0.15)) (justify left bottom mirror))
    )
    (fp_text value "R_4k7_0402" (at 0 -1.4 90) (layer "B.Fab") hide
        (effects (font (size 0.7 0.7) (thickness 0.15)) (justify left bottom mirror))
    )
    (fp_text user "${REFERENCE}" (at -0.95 -3.168 90) (layer "B.Fab") hide
        (effects (font (size 0.7 0.7) (thickness 0.15)) (justify left bottom mirror))
    )
    (fp_text user "Author: Antmicro" (at -0.95 -4.169 90) (layer "B.Fab") hide
        (effects (font (size 0.7 0.7) (thickness 0.15)) (justify left bottom mirror))
    )
    (fp_text user "License: Apache-2.0" (at -0.95 -5.169 90) (layer "B.Fab") hide
        (effects (font (size 0.7 0.7) (thickness 0.15)) (justify left bottom mirror))
    )
    (fp_rect (start -0.93 0.47) (end 0.93 -0.47)
      (stroke (width 0.05) (type solid)) (fill none) (layer "B.CrtYd"))
    (fp_rect (start -0.5 0.25) (end 0.5 -0.25)
      (stroke (width 0.15) (type solid)) (fill none) (layer "B.Fab"))
    (pad "1" smd roundrect (at -0.485 0 270) (size 0.59 0.64) (layers "B.Cu" "B.Paste" "B.Mask") (roundrect_rratio 0.25)
      (net 99 "/SPI_SS(SCL)") (pintype "passive"))
    (pad "2" smd roundrect (at 0.485 0 270) (size 0.59 0.64) (layers "B.Cu" "B.Paste" "B.Mask") (roundrect_rratio 0.25)
      (net 79 "VCC_IO") (pintype "passive"))
  )

  (footprint "sdi-mipi-bridge-footprints:R_0402_1005Metric" (layer "B.Cu")
    (at 130.4 129.025)
    (descr "Resistor SMD 0402")
    (tags "resistor SMD 0402")
    (property "Author" "Antmicro")
    (property "Current" "1A")
    (property "License" "Apache-2.0")
    (property "MPN" "ERJ2GE0R00X")
    (property "Manufacturer" "Panasonic")
    (property "Sheetfile" "sdi-mipi-bridge.kicad_sch")
    (property "Sheetname" "")
    (property "Tolerance" "")
    (property "Val" "0R")
    (property "ki_description" "0R resistor in 0402 package with unspecified tolerance")
    (attr smd)
    (fp_text reference "R25" (at -1 0.3 180) (layer "B.SilkS")
        (effects (font (size 0.7 0.7) (thickness 0.15)) (justify left bottom mirror))
    )
    (fp_text value "R_0R_0402" (at 0 -1.4 180) (layer "B.Fab") hide
        (effects (font (size 0.7 0.7) (thickness 0.15)) (justify left bottom mirror))
    )
    (fp_text user "Author: Antmicro" (at -0.95 -4.169 180) (layer "B.Fab") hide
        (effects (font (size 0.7 0.7) (thickness 0.15)) (justify left bottom mirror))
    )
    (fp_text user "${REFERENCE}" (at -0.95 -3.168 180) (layer "B.Fab") hide
        (effects (font (size 0.7 0.7) (thickness 0.15)) (justify left bottom mirror))
    )
    (fp_text user "License: Apache-2.0" (at -0.95 -5.169 180) (layer "B.Fab") hide
        (effects (font (size 0.7 0.7) (thickness 0.15)) (justify left bottom mirror))
    )
    (fp_rect (start -0.93 0.47) (end 0.93 -0.47)
      (stroke (width 0.05) (type solid)) (fill none) (layer "B.CrtYd"))
    (fp_rect (start -0.5 0.25) (end 0.5 -0.25)
      (stroke (width 0.15) (type solid)) (fill none) (layer "B.Fab"))
    (pad "1" smd roundrect (at -0.485 0) (size 0.59 0.64) (layers "B.Cu" "B.Paste" "B.Mask") (roundrect_rratio 0.25)
      (net 6 "+3V3") (pintype "passive"))
    (pad "2" smd roundrect (at 0.485 0) (size 0.59 0.64) (layers "B.Cu" "B.Paste" "B.Mask") (roundrect_rratio 0.25)
      (net 76 "IO_VDD") (pintype "passive"))
  )

  (footprint "sdi-mipi-bridge-footprints:R_0402_1005Metric" (layer "B.Cu")
    (at 111.75 134.25 90)
    (descr "Resistor SMD 0402")
    (tags "resistor SMD 0402")
    (property "Author" "Antmicro")
    (property "Current" "1A")
    (property "License" "Apache-2.0")
    (property "MPN" "ERJ2GE0R00X")
    (property "Manufacturer" "Panasonic")
    (property "Sheetfile" "sdi-mipi-bridge.kicad_sch")
    (property "Sheetname" "")
    (property "Tolerance" "")
    (property "Val" "0R")
    (property "ki_description" "0R resistor in 0402 package with unspecified tolerance")
    (attr smd)
    (fp_text reference "R24" (at 3.65 0.45 270) (layer "B.SilkS")
        (effects (font (size 0.7 0.7) (thickness 0.15)) (justify left bottom mirror))
    )
    (fp_text value "R_0R_0402" (at 0 -1.4 270) (layer "B.Fab") hide
        (effects (font (size 0.7 0.7) (thickness 0.15)) (justify left bottom mirror))
    )
    (fp_text user "Author: Antmicro" (at -0.95 -4.169 270) (layer "B.Fab") hide
        (effects (font (size 0.7 0.7) (thickness 0.15)) (justify left bottom mirror))
    )
    (fp_text user "License: Apache-2.0" (at -0.95 -5.169 270) (layer "B.Fab") hide
        (effects (font (size 0.7 0.7) (thickness 0.15)) (justify left bottom mirror))
    )
    (fp_text user "${REFERENCE}" (at -0.95 -3.168 270) (layer "B.Fab") hide
        (effects (font (size 0.7 0.7) (thickness 0.15)) (justify left bottom mirror))
    )
    (fp_rect (start -0.93 0.47) (end 0.93 -0.47)
      (stroke (width 0.05) (type solid)) (fill none) (layer "B.CrtYd"))
    (fp_rect (start -0.5 0.25) (end 0.5 -0.25)
      (stroke (width 0.15) (type solid)) (fill none) (layer "B.Fab"))
    (pad "1" smd roundrect (at -0.485 0 90) (size 0.59 0.64) (layers "B.Cu" "B.Paste" "B.Mask") (roundrect_rratio 0.25)
      (net 6 "+3V3") (pintype "passive"))
    (pad "2" smd roundrect (at 0.485 0 90) (size 0.59 0.64) (layers "B.Cu" "B.Paste" "B.Mask") (roundrect_rratio 0.25)
      (net 57 "VDD") (pintype "passive"))
  )

  (footprint "sdi-mipi-bridge-footprints:C_0402_1005Metric" (layer "B.Cu")
    (at 126.1 131.53 180)
    (descr "Capacitor SMD 0402")
    (tags "capacitor SMD 0402")
    (property "Author" "Antmicro")
    (property "Dielectric" "X7R")
    (property "License" "Apache-2.0")
    (property "MPN" "GRM155R71H103KA88D")
    (property "Manufacturer" "Murata")
    (property "Sheetfile" "sdi-mipi-bridge.kicad_sch")
    (property "Sheetname" "")
    (property "Val" "10n")
    (property "Voltage" "50V")
    (property "ki_description" " ")
    (attr smd)
    (fp_text reference "C32" (at 1.301 -0.35) (layer "B.SilkS")
        (effects (font (size 0.7 0.7) (thickness 0.15)) (justify left bottom mirror))
    )
    (fp_text value "C_10n_0402" (at -100.01 -1.42) (layer "B.Fab") hide
        (effects (font (size 0.7 0.7) (thickness 0.15)) (justify left bottom mirror))
    )
    (fp_text user "${REFERENCE}" (at -0.932 -3.168) (layer "B.Fab") hide
        (effects (font (size 0.7 0.7) (thickness 0.15)) (justify left bottom mirror))
    )
    (fp_text user "License: Apache-2.0" (at -0.932 -5.17) (layer "B.Fab") hide
        (effects (font (size 0.7 0.7) (thickness 0.15)) (justify left bottom mirror))
    )
    (fp_text user "Author: Antmicro" (at -0.932 -4.17) (layer "B.Fab") hide
        (effects (font (size 0.7 0.7) (thickness 0.15)) (justify left bottom mirror))
    )
    (fp_rect (start -0.94 0.47) (end 0.94 -0.47)
      (stroke (width 0.05) (type solid)) (fill none) (layer "B.CrtYd"))
    (fp_rect (start -0.499 0.249) (end 0.499 -0.249)
      (stroke (width 0.15) (type solid)) (fill none) (layer "B.Fab"))
    (pad "1" smd roundrect (at -0.484 0 180) (size 0.59 0.64) (layers "B.Cu" "B.Paste" "B.Mask") (roundrect_rratio 0.25)
      (net 3 "GNDA") (pintype "passive"))
    (pad "2" smd roundrect (at 0.484 0 180) (size 0.59 0.64) (layers "B.Cu" "B.Paste" "B.Mask") (roundrect_rratio 0.25)
      (net 5 "+3.3VA") (pintype "passive"))
  )

  (footprint "sdi-mipi-bridge-footprints:R_0402_1005Metric" (layer "B.Cu")
    (at 129.5 110.9 90)
    (descr "Resistor SMD 0402")
    (tags "resistor SMD 0402")
    (property "Author" "Antmicro")
    (property "Current" "1A")
    (property "License" "Apache-2.0")
    (property "MPN" "ERJ2GE0R00X")
    (property "Manufacturer" "Panasonic")
    (property "Sheetfile" "sdi-mipi-bridge.kicad_sch")
    (property "Sheetname" "")
    (property "Tolerance" "")
    (property "Val" "0R")
    (property "ki_description" "0R resistor in 0402 package with unspecified tolerance")
    (attr smd)
    (fp_text reference "R105" (at -0.9 0.3 90) (layer "B.SilkS")
        (effects (font (size 0.7 0.7) (thickness 0.15)) (justify left bottom mirror))
    )
    (fp_text value "R_0R_0402" (at 0 -1.4 90) (layer "B.Fab") hide
        (effects (font (size 0.7 0.7) (thickness 0.15)) (justify right bottom mirror))
    )
    (fp_text user "${REFERENCE}" (at -0.95 -3.168 90) (layer "B.Fab") hide
        (effects (font (size 0.7 0.7) (thickness 0.15)) (justify right bottom mirror))
    )
    (fp_text user "License: Apache-2.0" (at -0.95 -5.169 90) (layer "B.Fab") hide
        (effects (font (size 0.7 0.7) (thickness 0.15)) (justify right bottom mirror))
    )
    (fp_text user "Author: Antmicro" (at -0.95 -4.169 90) (layer "B.Fab") hide
        (effects (font (size 0.7 0.7) (thickness 0.15)) (justify right bottom mirror))
    )
    (fp_rect (start -0.93 0.47) (end 0.93 -0.47)
      (stroke (width 0.05) (type solid)) (fill none) (layer "B.CrtYd"))
    (fp_rect (start -0.5 0.25) (end 0.5 -0.25)
      (stroke (width 0.15) (type solid)) (fill none) (layer "B.Fab"))
    (pad "1" smd roundrect (at -0.485 0 90) (size 0.59 0.64) (layers "B.Cu" "B.Paste" "B.Mask") (roundrect_rratio 0.25)
      (net 127 "/~{RST_TRST_SOFT}") (pintype "passive"))
    (pad "2" smd roundrect (at 0.485 0 90) (size 0.59 0.64) (layers "B.Cu" "B.Paste" "B.Mask") (roundrect_rratio 0.25)
      (net 126 "/~{RST_TRST}") (pintype "passive"))
  )

  (footprint "sdi-mipi-bridge-footprints:R_0402_1005Metric" (layer "B.Cu")
    (at 128.5 110.9 -90)
    (descr "Resistor SMD 0402")
    (tags "resistor SMD 0402")
    (property "Author" "Antmicro")
    (property "License" "Apache-2.0")
    (property "MPN" "CR0402-FX-1002GLF")
    (property "Manufacturer" "Bourns")
    (property "Sheetfile" "sdi-mipi-bridge.kicad_sch")
    (property "Sheetname" "")
    (property "Tolerance" "1%")
    (property "Val" "10k")
    (property "ki_description" "10k resistor in 0402 package with 1% tolerance")
    (attr smd)
    (fp_text reference "R98" (at 0.9 -0.3 90) (layer "B.SilkS")
        (effects (font (size 0.7 0.7) (thickness 0.15)) (justify left bottom mirror))
    )
    (fp_text value "R_10k_0402" (at 0 -1.4 90) (layer "B.Fab") hide
        (effects (font (size 0.7 0.7) (thickness 0.15)) (justify left bottom mirror))
    )
    (fp_text user "License: Apache-2.0" (at -0.95 -5.169 90) (layer "B.Fab") hide
        (effects (font (size 0.7 0.7) (thickness 0.15)) (justify left bottom mirror))
    )
    (fp_text user "${REFERENCE}" (at -0.95 -3.168 90) (layer "B.Fab") hide
        (effects (font (size 0.7 0.7) (thickness 0.15)) (justify left bottom mirror))
    )
    (fp_text user "Author: Antmicro" (at -0.95 -4.169 90) (layer "B.Fab") hide
        (effects (font (size 0.7 0.7) (thickness 0.15)) (justify left bottom mirror))
    )
    (fp_rect (start -0.93 0.47) (end 0.93 -0.47)
      (stroke (width 0.05) (type solid)) (fill none) (layer "B.CrtYd"))
    (fp_rect (start -0.5 0.25) (end 0.5 -0.25)
      (stroke (width 0.15) (type solid)) (fill none) (layer "B.Fab"))
    (pad "1" smd roundrect (at -0.485 0 270) (size 0.59 0.64) (layers "B.Cu" "B.Paste" "B.Mask") (roundrect_rratio 0.25)
      (net 3 "GNDA") (pintype "passive"))
    (pad "2" smd roundrect (at 0.485 0 270) (size 0.59 0.64) (layers "B.Cu" "B.Paste" "B.Mask") (roundrect_rratio 0.25)
      (net 126 "/~{RST_TRST}") (pintype "passive"))
  )
  (gr_line (start 168 95.5) (end 168 137.5)
    (stroke (width 0.12) (type solid)) (layer "Edge.Cuts"))
  (gr_line (start 98 137.5) (end 98 95.5)
    (stroke (width 0.12) (type solid)) (layer "Edge.Cuts"))
  (gr_line (start 98 95.5) (end 168 95.5)
    (stroke (width 0.12) (type solid)) (layer "Edge.Cuts"))
  (gr_line (start 168 137.5) (end 98 137.5)
    (stroke (width 0.12) (type solid)) (layer "Edge.Cuts"))
  (gr_text "SDI-MIPI Bridge" (at 146.575 102.175) (layer "F.Cu")
    (effects (font (size 1 1) (thickness 0.2)))
  )
  (gr_text "Rev. 1.3.4 10/2023" (at 140.4 103.6068) (layer "F.Cu")
    (effects (font (size 0.7 0.7) (thickness 0.15)) (justify left))
  )

  (segment (start 119.5 116.9) (end 119 117.4) (width 0.15) (layer "F.Cu") (net 1))
  (segment (start 120.5 116.9) (end 120 117.4) (width 0.15) (layer "F.Cu") (net 1))
  (segment (start 122.5 111.9) (end 122 111.4) (width 0.15) (layer "F.Cu") (net 1))
  (segment (start 120.5 115.9) (end 120 116.4) (width 0.15) (layer "F.Cu") (net 1))
  (segment (start 144.4325 115.565) (end 143.945 115.0775) (width 0.1) (layer "F.Cu") (net 1))
  (segment (start 145.895 115.565) (end 146.22 115.24) (width 0.1) (layer "F.Cu") (net 1))
  (segment (start 147.0325 115.24) (end 147.195 115.0775) (width 0.1) (layer "F.Cu") (net 1))
  (segment (start 146.22 115.24) (end 147.0325 115.24) (width 0.1) (layer "F.Cu") (net 1))
  (segment (start 144.595 115.565) (end 144.4325 115.565) (width 0.1) (layer "F.Cu") (net 1))
  (segment (start 127 103.65) (end 127 102.32) (width 0.15) (layer "F.Cu") (net 1))
  (segment (start 129 103.65) (end 129 102.32) (width 0.15) (layer "F.Cu") (net 1))
  (segment (start 128.675 134.555) (end 128.82 134.7) (width 0.15) (layer "F.Cu") (net 1))
  (segment (start 122.5 118.9) (end 123 119.4) (width 0.15) (layer "F.Cu") (net 1))
  (segment (start 161.532 115.95) (end 161.44 115.858) (width 0.15) (layer "F.Cu") (net 1))
  (segment (start 120.5 114.9) (end 120 114.4) (width 0.15) (layer "F.Cu") (net 1))
  (segment (start 163.81 120.45) (end 162.6 120.45) (width 0.15) (layer "F.Cu") (net 1))
  (segment (start 147.94 119.56) (end 147.94 120.05) (width 0.1) (layer "F.Cu") (net 1))
  (segment (start 147.195 118.815) (end 147.94 119.56) (width 0.1) (layer "F.Cu") (net 1))
  (segment (start 129.247 124.975) (end 129.6 125.328) (width 0.15) (layer "F.Cu") (net 1))
  (segment (start 120 113.4) (end 119.974991 113.4) (width 0.15) (layer "F.Cu") (net 1))
  (segment (start 126.296438 113.396438) (end 126.3 113.4) (width 0.15) (layer "F.Cu") (net 1))
  (segment (start 120.635 130.73) (end 121.36001 130.73) (width 0.1) (layer "F.Cu") (net 1))
  (segment (start 122 111.4) (end 122 108.41) (width 0.15) (layer "F.Cu") (net 1))
  (segment (start 147.715 120.725) (end 146.87 119.88) (width 0.1) (layer "F.Cu") (net 1))
  (segment (start 146.87 118.49) (end 147.195 118.165) (width 0.1) (layer "F.Cu") (net 1))
  (segment (start 162.6 124.95) (end 163.690006 124.95) (width 0.15) (layer "F.Cu") (net 1))
  (segment (start 162.6 123.45) (end 163.72 123.45) (width 0.15) (layer "F.Cu") (net 1))
  (segment (start 162.6 115.95) (end 161.532 115.95) (width 0.15) (layer "F.Cu") (net 1))
  (segment (start 122 108.41) (end 122.005 108.405) (width 0.15) (layer "F.Cu") (net 1))
  (segment (start 120 114.4) (end 119.974991 114.4) (width 0.15) (layer "F.Cu") (net 1))
  (segment (start 148.515 120.565) (end 148.355 120.725) (width 0.1) (layer "F.Cu") (net 1))
  (segment (start 128.675 134.08) (end 128.675 134.555) (width 0.15) (layer "F.Cu") (net 1))
  (segment (start 146.87 112.315) (end 146.87 113.29) (width 0.1) (layer "F.Cu") (net 1))
  (segment (start 123 122.108908) (end 123.571092 122.68) (width 0.15) (layer "F.Cu") (net 1))
  (segment (start 131 103.65) (end 131 102.33) (width 0.15) (layer "F.Cu") (net 1))
  (segment (start 164.3 130.899) (end 164.3 130.95) (width 0.15) (layer "F.Cu") (net 1))
  (segment (start 129.6 125.328) (end 129.6 125.8) (width 0.15) (layer "F.Cu") (net 1))
  (segment (start 133 103.65) (end 133 102.33) (width 0.15) (layer "F.Cu") (net 1))
  (segment (start 144.27 112.08) (end 144.15 111.96) (width 0.1) (layer "F.Cu") (net 1))
  (segment (start 147.68 111.505) (end 146.87 112.315) (width 0.1) (layer "F.Cu") (net 1))
  (segment (start 122.985 130.73) (end 122.240008 130.73) (width 0.1) (layer "F.Cu") (net 1))
  (segment (start 164.3 102.502) (end 164.3 102.5) (width 0.15) (layer "F.Cu") (net 1))
  (segment (start 124.5 113.9) (end 125.003562 113.396438) (width 0.15) (layer "F.Cu") (net 1))
  (segment (start 163.429 114.45) (end 163.976 113.903) (width 0.15) (layer "F.Cu") (net 1))
  (segment (start 162.6 114.45) (end 163.429 114.45) (width 0.15) (layer "F.Cu") (net 1))
  (segment (start 123.571092 122.68) (end 124.71 122.68) (width 0.15) (layer "F.Cu") (net 1))
  (segment (start 120.5 113.9) (end 120 113.4) (width 0.15) (layer "F.Cu") (net 1))
  (segment (start 122.240008 130.73) (end 122.24 130.729992) (width 0.1) (layer "F.Cu") (net 1))
  (segment (start 129.6 133.3) (end 129.6 135) (width 0.15) (layer "F.Cu") (net 1))
  (segment (start 128.9975 102.32) (end 128.9925 102.315) (width 0.15) (layer "F.Cu") (net 1))
  (segment (start 149.775 110.785) (end 149.055 111.505) (width 0.1) (layer "F.Cu") (net 1))
  (segment (start 163.690006 124.95) (end 163.7 124.940006) (width 0.15) (layer "F.Cu") (net 1))
  (segment (start 127.91 133.08) (end 127.425 133.565) (width 0.15) (layer "F.Cu") (net 1))
  (segment (start 144.15 110.88) (end 144.05 110.78) (width 0.1) (layer "F.Cu") (net 1))
  (segment (start 162.6 121.95) (end 163.69 121.95) (width 0.15) (layer "F.Cu") (net 1))
  (segment (start 125.01 117.41) (end 126.41 117.41) (width 0.15) (layer "F.Cu") (net 1))
  (segment (start 147.195 112.965) (end 147.195 111.99) (width 0.1) (layer "F.Cu") (net 1))
  (segment (start 149.055 111.505) (end 147.68 111.505) (width 0.1) (layer "F.Cu") (net 1))
  (segment (start 144.15 111.96) (end 144.15 110.88) (width 0.1) (layer "F.Cu") (net 1))
  (segment (start 144.27 113.29) (end 144.27 112.08) (width 0.1) (layer "F.Cu") (net 1))
  (segment (start 128.675 133.08) (end 127.91 133.08) (width 0.15) (layer "F.Cu") (net 1))
  (segment (start 123 119.4) (end 123 122.108908) (width 0.15) (layer "F.Cu") (net 1))
  (segment (start 146.87 119.88) (end 146.87 118.49) (width 0.1) (layer "F.Cu") (net 1))
  (segment (start 125.003562 113.396438) (end 126.296438 113.396438) (width 0.15) (layer "F.Cu") (net 1))
  (segment (start 163.69 121.95) (end 163.7 121.96) (width 0.15) (layer "F.Cu") (net 1))
  (segment (start 144.595 113.615) (end 144.27 113.29) (width 0.1) (layer "F.Cu") (net 1))
  (segment (start 146.87 113.29) (end 147.195 113.615) (width 0.1) (layer "F.Cu") (net 1))
  (segment (start 127.925 124.975) (end 129.247 124.975) (width 0.15) (layer "F.Cu") (net 1))
  (segment (start 148.355 120.725) (end 147.715 120.725) (width 0.1) (layer "F.Cu") (net 1))
  (segment (start 124.5 116.9) (end 125.01 117.41) (width 0.15) (layer "F.Cu") (net 1))
  (via (at 119 117.4) (size 0.55) (drill 0.15) (layers "F.Cu" "B.Cu") (net 1))
  (via (at 120 117.4) (size 0.55) (drill 0.15) (layers "F.Cu" "B.Cu") (net 1))
  (via (at 120 116.4) (size 0.55) (drill 0.15) (layers "F.Cu" "B.Cu") (net 1))
  (via (at 143.945 115.0775) (size 0.55) (drill 0.15) (layers "F.Cu" "B.Cu") (net 1))
  (via (at 147.195 115.0775) (size 0.55) (drill 0.15) (layers "F.Cu" "B.Cu") (net 1))
  (via (at 127 102.32) (size 0.55) (drill 0.15) (layers "F.Cu" "B.Cu") (net 1))
  (via (at 128.995 102.315) (size 0.55) (drill 0.15) (layers "F.Cu" "B.Cu") (net 1))
  (via (at 132.84 134.08) (size 0.55) (drill 0.15) (layers "F.Cu" "B.Cu") (net 1))
  (via (at 133 102.33) (size 0.55) (drill 0.15) (layers "F.Cu" "B.Cu") (net 1))
  (via (at 121.36001 130.73) (size 0.55) (drill 0.15) (layers "F.Cu" "B.Cu") (net 1))
  (via (at 149.775 110.785) (size 0.55) (drill 0.15) (layers "F.Cu" "B.Cu") (net 1))
  (via (at 127.4 135.6) (size 0.55) (drill 0.15) (layers "F.Cu" "B.Cu") (net 1))
  (via (at 148.515 120.565) (size 0.55) (drill 0.15) (layers "F.Cu" "B.Cu") (net 1))
  (via (at 129.6 135) (size 0.55) (drill 0.15) (layers "F.Cu" "B.Cu") (net 1))
  (via (at 124.3 109.4) (size 0.55) (drill 0.15) (layers "F.Cu" "B.Cu") (net 1))
  (via (at 122.005 108.405) (size 0.55) (drill 0.15) (layers "F.Cu" "B.Cu") (net 1))
  (via (at 163.7 124.940006) (size 0.55) (drill 0.15) (layers "F.Cu" "B.Cu") (net 1))
  (via (at 137.426 117.481494) (size 0.55) (drill 0.15) (layers "F.Cu" "B.Cu") (net 1))
  (via (at 129.6 125.8) (size 0.55) (drill 0.15) (layers "F.Cu" "B.Cu") (net 1))
  (via (at 109.75 133) (size 0.55) (drill 0.15) (layers "F.Cu" "B.Cu") (net 1))
  (via (at 110.75 133) (size 0.55) (drill 0.15) (layers "F.Cu" "B.Cu") (net 1))
  (via (at 135.03 125.9) (size 0.55) (drill 0.15) (layers "F.Cu" "B.Cu") (net 1))
  (via (at 146.9 104.98) (size 0.55) (drill 0.15) (layers "F.Cu" "B.Cu") (net 1))
  (via (at 139.925 111.575) (size 0.55) (drill 0.15) (layers "F.Cu" "B.Cu") (net 1))
  (via (at 119.974991 113.4) (size 0.55) (drill 0.15) (layers "F.Cu" "B.Cu") (net 1))
  (via (at 149.885 120.015) (size 0.55) (drill 0.15) (layers "F.Cu" "B.Cu") (net 1))
  (via (at 127.425 133.565) (size 0.55) (drill 0.15) (layers "F.Cu" "B.Cu") (net 1))
  (via (at 122.24 130.729992) (size 0.55) (drill 0.15) (layers "F.Cu" "B.Cu") (net 1))
  (via (at 127.51 109.409998) (size 0.55) (drill 0.15) (layers "F.Cu" "B.Cu") (net 1))
  (via (at 163.72 123.45) (size 0.55) (drill 0.15) (layers "F.Cu" "B.Cu") (net 1))
  (via (at 125.4 109.4) (size 0.55) (drill 0.15) (layers "F.Cu" "B.Cu") (net 1))
  (via (at 135.59 136.08) (size 0.55) (drill 0.15) (layers "F.Cu" "B.Cu") (net 1))
  (via (at 119.974991 114.4) (size 0.55) (drill 0.15) (layers "F.Cu" "B.Cu") (net 1))
  (via (at 147.94 120.05) (size 0.55) (drill 0.15) (layers "F.Cu" "B.Cu") (net 1))
  (via (at 144.05 110.78) (size 0.55) (drill 0.15) (layers "F.Cu" "B.Cu") (net 1))
  (via (at 128.82 134.7) (size 0.55) (drill 0.15) (layers "F.Cu" "B.Cu") (net 1))
  (via (at 131 102.325) (size 0.55) (drill 0.15) (layers "F.Cu" "B.Cu") (net 1))
  (via (at 144.13 104.98) (size 0.55) (drill 0.15) (layers "F.Cu" "B.Cu") (net 1))
  (via (at 124.71 122.68) (size 0.55) (drill 0.15) (layers "F.Cu" "B.Cu") (net 1))
  (via (at 126.41 117.41) (size 0.55) (drill 0.15) (layers "F.Cu" "B.Cu") (net 1))
  (via (at 126.3 113.4) (size 0.55) (drill 0.15) (layers "F.Cu" "B.Cu") (net 1))
  (via (at 163.976 113.903) (size 0.55) (drill 0.15) (layers "F.Cu" "B.Cu") (net 1))
  (via (at 146.35999 108.52241) (size 0.55) (drill 0.15) (layers "F.Cu" "B.Cu") (net 1))
  (via (at 164.3 102.5) (size 0.55) (drill 0.15) (layers "F.Cu" "B.Cu") (net 1))
  (via (at 161.44 115.858) (size 0.55) (drill 0.15) (layers "F.Cu" "B.Cu") (net 1))
  (via (at 163.7 121.96) (size 0.55) (drill 0.15) (layers "F.Cu" "B.Cu") (net 1))
  (via (at 164.3 130.95) (size 0.55) (drill 0.15) (layers "F.Cu" "B.Cu") (net 1))
  (via (at 163.81 120.45) (size 0.55) (drill 0.15) (layers "F.Cu" "B.Cu") (net 1))
  (via (at 132.750002 133.08) (size 0.55) (drill 0.15) (layers "F.Cu" "B.Cu") (net 1))
  (via (at 130.5 134.7) (size 0.55) (drill 0.15) (layers "F.Cu" "B.Cu") (net 1))
  (via (at 126.5 109.4) (size 0.55) (drill 0.15) (layers "F.Cu" "B.Cu") (net 1))
  (segment (start 120.485 116.915) (end 120 117.4) (width 0.15) (layer "B.Cu") (net 1))
  (segment (start 121 113.9) (end 120.474991 113.9) (width 0.15) (layer "B.Cu") (net 1))
  (segment (start 149.885 120.015) (end 149.65 120.015) (width 0.15) (layer "B.Cu") (net 1))
  (segment (start 146.93 119.345) (end 146.89 119.345) (width 0.15) (layer "B.Cu") (net 1))
  (segment (start 125.5 110.415) (end 125.5 110.4) (width 0.15) (layer "B.Cu") (net 1))
  (segment (start 124.5 110.415) (end 124.5 110.3) (width 0.15) (layer "B.Cu") (net 1))
  (segment (start 128.7 133.93) (end 128.7 134.58) (width 0.15) (layer "B.Cu") (net 1))
  (segment (start 125.5 110.4) (end 126.5 109.4) (width 0.15) (layer "B.Cu") (net 1))
  (segment (start 144.085 110.815) (end 144.05 110.78) (width 0.15) (layer "B.Cu") (net 1))
  (segment (start 121.965 108.445) (end 121.965 110.85) (width 0.15) (layer "B.Cu") (net 1))
  (segment (start 147.96 115.415) (end 147.5325 115.415) (width 0.15) (layer "B.Cu") (net 1))
  (segment (start 138.389506 118.445) (end 142.48 118.445) (width 0.15) (layer "B.Cu") (net 1))
  (segment (start 133.615 134.08) (end 132.84 134.08) (width 0.15) (layer "B.Cu") (net 1))
  (segment (start 126.585 135.6) (end 127.4 135.6) (width 0.15) (layer "B.Cu") (net 1))
  (segment (start 141.345 112.085) (end 141.985 112.725) (width 0.15) (layer "B.Cu") (net 1))
  (segment (start 126.5 110.41) (end 127.500002 109.409998) (width 0.15) (layer "B.Cu") (net 1))
  (segment (start 145.915 112.46) (end 145.568 112.46) (width 0.15) (layer "B.Cu") (net 1))
  (segment (start 147.875 120.725) (end 146.93 119.78) (width 0.15) (layer "B.Cu") (net 1))
  (segment (start 120 116.4) (end 120.835 116.4) (width 0.15) (layer "B.Cu") (net 1))
  (segment (start 145.175 113.715) (end 144.345 113.715) (width 0.15) (layer "B.Cu") (net 1))
  (segment (start 126.5 110.415) (end 126.5 110.41) (width 0.15) (layer "B.Cu") (net 1))
  (segment (start 145.345 112.683) (end 145.345 113.545) (width 0.15) (layer "B.Cu") (net 1))
  (segment (start 144.345 113.715) (end 144.085 113.455) (width 0.15) (layer "B.Cu") (net 1))
  (segment (start 133.160001 124.932) (end 133.160001 125.252) (width 0.125) (layer "B.Cu") (net 1))
  (segment (start 119.515 114.859991) (end 119.974991 114.4) (width 0.15) (layer "B.Cu") (net 1))
  (segment (start 149.775 110.785) (end 150.025 110.785) (width 0.15) (layer "B.Cu") (net 1))
  (segment (start 133.160001 124.932) (end 133.160001 123.932) (width 0.15) (layer "B.Cu") (net 1))
  (segment (start 150.285 111.725) (end 149.555 112.455) (width 0.15) (layer "B.Cu") (net 1))
  (segment (start 142.48 118.445) (end 143.25 117.675) (width 0.15) (layer "B.Cu") (net 1))
  (segment (start 119.974991 113.4) (end 120.474991 113.9) (width 0.15) (layer "B.Cu") (net 1))
  (segment (start 121.515 115.72) (end 120.835 116.4) (width 0.15) (layer "B.Cu") (net 1))
  (segment (start 140.445 112.085) (end 141.345 112.085) (width 0.15) (layer "B.Cu") (net 1))
  (segment (start 149.65 120.015) (end 148.99 119.355) (width 0.15) (layer "B.Cu") (net 1))
  (segment (start 119.515 115.4) (end 119.515 114.859991) (width 0.15) (layer "B.Cu") (net 1))
  (segment (start 133.160001 123.909999) (end 134.14 122.93) (width 0.15) (layer "B.Cu") (net 1))
  (segment (start 145.8524 109.03) (end 146.35999 108.52241) (width 0.15) (layer "B.Cu") (net 1))
  (segment (start 150.025 110.785) (end 150.285 111.045) (width 0.15) (layer "B.Cu") (net 1))
  (segment (start 121 116.915) (end 120.485 116.915) (width 0.15) (layer "B.Cu") (net 1))
  (segment (start 145.265 107.86) (end 145.69758 107.86) (width 0.15) (layer "B.Cu") (net 1))
  (segment (start 139.925 111.575) (end 139.935 111.575) (width 0.15) (layer "B.Cu") (net 1))
  (segment (start 124.5 110.3) (end 125.4 109.4) (width 0.15) (layer "B.Cu") (net 1))
  (segment (start 149.02 116.415) (end 149.245 116.415) (width 0.15) (layer "B.Cu") (net 1))
  (segment (start 123.5 110.415) (end 123.5 110.2) (width 0.15) (layer "B.Cu") (net 1))
  (segment (start 146.895 113.49) (end 146.895 113.44) (width 0.15) (layer "B.Cu") (net 1))
  (segment (start 149.48 116.18) (end 149.48 112.52) (width 0.15) (layer "B.Cu") (net 1))
  (segment (start 121.965 110.85) (end 122.5 111.385) (width 0.15) (layer "B.Cu") (net 1))
  (segment (start 126.585 134.58) (end 126.585 135.6) (width 0.15) (layer "B.Cu") (net 1))
  (segment (start 147.96 119.355) (end 147.96 120.03) (width 0.15) (layer "B.Cu") (net 1))
  (segment (start 149.555 112.455) (end 149.545 112.455) (width 0.15) (layer "B.Cu") (net 1))
  (segment (start 149.245 116.415) (end 149.48 116.18) (width 0.15) (layer "B.Cu") (net 1))
  (segment (start 146.89 119.345) (end 145.82 118.275) (width 0.15) (layer "B.Cu") (net 1))
  (segment (start 146.895 113.44) (end 145.915 112.46) (width 0.15) (layer "B.Cu") (net 1))
  (segment (start 133.808001 125.9) (end 135.03 125.9) (width 0.125) (layer "B.Cu") (net 1))
  (segment (start 143.7875 115.235) (end 143.945 115.0775) (width 0.15) (layer "B.Cu") (net 1))
  (segment (start 145.69758 107.86) (end 146.35999 108.52241) (width 0.15) (layer "B.Cu") (net 1))
  (segment (start 110.75 133.765) (end 110.75 133) (width 0.15) (layer "B.Cu") (net 1))
  (segment (start 150.285 111.045) (end 150.285 111.725) (width 0.15) (layer "B.Cu") (net 1))
  (segment (start 123.5 110.2) (end 124.3 109.4) (width 0.15) (layer "B.Cu") (net 1))
  (segment (start 145.345 113.545) (end 145.175 113.715) (width 0.15) (layer "B.Cu") (net 1))
  (segment (start 145.568 112.46) (end 145.345 112.683) (width 0.15) (layer "B.Cu") (net 1))
  (segment (start 144.995 104.98) (end 144.13 104.98) (width 0.25) (layer "B.Cu") (net 1))
  (segment (start 137.426 117.481494) (end 138.389506 118.445) (width 0.15) (layer "B.Cu") (net 1))
  (segment (start 109.75 133.765) (end 109.75 133) (width 0.15) (layer "B.Cu") (net 1))
  (segment (start 128.7 134.58) (end 128.82 134.7) (width 0.15) (layer "B.Cu") (net 1))
  (segment (start 143.25 115.235) (end 143.7875 115.235) (width 0.15) (layer "B.Cu") (net 1))
  (segment (start 139.935 111.575) (end 140.445 112.085) (width 0.15) (layer "B.Cu") (net 1))
  (segment (start 134.585 136.08) (end 135.59 136.08) (width 0.1) (layer "B.Cu") (net 1))
  (segment (start 149.48 112.52) (end 149.545 112.455) (width 0.15) (layer "B.Cu") (net 1))
  (segment (start 133.160001 123.932) (end 133.160001 123.909999) (width 0.15) (layer "B.Cu") (net 1))
  (segment (start 121.515 115.4) (end 121.515 115.72) (width 0.15) (layer "B.Cu") (net 1))
  (segment (start 145.47 109.03) (end 145.8524 109.03) (width 0.15) (layer "B.Cu") (net 1))
  (segment (start 145.995 104.98) (end 146.9 104.98) (width 0.25) (layer "B.Cu") (net 1))
  (segment (start 145.74 114.96) (end 147.0775 114.96) (width 0.15) (layer "B.Cu") (net 1))
  (segment (start 133.615 133.08) (end 132.750002 133.08) (width 0.15) (layer "B.Cu") (net 1))
  (segment (start 147.5325 115.415) (end 147.195 115.0775) (width 0.15) (layer "B.Cu") (net 1))
  (segment (start 146.93 119.78) (end 146.93 119.345) (width 0.15) (layer "B.Cu") (net 1))
  (segment (start 147.0775 114.96) (end 147.195 115.0775) (width 0.15) (layer "B.Cu") (net 1))
  (segment (start 130.5 133.93) (end 130.5 134.7) (width 0.15) (layer "B.Cu") (net 1))
  (segment (start 147.96 120.03) (end 147.94 120.05) (width 0.15) (layer "B.Cu") (net 1))
  (segment (start 122.005 108.405) (end 121.965 108.445) (width 0.15) (layer "B.Cu") (net 1))
  (segment (start 148.515 120.565) (end 148.355 120.725) (width 0.15) (layer "B.Cu") (net 1))
  (segment (start 144.085 113.455) (end 144.085 110.815) (width 0.15) (layer "B.Cu") (net 1))
  (segment (start 133.160001 125.252) (end 133.808001 125.9) (width 0.125) (layer "B.Cu") (net 1))
  (segment (start 148.355 120.725) (end 147.875 120.725) (width 0.15) (layer "B.Cu") (net 1))
  (segment (start 149.545 112.455) (end 148.95 112.455) (width 0.15) (layer "B.Cu") (net 1))
  (segment (start 127.500002 109.409998) (end 127.51 109.409998) (width 0.15) (layer "B.Cu") (net 1))
  (segment (start 126.585 133.58) (end 127.41 133.58) (width 0.15) (layer "B.Cu") (net 1))
  (segment (start 121.5 115.9) (end 122 116.4) (width 0.15) (layer "F.Cu") (net 2))
  (segment (start 121.5 116.9) (end 122 117.4) (width 0.15) (layer "F.Cu") (net 2))
  (segment (start 145.895 116.215) (end 146.22 116.54) (width 0.1) (layer "F.Cu") (net 2))
  (segment (start 146.22 116.54) (end 146.22 117.3525) (width 0.1) (layer "F.Cu") (net 2))
  (segment (start 146.22 117.3525) (end 146.3825 117.515) (width 0.1) (layer "F.Cu") (net 2))
  (segment (start 145.895 114.7525) (end 146.3825 114.265) (width 0.1) (layer "F.Cu") (net 2))
  (segment (start 145.895 114.915) (end 145.895 114.7525) (width 0.1) (layer "F.Cu") (net 2))
  (segment (start 144.05 108.75) (end 145.08 107.72) (width 0.15) (layer "F.Cu") (net 2))
  (segment (start 121.989991 114.410009) (end 121.989991 114.4) (width 0.15) (layer "F.Cu") (net 2))
  (segment (start 131.837 130.413) (end 133.38 128.87) (width 0.15) (layer "F.Cu") (net 2))
  (segment (start 133.38 128.87) (end 134.989 128.87) (width 0.15) (layer "F.Cu") (net 2))
  (segment (start 138.959166 108.75) (end 144.05 108.75) (width 0.15) (layer "F.Cu") (net 2))
  (segment (start 121.989991 113.410009) (end 121.989991 113.39498) (width 0.15) (layer "F.Cu") (net 2))
  (segment (start 131.179 132.58) (end 131.837 131.922) (width 0.15) (layer "F.Cu") (net 2))
  (segment (start 121.5 114.9) (end 121.989991 114.410009) (width 0.15) (layer "F.Cu") (net 2))
  (segment (start 145.08 107.72) (end 147.07 107.72) (width 0.15) (layer "F.Cu") (net 2))
  (segment (start 131.837 131.922) (end 131.837 130.413) (width 0.15) (layer "F.Cu") (net 2))
  (segment (start 138.856583 108.852583) (end 138.959166 108.75) (width 0.15) (layer "F.Cu") (net 2))
  (segment (start 130.525 132.58) (end 131.179 132.58) (width 0.15) (layer "F.Cu") (net 2))
  (segment (start 121.5 113.9) (end 121.989991 113.410009) (width 0.15) (layer "F.Cu") (net 2))
  (via (at 122 117.4) (size 0.55) (drill 0.15) (layers "F.Cu" "B.Cu") (net 2))
  (via (at 122 116.4) (size 0.55) (drill 0.15) (layers "F.Cu" "B.Cu") (net 2))
  (via (at 146.3825 114.265) (size 0.55) (drill 0.15) (layers "F.Cu" "B.Cu") (net 2))
  (via (at 146.3825 117.515) (size 0.55) (drill 0.15) (layers "F.Cu" "B.Cu") (net 2))
  (via (at 135.59 135.08) (size 0.55) (drill 0.15) (layers "F.Cu" "B.Cu") (net 2))
  (via (at 135.61 134.06) (size 0.55) (drill 0.15) (layers "F.Cu" "B.Cu") (net 2))
  (via (at 134.989 128.87) (size 0.55) (drill 0.15) (layers "F.Cu" "B.Cu") (net 2))
  (via (at 149.905 119.095) (size 0.55) (drill 0.15) (layers "F.Cu" "B.Cu") (net 2))
  (via (at 135.600001 130.230001) (size 0.55) (drill 0.15) (layers "F.Cu" "B.Cu") (net 2))
  (via (at 137.35 119.19) (size 0.55) (drill 0.15) (layers "F.Cu" "B.Cu") (net 2))
  (via (at 138.856583 108.852583) (size 0.55) (drill 0.15) (layers "F.Cu" "B.Cu") (net 2))
  (via (at 135.61 133.08) (size 0.55) (drill 0.15) (layers "F.Cu" "B.Cu") (net 2))
  (via (at 147.07 107.72) (size 0.55) (drill 0.15) (layers "F.Cu" "B.Cu") (net 2))
  (via (at 121.989991 114.4) (size 0.55) (drill 0.15) (layers "F.Cu" "B.Cu") (net 2))
  (via (at 121.989991 113.39498) (size 0.55) (drill 0.15) (layers "F.Cu" "B.Cu") (net 2))
  (segment (start 148.94 112.58) (end 148.94 109.59) (width 0.125) (layer "In2.Cu") (net 2))
  (segment (start 147.07 107.72) (end 148.94 109.59) (width 0.125) (layer "In2.Cu") (net 2))
  (segment (start 147.84 113.68) (end 148.94 112.58) (width 0.125) (layer "In2.Cu") (net 2))
  (segment (start 146.3825 114.265) (end 146.9675 113.68) (width 0.125) (layer "In2.Cu") (net 2))
  (segment (start 146.3825 117.515) (end 146.3825 118.3325) (width 0.125) (layer "In2.Cu") (net 2))
  (segment (start 146.9675 113.68) (end 147.84 113.68) (width 0.125) (layer "In2.Cu") (net 2))
  (segment (start 149.56 118.75) (end 149.905 119.095) (width 0.125) (layer "In2.Cu") (net 2))
  (segment (start 146.8 118.75) (end 149.56 118.75) (width 0.125) (layer "In2.Cu") (net 2))
  (segment (start 146.3825 118.3325) (end 146.8 118.75) (width 0.125) (layer "In2.Cu") (net 2))
  (segment (start 146.93 118.375) (end 147.95 118.375) (width 0.15) (layer "B.Cu") (net 2))
  (segment (start 148.99 118.385) (end 149.195 118.385) (width 0.15) (layer "B.Cu") (net 2))
  (segment (start 122.485 115.4) (end 122.485 115.915) (width 0.15) (layer "B.Cu") (net 2))
  (segment (start 121.165 114.4) (end 121.989991 114.4) (width 0.15) (layer "B.Cu") (net 2))
  (segment (start 133.71 128.87) (end 134.989 128.87) (width 0.15) (layer "B.Cu") (net 2))
  (segment (start 135.59 134.08) (end 135.61 134.06) (width 0.15) (layer "B.Cu") (net 2))
  (segment (start 134.585 133.08) (end 135.61 133.08) (width 0.15) (layer "B.Cu") (net 2))
  (segment (start 120.485 115.08) (end 121.165 114.4) (width 0.15) (layer "B.Cu") (net 2))
  (segment (start 146.81 109.74) (end 146.81 107.98) (width 0.15) (layer "B.Cu") (net 2))
  (segment (start 140.285 119.95) (end 138.11 119.95) (width 0.15) (layer "B.Cu") (net 2))
  (segment (start 134.585 134.08) (end 135.59 134.08) (width 0.15) (layer "B.Cu") (net 2))
  (segment (start 138.11 119.95) (end 137.35 119.19) (width 0.15) (layer "B.Cu") (net 2))
  (segment (start 130.5 132.53) (end 130.5 132.08) (width 0.15) (layer "B.Cu") (net 2))
  (segment (start 148.99 117.415) (end 149.02 117.385) (width 0.15) (layer "B.Cu") (net 2))
  (segment (start 131.8 132.445) (end 130.585 132.445) (width 0.15) (layer "B.Cu") (net 2))
  (segment (start 146.81 107.98) (end 147.07 107.72) (width 0.15) (layer "B.Cu") (net 2))
  (segment (start 146.3825 117.515) (end 146.3825 117.8275) (width 0.15) (layer "B.Cu") (net 2))
  (segment (start 147.95 118.375) (end 147.96 118.385) (width 0.15) (layer "B.Cu") (net 2))
  (segment (start 121.515 117.885) (end 122 117.4) (width 0.15) (layer "B.Cu") (net 2))
  (segment (start 149.195 118.385) (end 149.905 119.095) (width 0.15) (layer "B.Cu") (net 2))
  (segment (start 134.585 135.08) (end 135.59 135.08) (width 0.15) (layer "B.Cu") (net 2))
  (segment (start 146.3825 117.8275) (end 146.93 118.375) (width 0.15) (layer "B.Cu") (net 2))
  (segment (start 148.99 118.385) (end 148.99 117.415) (width 0.15) (layer "B.Cu") (net 2))
  (segment (start 130.5 132.08) (end 133.71 128.87) (width 0.15) (layer "B.Cu") (net 2))
  (segment (start 140.747 119.488) (end 140.285 119.95) (width 0.15) (layer "B.Cu") (net 2))
  (segment (start 122.485 115.915) (end 122 116.4) (width 0.15) (layer "B.Cu") (net 2))
  (segment (start 141.65 119.488) (end 140.747 119.488) (width 0.15) (layer "B.Cu") (net 2))
  (segment (start 121.510011 112.915) (end 121.989991 113.39498) (width 0.15) (layer "B.Cu") (net 2))
  (segment (start 130.585 132.445) (end 130.5 132.53) (width 0.15) (layer "B.Cu") (net 2))
  (segment (start 121 117.885) (end 121.515 117.885) (width 0.15) (layer "B.Cu") (net 2))
  (segment (start 135.6 131.095) (end 135.600001 130.230001) (width 0.125) (layer "B.Cu") (net 2))
  (segment (start 120.485 115.4) (end 120.485 115.08) (width 0.15) (layer "B.Cu") (net 2))
  (segment (start 121 112.915) (end 121.510011 112.915) (width 0.15) (layer "B.Cu") (net 2))
  (segment (start 119.5 114.9) (end 119 114.4) (width 0.15) (layer "F.Cu") (net 3))
  (segment (start 117.5 116.9) (end 117 116.4) (width 0.15) (layer "F.Cu") (net 3))
  (segment (start 119.5 111.9) (end 119 111.4) (width 0.15) (layer "F.Cu") (net 3))
  (segment (start 117.5 114.9) (end 117 114.4) (width 0.15) (layer "F.Cu") (net 3))
  (segment (start 118.5 113.9) (end 118 113.4) (width 0.15) (layer "F.Cu") (net 3))
  (segment (start 119.5 113.9) (end 119 113.4) (width 0.15) (layer "F.Cu") (net 3))
  (segment (start 118.5 114.9) (end 118 114.4) (width 0.15) (layer "F.Cu") (net 3))
  (segment (start 99.33 121.03) (end 99.33 119.96) (width 0.6) (layer "F.Cu") (net 3))
  (segment (start 103.83 121.03) (end 103.83 119.96) (width 0.6) (layer "F.Cu") (net 3))
  (segment (start 99.43 121.13) (end 99.33 121.03) (width 0.6) (layer "F.Cu") (net 3))
  (segment (start 101.33 121.13) (end 103.73 121.13) (width 0.6) (layer "F.Cu") (net 3))
  (segment (start 103.73 121.13) (end 103.83 121.03) (width 0.6) (layer "F.Cu") (net 3))
  (segment (start 101.33 121.13) (end 99.43 121.13) (width 0.6) (layer "F.Cu") (net 3))
  (segment (start 114.81 111.66) (end 115.55 112.4) (width 0.15) (layer "F.Cu") (net 3))
  (segment (start 158.95 135.102) (end 158.002 135.102) (width 0.1) (layer "F.Cu") (net 3))
  (segment (start 113.36 110.29) (end 113.36 109.6) (width 0.25) (layer "F.Cu") (net 3))
  (segment (start 109.91 125.085) (end 109.91 125.83) (width 0.25) (layer "F.Cu") (net 3))
  (segment (start 117 116.4) (end 115.5 116.4) (width 0.15) (layer "F.Cu") (net 3))
  (segment (start 145.5 132.2) (end 145.5 132.75) (width 0.125) (layer "F.Cu") (net 3))
  (segment (start 101.35 111.85) (end 103.78 111.85) (width 0.6) (layer "F.Cu") (net 3))
  (segment (start 138 132.25) (end 138 132.8) (width 0.125) (layer "F.Cu") (net 3))
  (segment (start 144.25 132.2) (end 144.25 132.75) (width 0.125) (layer "F.Cu") (net 3))
  (segment (start 101.35 102.15) (end 99.45 102.15) (width 0.6) (layer "F.Cu") (net 3))
  (segment (start 103.78 111.85) (end 103.85 111.92) (width 0.6) (layer "F.Cu") (net 3))
  (segment (start 115.834184 117.357909) (end 114.297091 117.357909) (width 0.15) (layer "F.Cu") (net 3))
  (segment (start 118 116.4) (end 118 116.41001) (width 0.15) (layer "F.Cu") (net 3))
  (segment (start 117 114.4) (end 115.4 114.4) (width 0.15) (layer "F.Cu") (net 3))
  (segment (start 149.25 132.2) (end 149.25 132.75) (width 0.125) (layer "F.Cu") (net 3))
  (segment (start 111.185 117.77) (end 111.38 117.77) (width 0.15) (layer "F.Cu") (net 3))
  (segment (start 112.365 114.95) (end 111.61 114.95) (width 0.25) (layer "F.Cu") (net 3))
  (segment (start 111.411 125.789) (end 113.685 125.789) (width 0.15) (layer "F.Cu") (net 3))
  (segment (start 99.33 131.08) (end 99.58 130.83) (width 0.6) (layer "F.Cu") (net 3))
  (segment (start 146.75 132.2) (end 146.75 132.75) (width 0.125) (layer "F.Cu") (net 3))
  (segment (start 116.5 105.07) (end 116.505 105.065) (width 0.15) (layer "F.Cu") (net 3))
  (segment (start 139.25 132.2) (end 139.25 132.75) (width 0.125) (layer "F.Cu") (net 3))
  (segment (start 118.5 115.9) (end 118 116.4) (width 0.15) (layer "F.Cu") (net 3))
  (segment (start 103.85 111.92) (end 103.85 112.98) (width 0.6) (layer "F.Cu") (net 3))
  (segment (start 115.34 114.4) (end 114.53 115.21) (width 0.15) (layer "F.Cu") (net 3))
  (segment (start 151.745864 132.155842) (end 151.745864 132.705842) (width 0.125) (layer "F.Cu") (net 3))
  (segment (start 111.41 125.79) (end 111.411 125.789) (width 0.15) (layer "F.Cu") (net 3))
  (segment (start 99.33 131.96) (end 99.33 131.08) (width 0.6) (layer "F.Cu") (net 3))
  (segment (start 119.5 115.9) (end 119 116.4) (width 0.15) (layer "F.Cu") (net 3))
  (segment (start 117.5 105.07) (end 117.505 105.065) (width 0.15) (layer "F.Cu") (net 3))
  (segment (start 107.405 118.18) (end 106.56 118.18) (width 0.25) (layer "F.Cu") (net 3))
  (segment (start 113.833 125.641) (end 113.833 125.277) (width 0.15) (layer "F.Cu") (net 3))
  (segment (start 101.35 111.85) (end 99.6 111.85) (width 0.6) (layer "F.Cu") (net 3))
  (segment (start 115.55 112.4) (end 117 112.4) (width 0.15) (layer "F.Cu") (net 3))
  (segment (start 117.5 105.915) (end 117.5 105.07) (width 0.15) (layer "F.Cu") (net 3))
  (segment (start 99.58 130.83) (end 103.76 130.83) (width 0.6) (layer "F.Cu") (net 3))
  (segment (start 119 111.4) (end 119 108.9) (width 0.15) (layer "F.Cu") (net 3))
  (segment (start 143 132.2) (end 143 132.75) (width 0.125) (layer "F.Cu") (net 3))
  (segment (start 117.5 113.9) (end 118 114.4) (width 0.15) (layer "F.Cu") (net 3))
  (segment (start 114.81 110.75) (end 114.81 111.66) (width 0.15) (layer "F.Cu") (net 3))
  (segment (start 114.805 120.6) (end 113.91 120.6) (width 0.15) (layer "F.Cu") (net 3))
  (segment (start 119.5 105.915) (end 119.5 104.37) (width 0.15) (layer "F.Cu") (net 3))
  (segment (start 103.76 130.83) (end 103.801428 130.871428) (width 0.6) (layer "F.Cu") (net 3))
  (segment (start 103.75 102.15) (end 103.821428 102.078572) (width 0.6) (layer "F.Cu") (net 3))
  (segment (start 141.75 132.2) (end 141.75 132.75) (width 0.125) (layer "F.Cu") (net 3))
  (segment (start 113.685 125.789) (end 113.833 125.641) (width 0.15) (layer "F.Cu") (net 3))
  (segment (start 111.38 117.77) (end 112.06 117.09) (width 0.15) (layer "F.Cu") (net 3))
  (segment (start 103.801428 130.871428) (end 103.801428 131.95) (width 0.6) (layer "F.Cu") (net 3))
  (segment (start 158.002 135.102) (end 158 135.1) (width 0.1) (layer "F.Cu") (net 3))
  (segment (start 108.35 125.16) (end 108.35 126.23) (width 0.25) (layer "F.Cu") (net 3))
  (segment (start 154.852 135.102) (end 155.698 135.102) (width 0.1) (layer "F.Cu") (net 3))
  (segment (start 99.35 102.05) (end 99.35 100.98) (width 0.6) (layer "F.Cu") (net 3))
  (segment (start 119 116.4) (end 119 116.41001) (width 0.15) (layer "F.Cu") (net 3))
  (segment (start 148 132.2) (end 148 132.75) (width 0.125) (layer "F.Cu") (net 3))
  (segment (start 103.821428 102.078572) (end 103.821428 100.98) (width 0.6) (layer "F.Cu") (net 3))
  (segment (start 109.96 120.6) (end 109.26 120.6) (width 0.15) (layer "F.Cu") (net 3))
  (segment (start 155.698 135.102) (end 155.7 135.1) (width 0.1) (layer "F.Cu") (net 3))
  (segment (start 114.992 120.787) (end 114.805 120.6) (width 0.15) (layer "F.Cu") (net 3))
  (segment (start 115.4 114.4) (end 115.34 114.4) (width 0.15) (layer "F.Cu") (net 3))
  (segment (start 140.5 132.2) (end 140.5 132.75) (width 0.125) (layer "F.Cu") (net 3))
  (segment (start 101.35 102.15) (end 103.75 102.15) (width 0.6) (layer "F.Cu") (net 3))
  (segment (start 114.297091 117.357909) (end 114.255 117.4) (width 0.15) (layer "F.Cu") (net 3))
  (segment (start 116.957909 117.357909) (end 115.834184 117.357909) (width 0.15) (layer "F.Cu") (net 3))
  (segment (start 119.5 104.37) (end 119.505 104.365) (width 0.15) (layer "F.Cu") (net 3))
  (segment (start 117.5 117.9) (end 116.957909 117.357909) (width 0.15) (layer "F.Cu") (net 3))
  (segment (start 99.35 112.1) (end 99.35 112.98) (width 0.6) (layer "F.Cu") (net 3))
  (segment (start 116.5 105.915) (end 116.5 105.07) (width 0.15) (layer "F.Cu") (net 3))
  (segment (start 99.45 102.15) (end 99.35 102.05) (width 0.6) (layer "F.Cu") (net 3))
  (segment (start 99.6 111.85) (end 99.35 112.1) (width 0.6) (layer "F.Cu") (net 3))
  (segment (start 150.5 132.2) (end 150.5 132.75) (width 0.125) (layer "F.Cu") (net 3))
  (segment (start 117 112.4) (end 117.5 112.9) (width 0.15) (layer "F.Cu") (net 3))
  (via (at 119 114.4) (size 0.55) (drill 0.15) (layers "F.Cu" "B.Cu") (net 3))
  (via (at 119 113.4) (size 0.55) (drill 0.15) (layers "F.Cu" "B.Cu") (net 3))
  (via (at 118 114.4) (size 0.55) (drill 0.15) (layers "F.Cu" "B.Cu") (net 3))
  (via (at 118 113.4) (size 0.55) (drill 0.15) (layers "F.Cu" "B.Cu") (net 3))
  (via (at 112.31 120.14) (size 0.55) (drill 0.15) (layers "F.Cu" "B.Cu") (net 3))
  (via (at 111.51 120.94) (size 0.55) (drill 0.15) (layers "F.Cu" "B.Cu") (net 3))
  (via (at 112.31 120.94) (size 0.55) (drill 0.15) (layers "F.Cu" "B.Cu") (net 3))
  (via (at 111.51 121.74) (size 0.55) (drill 0.15) (layers "F.Cu" "B.Cu") (net 3))
  (via (at 112.31 121.74) (size 0.55) (drill 0.15) (layers "F.Cu" "B.Cu") (net 3))
  (via (at 99.458333 113.025) (size 0.55) (drill 0.15) (layers "F.Cu" "B.Cu") (net 3))
  (via (at 99.408333 119.8) (size 0.55) (drill 0.15) (layers "F.Cu" "B.Cu") (net 3))
  (via (at 103.441665 119.8) (size 0.55) (drill 0.15) (layers "F.Cu" "B.Cu") (net 3))
  (via (at 99.458333 132.15) (size 0.55) (drill 0.15) (layers "F.Cu" "B.Cu") (net 3))
  (via (at 103.491665 132.15) (size 0.55) (drill 0.15) (layers "F.Cu" "B.Cu") (net 3))
  (via (at 148 132.75) (size 0.55) (drill 0.15) (layers "F.Cu" "B.Cu") (net 3))
  (via (at 111.51 120.14) (size 0.55) (drill 0.15) (layers "F.Cu" "B.Cu") (net 3))
  (via (at 124.7 135.6) (size 0.55) (drill 0.15) (layers "F.Cu" "B.Cu") (net 3))
  (via (at 144.25 132.75) (size 0.55) (drill 0.15) (layers "F.Cu" "B.Cu") (net 3))
  (via (at 155.7 135.1) (size 0.55) (drill 0.15) (layers "F.Cu" "B.Cu") (net 3))
  (via (at 111.61 114.95) (size 0.55) (drill 0.15) (layers "F.Cu" "B.Cu") (net 3))
  (via (at 158 135.1) (size 0.55) (drill 0.15) (layers "F.Cu" "B.Cu") (net 3))
  (via (at 127.375 132.575) (size 0.55) (drill 0.15) (layers "F.Cu" "B.Cu") (net 3))
  (via (at 114.81 110.75) (size 0.55) (drill 0.15) (layers "F.Cu" "B.Cu") (net 3))
  (via (at 151.745864 132.705842) (size 0.55) (drill 0.15) (layers "F.Cu" "B.Cu") (net 3))
  (via (at 114.53 115.21) (size 0.55) (drill 0.15) (layers "F.Cu" "B.Cu") (net 3))
  (via (at 103.491665 113.025) (size 0.55) (drill 0.15) (layers "F.Cu" "B.Cu") (net 3))
  (via (at 143 132.75) (size 0.55) (drill 0.15) (layers "F.Cu" "B.Cu") (net 3))
  (via (at 132.7 132.08) (size 0.55) (drill 0.15) (layers "F.Cu" "B.Cu") (net 3))
  (via (at 106.56 118.18) (size 0.55) (drill 0.15) (layers "F.Cu" "B.Cu") (net 3))
  (via (at 146.75 132.75) (size 0.55) (drill 0.15) (layers "F.Cu" "B.Cu") (net 3))
  (via (at 117.505 105.065) (size 0.55) (drill 0.15) (layers "F.Cu" "B.Cu") (net 3))
  (via (at 119 116.41001) (size 0.55) (drill 0.15) (layers "F.Cu" "B.Cu") (net 3))
  (via (at 139.25 132.75) (size 0.55) (drill 0.15) (layers "F.Cu" "B.Cu") (net 3))
  (via (at 114.992 120.787) (size 0.55) (drill 0.15) (layers "F.Cu" "B.Cu") (net 3))
  (via (at 109.91 125.83) (size 0.55) (drill 0.15) (layers "F.Cu" "B.Cu") (net 3))
  (via (at 115.89 110.42) (size 0.55) (drill 0.15) (layers "F.Cu" "B.Cu") (net 3))
  (via (at 113.36 109.6) (size 0.55) (drill 0.15) (layers "F.Cu" "B.Cu") (net 3))
  (via (at 118 116.41001) (size 0.55) (drill 0.15) (layers "F.Cu" "B.Cu") (net 3))
  (via (at 111.41 125.79) (size 0.55) (drill 0.15) (layers "F.Cu" "B.Cu") (net 3))
  (via (at 109.26 120.6) (size 0.55) (drill 0.15) (layers "F.Cu" "B.Cu") (net 3))
  (via (at 113.75 135.5) (size 0.55) (drill 0.15) (layers "F.Cu" "B.Cu") (net 3))
  (via (at 117 108.9) (size 0.55) (drill 0.15) (layers "F.Cu" "B.Cu") (net 3))
  (via (at 140.5 132.75) (size 0.55) (drill 0.15) (layers "F.Cu" "B.Cu") (net 3))
  (via (at 145.5 132.75) (size 0.55) (drill 0.15) (layers "F.Cu" "B.Cu") (net 3))
  (via (at 150.5 132.75) (size 0.55) (drill 0.15) (layers "F.Cu" "B.Cu") (net 3))
  (via (at 127.385 131.585) (size 0.55) (drill 0.15) (layers "F.Cu" "B.Cu") (net 3))
  (via (at 129.3 109.3) (size 0.55) (drill 0.15) (layers "F.Cu" "B.Cu") (net 3))
  (via (at 119 108.9) (size 0.55) (drill 0.15) (layers "F.Cu" "B.Cu") (net 3))
  (via (at 115.5 116.4) (size 0.55) (drill 0.15) (layers "F.Cu" "B.Cu") (net 3))
  (via (at 141.75 132.75) (size 0.55) (drill 0.15) (layers "F.Cu" "B.Cu") (net 3))
  (via (at 103.646426 100.975) (size 0.55) (drill 0.15) (layers "F.Cu" "B.Cu") (net 3))
  (via (at 116.505 105.065) (size 0.55) (drill 0.15) (layers "F.Cu" "B.Cu") (net 3))
  (via (at 138 132.8) (size 0.55) (drill 0.15) (layers "F.Cu" "B.Cu") (net 3))
  (via (at 115.834184 117.357909) (size 0.55) (drill 0.15) (layers "F.Cu" "B.Cu") (net 3))
  (via (at 99.378571 100.975) (size 0.55) (drill 0.15) (layers "F.Cu" "B.Cu") (net 3))
  (via (at 149.25 132.75) (size 0.55) (drill 0.15) (layers "F.Cu" "B.Cu") (net 3))
  (via (at 108.35 126.23) (size 0.55) (drill 0.15) (layers "F.Cu" "B.Cu") (net 3))
  (via (at 119.505 104.365) (size 0.55) (drill 0.15) (layers "F.Cu" "B.Cu") (net 3))
  (via (at 112.06 117.09) (size 0.55) (drill 0.15) (layers "F.Cu" "B.Cu") (net 3))
  (via (at 112.75 135.5) (size 0.55) (drill 0.15) (layers "F.Cu" "B.Cu") (net 3))
  (via (at 115.5 118.9) (size 0.55) (drill 0.15) (layers "F.Cu" "B.Cu") (net 3))
  (via (at 133.61 130.25) (size 0.55) (drill 0.15) (layers "F.Cu" "B.Cu") (net 3))
  (segment (start 115.5 116.4) (end 116.28 116.4) (width 0.15) (layer "B.Cu") (net 3))
  (segment (start 116.5 115.885) (end 116.5 116.18) (width 0.15) (layer "B.Cu") (net 3))
  (segment (start 128.5 110.1) (end 129.3 109.3) (width 0.125) (layer "B.Cu") (net 3))
  (segment (start 112.75 134.75) (end 112.75 135.5) (width 0.15) (layer "B.Cu") (net 3))
  (segment (start 119.48 112.92) (end 120.12 112.92) (width 0.15) (layer "B.Cu") (net 3))
  (segment (start 119 113.4) (end 119.48 112.92) (width 0.15) (layer "B.Cu") (net 3))
  (segment (start 121.25 111.79) (end 121.25 111.55) (width 0.15) (layer "B.Cu") (net 3))
  (segment (start 133.61 131.075) (end 133.61 130.35) (width 0.15) (layer "B.Cu") (net 3))
  (segment (start 118 110.415) (end 118 109.9) (width 0.15) (layer "B.Cu") (net 3))
  (segment (start 114.524 115.204) (end 114.524 114.332) (width 0.15) (layer "B.Cu") (net 3))
  (segment (start 118 109.9) (end 117 108.9) (width 0.15) (layer "B.Cu") (net 3))
  (segment (start 119 110.415) (end 119 108.9) (width 0.15) (layer "B.Cu") (net 3))
  (segment (start 113.75 134.75) (end 113.75 135.5) (width 0.15) (layer "B.Cu") (net 3))
  (segment (start 114.524 114.332) (end 115.471 113.385) (width 0.15) (layer "B.Cu") (net 3))
  (segment (start 115.471 113.385) (end 116.5 113.385) (width 0.15) (layer "B.Cu") (net 3))
  (segment (start 114.53 115.21) (end 114.524 115.204) (width 0.15) (layer "B.Cu") (net 3))
  (segment (start 116.5 116.18) (end 116.28 116.4) (width 0.15) (layer "B.Cu") (net 3))
  (segment (start 125.615 135.6) (end 124.7 135.6) (width 0.15) (layer "B.Cu") (net 3))
  (segment (start 115.895 110.415) (end 117 110.415) (width 0.15) (layer "B.Cu") (net 3))
  (segment (start 126.585 131.58) (end 127.38 131.58) (width 0.15) (layer "B.Cu") (net 3))
  (segment (start 116.5 118.885) (end 115.515 118.885) (width 0.15) (layer "B.Cu") (net 3))
  (segment (start 115.89 110.42) (end 115.895 110.415) (width 0.15) (layer "B.Cu") (net 3))
  (segment (start 115.515 118.885) (end 115.5 118.9) (width 0.15) (layer "B.Cu") (net 3))
  (segment (start 120.12 112.92) (end 121.25 111.79) (width 0.15) (layer "B.Cu") (net 3))
  (segment (start 128.5 110.415) (end 128.5 110.1) (width 0.125) (layer "B.Cu") (net 3))
  (segment (start 133.61 130.35) (end 133.61 130.25) (width 0.1) (layer "B.Cu") (net 3))
  (segment (start 126.585 132.58) (end 127.37 132.58) (width 0.15) (layer "B.Cu") (net 3))
  (segment (start 133.615 132.08) (end 132.7 132.08) (width 0.15) (layer "B.Cu") (net 3))
  (segment (start 119.5 112.9) (end 119 112.4) (width 0.15) (layer "F.Cu") (net 4))
  (segment (start 118.5 112.9) (end 118 112.4) (width 0.15) (layer "F.Cu") (net 4))
  (segment (start 117 111.4) (end 117.5 111.9) (width 0.15) (layer "F.Cu") (net 4))
  (segment (start 115.88 111.4) (end 117 111.4) (width 0.15) (layer "F.Cu") (net 4))
  (via (at 119 112.4) (size 0.55) (drill 0.15) (layers "F.Cu" "B.Cu") (net 4))
  (via (at 118 112.4) (size 0.55) (drill 0.15) (layers "F.Cu" "B.Cu") (net 4))
  (via (at 136.51 127.6) (size 0.55) (drill 0.15) (layers "F.Cu" "B.Cu") (net 4))
  (via (at 137.24 127.6) (size 0.55) (drill 0.15) (layers "F.Cu" "B.Cu") (net 4))
  (via (at 115.88 111.4) (size 0.55) (drill 0.15) (layers "F.Cu" "B.Cu") (net 4))
  (segment (start 136.51 128.592) (end 136.51 127.6) (width 0.15) (layer "B.Cu") (net 4))
  (segment (start 119 111.385) (end 119 112.4) (width 0.15) (layer "B.Cu") (net 4))
  (segment (start 135.585 132.08) (end 135.6 132.065) (width 0.15) (layer "B.Cu") (net 4))
  (segment (start 115.88 111.4) (end 115.895 111.385) (width 0.15) (layer "B.Cu") (net 4))
  (segment (start 135.6 132.065) (end 136.409 132.065) (width 0.15) (layer "B.Cu") (net 4))
  (segment (start 137.24 131.234) (end 137.24 127.6) (width 0.15) (layer "B.Cu") (net 4))
  (segment (start 134.585 131.08) (end 134.585 130.517) (width 0.15) (layer "B.Cu") (net 4))
  (segment (start 120 111.385) (end 119 111.385) (width 0.15) (layer "B.Cu") (net 4))
  (segment (start 115.895 111.385) (end 117 111.385) (width 0.15) (layer "B.Cu") (net 4))
  (segment (start 136.409 132.065) (end 137.24 131.234) (width 0.15) (layer "B.Cu") (net 4))
  (segment (start 134.585 132.08) (end 135.585 132.08) (width 0.15) (layer "B.Cu") (net 4))
  (segment (start 134.585 130.517) (end 136.51 128.592) (width 0.15) (layer "B.Cu") (net 4))
  (segment (start 118 111.385) (end 118 112.4) (width 0.15) (layer "B.Cu") (net 4))
  (segment (start 118.5 105.915) (end 118.5 105.1) (width 0.15) (layer "F.Cu") (net 5))
  (segment (start 115.425001 109.264999) (end 115.73 108.96) (width 0.15) (layer "F.Cu") (net 5))
  (segment (start 115.34 117.93) (end 115.37 117.9) (width 0.15) (layer "F.Cu") (net 5))
  (segment (start 115.85 114.9) (end 116.5 114.9) (width 0.15) (layer "F.Cu") (net 5))
  (segment (start 115.5 115.25) (end 115.85 114.9) (width 0.15) (layer "F.Cu") (net 5))
  (segment (start 115.73 105.67) (end 115.72 105.66) (width 0.15) (layer "F.Cu") (net 5))
  (segment (start 115.73 108.96) (end 115.73 105.67) (width 0.15) (layer "F.Cu") (net 5))
  (segment (start 115.56 111.9) (end 115.425001 111.765001) (width 0.15) (layer "F.Cu") (net 5))
  (segment (start 116.5 111.9) (end 115.56 111.9) (width 0.15) (layer "F.Cu") (net 5))
  (segment (start 115.425001 111.765001) (end 115.425001 109.264999) (width 0.15) (layer "F.Cu") (net 5))
  (segment (start 115.37 117.9) (end 116.5 117.9) (width 0.15) (layer "F.Cu") (net 5))
  (via (at 115.72 105.66) (size 0.55) (drill 0.15) (layers "F.Cu" "B.Cu") (net 5))
  (via (at 115.5 115.25) (size 0.55) (drill 0.15) (layers "F.Cu" "B.Cu") (net 5))
  (via (at 118.5 105.1) (size 0.55) (drill 0.15) (layers "F.Cu" "B.Cu") (net 5))
  (via (at 124.7 132.58) (size 0.55) (drill 0.15) (layers "F.Cu" "B.Cu") (net 5))
  (via (at 115.34 117.93) (size 0.55) (drill 0.15) (layers "F.Cu" "B.Cu") (net 5))
  (via (at 124.7 131.58) (size 0.55) (drill 0.15) (layers "F.Cu" "B.Cu") (net 5))
  (segment (start 116.075 112.415) (end 115.425001 111.765001) (width 0.15) (layer "B.Cu") (net 5))
  (segment (start 117.27 114.465) (end 117.27 112.66) (width 0.15) (layer "B.Cu") (net 5))
  (segment (start 125.615 131.58) (end 124.7 131.58) (width 0.15) (layer "B.Cu") (net 5))
  (segment (start 115.425001 109.556999) (end 115.73 109.252) (width 0.15) (layer "B.Cu") (net 5))
  (segment (start 115.73 109.252) (end 115.73 105.65) (width 0.15) (layer "B.Cu") (net 5))
  (segment (start 115.73 105.65) (end 115.72 105.66) (width 0.15) (layer "B.Cu") (net 5))
  (segment (start 125.615 130.5) (end 125.615 131.58) (width 0.125) (layer "B.Cu") (net 5))
  (segment (start 116.5 112.415) (end 116.075 112.415) (width 0.15) (layer "B.Cu") (net 5))
  (segment (start 115.425001 111.765001) (end 115.425001 109.556999) (width 0.15) (layer "B.Cu") (net 5))
  (segment (start 117.02 112.41) (end 116.505 112.41) (width 0.15) (layer "B.Cu") (net 5))
  (segment (start 116.505 112.41) (end 116.5 112.415) (width 0.15) (layer "B.Cu") (net 5))
  (segment (start 115.355 117.915) (end 116.5 117.915) (width 0.15) (layer "B.Cu") (net 5))
  (segment (start 117.27 112.66) (end 117.02 112.41) (width 0.15) (layer "B.Cu") (net 5))
  (segment (start 116.5 114.915) (end 115.835 114.915) (width 0.15) (layer "B.Cu") (net 5))
  (segment (start 116.5 114.915) (end 116.82 114.915) (width 0.15) (layer "B.Cu") (net 5))
  (segment (start 115.34 117.93) (end 115.355 117.915) (width 0.15) (layer "B.Cu") (net 5))
  (segment (start 125.615 132.58) (end 124.7 132.58) (width 0.15) (layer "B.Cu") (net 5))
  (segment (start 115.835 114.915) (end 115.5 115.25) (width 0.15) (layer "B.Cu") (net 5))
  (segment (start 116.82 114.915) (end 117.27 114.465) (width 0.15) (layer "B.Cu") (net 5))
  (segment (start 132.135 125.625) (end 131.874999 125.885001) (width 0.125) (layer "F.Cu") (net 6))
  (segment (start 128.175 133.58) (end 127.850002 133.904998) (width 0.15) (layer "F.Cu") (net 6))
  (segment (start 131.874999 125.885001) (end 131.874999 126.924999) (width 0.125) (layer "F.Cu") (net 6))
  (segment (start 131.874999 126.924999) (end 132.42 127.47) (width 0.125) (layer "F.Cu") (net 6))
  (segment (start 132.42 127.47) (end 132.42 129.39) (width 0.125) (layer "F.Cu") (net 6))
  (segment (start 128.675 133.58) (end 128.175 133.58) (width 0.15) (layer "F.Cu") (net 6))
  (segment (start 132.42 129.39) (end 131.73 130.08) (width 0.125) (layer "F.Cu") (net 6))
  (segment (start 131.73 130.08) (end 129.81 130.08) (width 0.125) (layer "F.Cu") (net 6))
  (segment (start 146.87 115.565) (end 147.195 115.89) (width 0.1) (layer "F.Cu") (net 6))
  (segment (start 127.850002 133.904998) (end 127.850002 134.63) (width 0.15) (layer "F.Cu") (net 6))
  (segment (start 128.7 131.7) (end 128.7 132.555) (width 0.15) (layer "F.Cu") (net 6))
  (segment (start 159.315 105.9) (end 159.315 107) (width 0.25) (layer "F.Cu") (net 6))
  (segment (start 133.575 125.625) (end 132.135 125.625) (width 0.125) (layer "F.Cu") (net 6))
  (segment (start 146.545 115.565) (end 146.87 115.565) (width 0.1) (layer "F.Cu") (net 6))
  (segment (start 159.315 105.9) (end 158.3 105.9) (width 0.25) (layer "F.Cu") (net 6))
  (via (at 129.075 129) (size 0.55) (drill 0.15) (layers "F.Cu" "B.Cu") (net 6))
  (via (at 124.7 133.6) (size 0.55) (drill 0.15) (layers "F.Cu" "B.Cu") (net 6))
  (via (at 150.5 107.5) (size 0.55) (drill 0.15) (layers "F.Cu" "B.Cu") (net 6))
  (via (at 128.7 131.7) (size 0.55) (drill 0.15) (layers "F.Cu" "B.Cu") (net 6))
  (via (at 127.850002 134.63) (size 0.55) (drill 0.15) (layers "F.Cu" "B.Cu") (net 6))
  (via (at 159.315 107) (size 0.75) (drill 0.25) (layers "F.Cu" "B.Cu") (net 6))
  (via (at 158.3 105.9) (size 0.75) (drill 0.25) (layers "F.Cu" "B.Cu") (net 6))
  (via (at 129.81 130.08) (size 0.55) (drill 0.15) (layers "F.Cu" "B.Cu") (net 6))
  (via (at 109.75 135.5) (size 0.55) (drill 0.15) (layers "F.Cu" "B.Cu") (net 6))
  (via (at 124.695 134.585) (size 0.55) (drill 0.15) (layers "F.Cu" "B.Cu") (net 6))
  (via (at 111.75 135.5) (size 0.55) (drill 0.15) (layers "F.Cu" "B.Cu") (net 6))
  (via (at 127.4 130.5) (size 0.55) (drill 0.15) (layers "F.Cu" "B.Cu") (net 6))
  (via (at 150.57 108.52) (size 0.55) (drill 0.15) (layers "F.Cu" "B.Cu") (net 6))
  (via (at 147.195 115.89) (size 0.55) (drill 0.15) (layers "F.Cu" "B.Cu") (net 6))
  (via (at 128.2 129) (size 0.55) (drill 0.15) (layers "F.Cu" "B.Cu") (net 6))
  (via (at 110.75 135.5) (size 0.55) (drill 0.15) (layers "F.Cu" "B.Cu") (net 6))
  (segment (start 149.23 109.158908) (end 150.5 107.888908) (width 0.125) (layer "In2.Cu") (net 6))
  (segment (start 147.195 115.89) (end 149.23 113.855) (width 0.125) (layer "In2.Cu") (net 6))
  (segment (start 149.23 113.855) (end 149.23 109.158908) (width 0.125) (layer "In2.Cu") (net 6))
  (segment (start 150.5 107.888908) (end 150.5 107.5) (width 0.125) (layer "In2.Cu") (net 6))
  (segment (start 148.985 109.403908) (end 150.5 107.888908) (width 0.15) (layer "B.Cu") (net 6))
  (segment (start 125.615 134.58) (end 124.7 134.58) (width 0.15) (layer "B.Cu") (net 6))
  (segment (start 124.72 133.58) (end 124.7 133.6) (width 0.15) (layer "B.Cu") (net 6))
  (segment (start 109.75 134.735) (end 109.75 135.5) (width 0.15) (layer "B.Cu") (net 6))
  (segment (start 149.725 109.365) (end 149.725 109.99) (width 0.15) (layer "B.Cu") (net 6))
  (segment (start 145.45 111.545) (end 148.705 111.545) (width 0.15) (layer "B.Cu") (net 6))
  (segment (start 111.75 134.75) (end 111.75 135.5) (width 0.15) (layer "B.Cu") (net 6))
  (segment (start 125.615 133.58) (end 124.72 133.58) (width 0.15) (layer "B.Cu") (net 6))
  (segment (start 150.57 108.52) (end 149.725 109.365) (width 0.15) (layer "B.Cu") (net 6))
  (segment (start 110.75 134.735) (end 110.75 135.5) (width 0.15) (layer "B.Cu") (net 6))
  (segment (start 126.585 130.5) (end 127.4 130.5) (width 0.15) (layer "B.Cu") (net 6))
  (segment (start 148.985 111.265) (end 148.985 109.403908) (width 0.15) (layer "B.Cu") (net 6))
  (segment (start 150.5 107.888908) (end 150.5 107.5) (width 0.15) (layer "B.Cu") (net 6))
  (segment (start 144.79 112.205) (end 145.45 111.545) (width 0.15) (layer "B.Cu") (net 6))
  (segment (start 129.1 129.025) (end 129.075 129) (width 0.15) (layer "B.Cu") (net 6))
  (segment (start 147.195 115.89) (end 148.515 115.89) (width 0.15) (layer "B.Cu") (net 6))
  (segment (start 148.705 111.545) (end 148.985 111.265) (width 0.15) (layer "B.Cu") (net 6))
  (segment (start 144.79 112.99) (end 144.79 112.205) (width 0.15) (layer "B.Cu") (net 6))
  (segment (start 129 127.9) (end 128.2 128.7) (width 0.15) (layer "B.Cu") (net 6))
  (segment (start 129.915 129.025) (end 129.1 129.025) (width 0.15) (layer "B.Cu") (net 6))
  (segment (start 128.7 132.53) (end 128.7 131.7) (width 0.15) (layer "B.Cu") (net 6))
  (segment (start 129.915 127.9) (end 129 127.9) (width 0.15) (layer "B.Cu") (net 6))
  (segment (start 148.515 115.89) (end 148.98 115.425) (width 0.15) (layer "B.Cu") (net 6))
  (segment (start 128.2 128.7) (end 128.2 129) (width 0.15) (layer "B.Cu") (net 6))
  (segment (start 119.66 128.17) (end 119.66 130.725) (width 0.15) (layer "F.Cu") (net 7))
  (segment (start 121.54 127.39) (end 120.76 128.17) (width 0.15) (layer "F.Cu") (net 7))
  (segment (start 121.54 126.02) (end 121.54 127.39) (width 0.15) (layer "F.Cu") (net 7))
  (segment (start 121 125.48) (end 121.54 126.02) (width 0.15) (layer "F.Cu") (net 7))
  (segment (start 121 119.4) (end 121 125.48) (width 0.15) (layer "F.Cu") (net 7))
  (segment (start 120.76 128.17) (end 119.66 128.17) (width 0.15) (layer "F.Cu") (net 7))
  (segment (start 121.5 118.9) (end 121 119.4) (width 0.15) (layer "F.Cu") (net 7))
  (segment (start 123.96 130.725) (end 123.96 128.17) (width 0.15) (layer "F.Cu") (net 8))
  (segment (start 123.21 128.17) (end 123.225 128.185) (width 0.15) (layer "F.Cu") (net 8))
  (segment (start 121.93 127.39) (end 122.71 128.17) (width 0.15) (layer "F.Cu") (net 8))
  (segment (start 121.5 119.9) (end 121.5 125.52) (width 0.15) (layer "F.Cu") (net 8))
  (segment (start 121.5 125.52) (end 121.93 125.95) (width 0.15) (layer "F.Cu") (net 8))
  (segment (start 121.93 125.95) (end 121.93 127.39) (width 0.15) (layer "F.Cu") (net 8))
  (segment (start 122.71 128.17) (end 123.96 128.17) (width 0.15) (layer "F.Cu") (net 8))
  (segment (start 114.255 116.4) (end 114.5 116.4) (width 0.15) (layer "F.Cu") (net 9))
  (segment (start 114.5 116.4) (end 115 115.9) (width 0.15) (layer "F.Cu") (net 9))
  (segment (start 116.5 115.9) (end 115 115.9) (width 0.15) (layer "F.Cu") (net 9))
  (segment (start 117.5 110.9) (end 117.5 106.885) (width 0.15) (layer "F.Cu") (net 10))
  (segment (start 116.5 110.9) (end 116.5 106.885) (width 0.15) (layer "F.Cu") (net 11))
  (segment (start 113.285 116.4) (end 113.285 116.72998) (width 0.15) (layer "F.Cu") (net 12))
  (segment (start 113.285 117.08) (end 113.285 117.4) (width 0.15) (layer "F.Cu") (net 12))
  (segment (start 113.46001 116.90499) (end 113.285 117.08) (width 0.15) (layer "F.Cu") (net 12))
  (segment (start 113.285 116.72998) (end 113.46001 116.90499) (width 0.15) (layer "F.Cu") (net 12))
  (segment (start 116.5 116.9) (end 113.465 116.9) (width 0.15) (layer "F.Cu") (net 12))
  (segment (start 113.465 116.9) (end 113.46001 116.90499) (width 0.15) (layer "F.Cu") (net 12))
  (segment (start 123.5 109.5) (end 123.4 109.4) (width 0.15) (layer "F.Cu") (net 13))
  (segment (start 123.5 110.9) (end 123.5 109.5) (width 0.15) (layer "F.Cu") (net 13))
  (segment (start 143.295 116.865) (end 142.97 116.54) (width 0.1) (layer "F.Cu") (net 13))
  (segment (start 138.039999 116.540001) (end 142.97 116.54) (width 0.1) (layer "F.Cu") (net 13))
  (via (at 123.4 109.4) (size 0.55) (drill 0.15) (layers "F.Cu" "B.Cu") (net 13))
  (via (at 138.039999 116.540001) (size 0.55) (drill 0.15) (layers "F.Cu" "B.Cu") (net 13))
  (segment (start 123.9 111.8) (end 126.6 111.8) (width 0.125) (layer "In2.Cu") (net 13))
  (segment (start 123.4 109.4) (end 123.4 111.3) (width 0.125) (layer "In2.Cu") (net 13))
  (segment (start 131.340001 116.540001) (end 138.039999 116.540001) (width 0.125) (layer "In2.Cu") (net 13))
  (segment (start 126.6 111.8) (end 131.340001 116.540001) (width 0.125) (layer "In2.Cu") (net 13))
  (segment (start 123.4 111.3) (end 123.9 111.8) (width 0.125) (layer "In2.Cu") (net 13))
  (segment (start 120.5 106.9) (end 121.5 105.9) (width 0.15) (layer "F.Cu") (net 14))
  (segment (start 122.5 105.9) (end 123.5 105.9) (width 0.15) (layer "F.Cu") (net 14))
  (segment (start 145.245 112.965) (end 145.245 110.965) (width 0.1) (layer "F.Cu") (net 14))
  (segment (start 145.245 110.965) (end 145.34 110.87) (width 0.1) (layer "F.Cu") (net 14))
  (segment (start 120.5 110.9) (end 120.5 106.9) (width 0.15) (layer "F.Cu") (net 14))
  (segment (start 121.5 105.9) (end 122.5 105.9) (width 0.15) (layer "F.Cu") (net 14))
  (via (at 123.5 105.9) (size 0.55) (drill 0.15) (layers "F.Cu" "B.Cu") (net 14))
  (via (at 145.34 110.87) (size 0.55) (drill 0.15) (layers "F.Cu" "B.Cu") (net 14))
  (segment (start 140.977 104.75) (end 145.34 109.113) (width 0.125) (layer "In2.Cu") (net 14))
  (segment (start 123.5 105.9) (end 124.65 104.75) (width 0.125) (layer "In2.Cu") (net 14))
  (segment (start 145.34 109.113) (end 145.34 110.87) (width 0.125) (layer "In2.Cu") (net 14))
  (segment (start 124.65 104.75) (end 140.977 104.75) (width 0.125) (layer "In2.Cu") (net 14))
  (segment (start 121.5 107.9) (end 122 107.4) (width 0.15) (layer "F.Cu") (net 15))
  (segment (start 122.5 107.4) (end 123.5 107.4) (width 0.15) (layer "F.Cu") (net 15))
  (segment (start 144.92 111.59) (end 144.81 111.48) (width 0.1) (layer "F.Cu") (net 15))
  (segment (start 144.92 113.29) (end 144.92 111.59) (width 0.1) (layer "F.Cu") (net 15))
  (segment (start 122 107.4) (end 122.5 107.4) (width 0.15) (layer "F.Cu") (net 15))
  (segment (start 121.5 110.9) (end 121.5 107.9) (width 0.15) (layer "F.Cu") (net 15))
  (segment (start 145.245 113.615) (end 144.92 113.29) (width 0.1) (layer "F.Cu") (net 15))
  (via (at 123.5 107.4) (size 0.55) (drill 0.15) (layers "F.Cu" "B.Cu") (net 15))
  (via (at 144.81 111.48) (size 0.55) (drill 0.15) (layers "F.Cu" "B.Cu") (net 15))
  (segment (start 141.055 105.25) (end 144.81 109.005) (width 0.125) (layer "In2.Cu") (net 15))
  (segment (start 125.65 105.25) (end 141.055 105.25) (width 0.125) (layer "In2.Cu") (net 15))
  (segment (start 123.5 107.4) (end 125.65 105.25) (width 0.125) (layer "In2.Cu") (net 15))
  (segment (start 144.81 109.005) (end 144.81 111.48) (width 0.125) (layer "In2.Cu") (net 15))
  (segment (start 122.5 117.9) (end 123 118.4) (width 0.1) (layer "F.Cu") (net 16))
  (segment (start 143 130.75) (end 143 130.235) (width 0.1) (layer "F.Cu") (net 16))
  (segment (start 140.205 117.515) (end 138.64 119.08) (width 0.1) (layer "F.Cu") (net 16))
  (segment (start 140.48 121.61) (end 140.494994 121.61) (width 0.1) (layer "F.Cu") (net 16))
  (segment (start 143 131.265) (end 143 130.75) (width 0.1) (layer "F.Cu") (net 16))
  (segment (start 138.64 119.08) (end 138.64 119.77) (width 0.1) (layer "F.Cu") (net 16))
  (segment (start 138.64 119.77) (end 140.48 121.61) (width 0.1) (layer "F.Cu") (net 16))
  (segment (start 142.645 117.515) (end 140.205 117.515) (width 0.1) (layer "F.Cu") (net 16))
  (via (at 123 118.4) (size 0.55) (drill 0.15) (layers "F.Cu" "B.Cu") (net 16))
  (via (at 140.494994 121.61) (size 0.55) (drill 0.15) (layers "F.Cu" "B.Cu") (net 16))
  (via (at 143 130.75) (size 0.55) (drill 0.15) (layers "F.Cu" "B.Cu") (net 16))
  (segment (start 123 123.035) (end 123 118.4) (width 0.125) (layer "In2.Cu") (net 16))
  (segment (start 140.494994 123.264006) (end 139.888 123.871) (width 0.125) (layer "In2.Cu") (net 16))
  (segment (start 123.836 123.871) (end 123 123.035) (width 0.125) (layer "In2.Cu") (net 16))
  (segment (start 140.494994 121.61) (end 140.494994 123.264006) (width 0.125) (layer "In2.Cu") (net 16))
  (segment (start 139.888 123.871) (end 123.836 123.871) (width 0.125) (layer "In2.Cu") (net 16))
  (segment (start 143 124.115006) (end 140.494994 121.61) (width 0.1) (layer "B.Cu") (net 16))
  (segment (start 143 130.75) (end 143 124.115006) (width 0.1) (layer "B.Cu") (net 16))
  (segment (start 122.5 116.9) (end 123 117.4) (width 0.1) (layer "F.Cu") (net 17))
  (segment (start 141.37 121.28) (end 141.37 121.57) (width 0.1) (layer "F.Cu") (net 17))
  (segment (start 139.52 119.06) (end 139.52 119.43) (width 0.1) (layer "F.Cu") (net 17))
  (segment (start 139.52 119.43) (end 141.37 121.28) (width 0.1) (layer "F.Cu") (net 17))
  (segment (start 140.415 118.165) (end 139.52 119.06) (width 0.1) (layer "F.Cu") (net 17))
  (segment (start 144.25 130.75) (end 144.25 130.235) (width 0.1) (layer "F.Cu") (net 17))
  (segment (start 142.645 118.165) (end 140.415 118.165) (width 0.1) (layer "F.Cu") (net 17))
  (segment (start 144.25 131.265) (end 144.25 130.75) (width 0.1) (layer "F.Cu") (net 17))
  (via (at 123 117.4) (size 0.55) (drill 0.15) (layers "F.Cu" "B.Cu") (net 17))
  (via (at 144.25 130.75) (size 0.55) (drill 0.15) (layers "F.Cu" "B.Cu") (net 17))
  (via (at 141.37 121.57) (size 0.55) (drill 0.15) (layers "F.Cu" "B.Cu") (net 17))
  (segment (start 122.53 117.87) (end 122.53 123.05) (width 0.125) (layer "In2.Cu") (net 17))
  (segment (start 123 117.4) (end 122.53 117.87) (width 0.125) (layer "In2.Cu") (net 17))
  (segment (start 123.611 124.131) (end 140.579 124.131) (width 0.125) (layer "In2.Cu") (net 17))
  (segment (start 140.579 124.131) (end 141.37 123.34) (width 0.125) (layer "In2.Cu") (net 17))
  (segment (start 122.53 123.05) (end 123.611 124.131) (width 0.125) (layer "In2.Cu") (net 17))
  (segment (start 141.37 123.34) (end 141.37 121.57) (width 0.125) (layer "In2.Cu") (net 17))
  (segment (start 144.25 124.45) (end 141.37 121.57) (width 0.1) (layer "B.Cu") (net 17))
  (segment (start 144.25 130.75) (end 144.25 124.45) (width 0.1) (layer "B.Cu") (net 17))
  (segment (start 123.5 116.9) (end 124 117.4) (width 0.1) (layer "F.Cu") (net 18))
  (segment (start 145.5 130.75) (end 145.5 130.235) (width 0.1) (layer "F.Cu") (net 18))
  (segment (start 142.245 119.215) (end 142.245 121.465) (width 0.1) (layer "F.Cu") (net 18))
  (segment (start 145.5 131.265) (end 145.5 130.75) (width 0.1) (layer "F.Cu") (net 18))
  (segment (start 142.645 118.815) (end 142.245 119.215) (width 0.1) (layer "F.Cu") (net 18))
  (via (at 124 117.4) (size 0.55) (drill 0.15) (layers "F.Cu" "B.Cu") (net 18))
  (via (at 142.245 121.465) (size 0.55) (drill 0.15) (layers "F.Cu" "B.Cu") (net 18))
  (via (at 145.5 130.75) (size 0.55) (drill 0.15) (layers "F.Cu" "B.Cu") (net 18))
  (segment (start 126.885 121.81) (end 124.47 119.395) (width 0.125) (layer "In2.Cu") (net 18))
  (segment (start 124.47 119.395) (end 124.47 117.87) (width 0.125) (layer "In2.Cu") (net 18))
  (segment (start 140.735 119.62) (end 138.545 121.81) (width 0.125) (layer "In2.Cu") (net 18))
  (segment (start 124 117.4) (end 124.47 117.87) (width 0.125) (layer "In2.Cu") (net 18))
  (segment (start 142.245 121.465) (end 142.245 120.555) (width 0.125) (layer "In2.Cu") (net 18))
  (segment (start 141.31 119.62) (end 140.735 119.62) (width 0.125) (layer "In2.Cu") (net 18))
  (segment (start 138.545 121.81) (end 126.885 121.81) (width 0.125) (layer "In2.Cu") (net 18))
  (segment (start 142.245 120.555) (end 141.31 119.62) (width 0.125) (layer "In2.Cu") (net 18))
  (segment (start 145.5 130.75) (end 145.5 126.25) (width 0.1) (layer "B.Cu") (net 18))
  (segment (start 144.75 125.5) (end 144.75 123.97) (width 0.1) (layer "B.Cu") (net 18))
  (segment (start 144.75 123.97) (end 142.245 121.465) (width 0.1) (layer "B.Cu") (net 18))
  (segment (start 145.5 126.25) (end 144.75 125.5) (width 0.1) (layer "B.Cu") (net 18))
  (segment (start 120.5 111.9) (end 120 111.4) (width 0.15) (layer "F.Cu") (net 19))
  (segment (start 120 111.4) (end 120 108.9) (width 0.15) (layer "F.Cu") (net 19))
  (segment (start 122.5125 102.0915) (end 122.5125 96.989) (width 0.15) (layer "F.Cu") (net 19))
  (segment (start 144.92 118.49) (end 145.245 118.165) (width 0.1) (layer "F.Cu") (net 19))
  (segment (start 144.92 120.41) (end 144.92 118.49) (width 0.1) (layer "F.Cu") (net 19))
  (segment (start 121.204 103.4) (end 122.5125 102.0915) (width 0.15) (layer "F.Cu") (net 19))
  (segment (start 144.815 120.515) (end 144.92 120.41) (width 0.1) (layer "F.Cu") (net 19))
  (segment (start 120.245 103.4) (end 121.204 103.4) (width 0.15) (layer "F.Cu") (net 19))
  (via (at 140.95 120.17001) (size 0.55) (drill 0.15) (layers "F.Cu" "B.Cu") (net 19))
  (via (at 144.815 120.515) (size 0.55) (drill 0.15) (layers "F.Cu" "B.Cu") (net 19))
  (via (at 120 108.9) (size 0.55) (drill 0.15) (layers "F.Cu" "B.Cu") (net 19))
  (via (at 120.245 103.4) (size 0.55) (drill 0.15) (layers "F.Cu" "B.Cu") (net 19))
  (segment (start 120.245 103.4) (end 120 103.645) (width 0.125) (layer "In2.Cu") (net 19))
  (segment (start 123.5 115.79) (end 123.5 118.806) (width 0.125) (layer "In2.Cu") (net 19))
  (segment (start 122.99 115.28) (end 123.5 115.79) (width 0.125) (layer "In2.Cu") (net 19))
  (segment (start 120 103.645) (end 120 108.9) (width 0.125) (layer "In2.Cu") (net 19))
  (segment (start 120 110.551) (end 121.25 111.801) (width 0.125) (layer "In2.Cu") (net 19))
  (segment (start 121.25 114.75) (end 121.78 115.28) (width 0.125) (layer "In2.Cu") (net 19))
  (segment (start 126.754011 122.060011) (end 138.712989 122.060011) (width 0.125) (layer "In2.Cu") (net 19))
  (segment (start 121.78 115.28) (end 122.99 115.28) (width 0.125) (layer "In2.Cu") (net 19))
  (segment (start 138.712989 122.060011) (end 140.60299 120.17001) (width 0.125) (layer "In2.Cu") (net 19))
  (segment (start 120 108.9) (end 120 110.551) (width 0.125) (layer "In2.Cu") (net 19))
  (segment (start 123.5 118.806) (end 126.754011 122.060011) (width 0.125) (layer "In2.Cu") (net 19))
  (segment (start 140.60299 120.17001) (end 140.95 120.17001) (width 0.125) (layer "In2.Cu") (net 19))
  (segment (start 121.25 111.801) (end 121.25 114.75) (width 0.125) (layer "In2.Cu") (net 19))
  (segment (start 140.95 120.17001) (end 142.10999 120.17001) (width 0.15) (layer "B.Cu") (net 19))
  (segment (start 143.95 119.65) (end 144.815 120.515) (width 0.15) (layer "B.Cu") (net 19))
  (segment (start 142.10999 120.17001) (end 142.63 119.65) (width 0.15) (layer "B.Cu") (net 19))
  (segment (start 142.63 119.65) (end 143.95 119.65) (width 0.15) (layer "B.Cu") (net 19))
  (segment (start 121.5 111.9) (end 121 111.4) (width 0.15) (layer "F.Cu") (net 20))
  (segment (start 129 108.66) (end 128.919999 108.740001) (width 0.15) (layer "F.Cu") (net 20))
  (segment (start 129 107.885) (end 129 108.66) (width 0.15) (layer "F.Cu") (net 20))
  (segment (start 129 107.885) (end 130 107.885) (width 0.15) (layer "F.Cu") (net 20))
  (segment (start 121 111.4) (end 121 108.9) (width 0.15) (layer "F.Cu") (net 20))
  (segment (start 124.341 102.309) (end 124.341 97.001) (width 0.15) (layer "F.Cu") (net 20))
  (segment (start 123.25 103.4) (end 124.341 102.309) (width 0.15) (layer "F.Cu") (net 20))
  (via (at 128.919999 108.740001) (size 0.55) (drill 0.15) (layers "F.Cu" "B.Cu") (net 20))
  (via (at 123.25 103.4) (size 0.55) (drill 0.15) (layers "F.Cu" "B.Cu") (net 20))
  (via (at 121 108.9) (size 0.55) (drill 0.15) (layers "F.Cu" "B.Cu") (net 20))
  (segment (start 123.25 103.4) (end 121 105.65) (width 0.125) (layer "In2.Cu") (net 20))
  (segment (start 121 108.9) (end 128.76 108.9) (width 0.125) (layer "In2.Cu") (net 20))
  (segment (start 128.76 108.9) (end 128.919999 108.740001) (width 0.125) (layer "In2.Cu") (net 20))
  (segment (start 121 105.65) (end 121 108.9) (width 0.125) (layer "In2.Cu") (net 20))
  (segment (start 120.5 112.9) (end 120 112.4) (width 0.1) (layer "F.Cu") (net 21))
  (segment (start 118.75 103.4) (end 120.696 101.454) (width 0.15) (layer "F.Cu") (net 21))
  (segment (start 145.245 118.815) (end 145.245 120.405) (width 0.1) (layer "F.Cu") (net 21))
  (segment (start 145.995 121.155) (end 145.995 124.038) (width 0.1) (layer "F.Cu") (net 21))
  (segment (start 145.339 124.694) (end 145.995 124.038) (width 0.1) (layer "F.Cu") (net 21))
  (segment (start 145.245 120.405) (end 145.995 121.155) (width 0.1) (layer "F.Cu") (net 21))
  (segment (start 120.696 101.454) (end 120.696 96.989) (width 0.15) (layer "F.Cu") (net 21))
  (via (at 120 112.4) (size 0.55) (drill 0.15) (layers "F.Cu" "B.Cu") (net 21))
  (via (at 118.75 103.4) (size 0.55) (drill 0.15) (layers "F.Cu" "B.Cu") (net 21))
  (via (at 145.339 124.694) (size 0.55) (drill 0.15) (layers "F.Cu" "B.Cu") (net 21))
  (segment (start 144.852 125.181) (end 145.339 124.694) (width 0.125) (layer "In2.Cu") (net 21))
  (segment (start 121.021 125.181) (end 144.852 125.181) (width 0.125) (layer "In2.Cu") (net 21))
  (segment (start 120.450001 114.799999) (end 119.315 115.935) (width 0.125) (layer "In2.Cu") (net 21))
  (segment (start 120.450001 112.850001) (end 120.450001 114.799999) (width 0.125) (layer "In2.Cu") (net 21))
  (segment (start 118.5 108.25) (end 119 107.75) (width 0.125) (layer "In2.Cu") (net 21))
  (segment (start 117 116.733998) (end 117 121.16) (width 0.125) (layer "In2.Cu") (net 21))
  (segment (start 117.798998 115.935) (end 117 116.733998) (width 0.125) (layer "In2.Cu") (net 21))
  (segment (start 120 112.4) (end 120.450001 112.850001) (width 0.125) (layer "In2.Cu") (net 21))
  (segment (start 119 107.75) (end 119 103.65) (width 0.125) (layer "In2.Cu") (net 21))
  (segment (start 119 103.65) (end 118.75 103.4) (width 0.125) (layer "In2.Cu") (net 21))
  (segment (start 119.315 115.935) (end 117.798998 115.935) (width 0.125) (layer "In2.Cu") (net 21))
  (segment (start 117 121.16) (end 121.021 125.181) (width 0.125) (layer "In2.Cu") (net 21))
  (segment (start 120 111.9) (end 118.5 110.4) (width 0.125) (layer "In2.Cu") (net 21))
  (segment (start 120 112.4) (end 120 111.9) (width 0.125) (layer "In2.Cu") (net 21))
  (segment (start 118.5 110.4) (end 118.5 108.25) (width 0.125) (layer "In2.Cu") (net 21))
  (segment (start 121.5 112.9) (end 122 112.4) (width 0.1) (layer "F.Cu") (net 22))
  (segment (start 146.94 121.19) (end 145.895 120.145) (width 0.1) (layer "F.Cu") (net 22))
  (segment (start 145.895 120.145) (end 145.895 118.815) (width 0.1) (layer "F.Cu") (net 22))
  (via (at 122 112.4) (size 0.55) (drill 0.15) (layers "F.Cu" "B.Cu") (net 22))
  (via (at 120.49 104.99) (size 0.55) (drill 0.15) (layers "F.Cu" "B.Cu") (net 22))
  (via (at 134.75 107.16) (size 0.55) (drill 0.15) (layers "F.Cu" "B.Cu") (net 22))
  (via (at 146.94 121.19) (size 0.55) (drill 0.15) (layers "F.Cu" "B.Cu") (net 22))
  (segment (start 146.884999 121.134999) (end 143.274999 121.134999) (width 0.125) (layer "In2.Cu") (net 22))
  (segment (start 124 115) (end 122.79 115) (width 0.125) (layer "In2.Cu") (net 22))
  (segment (start 128.08 121.56) (end 124.75 118.23) (width 0.125) (layer "In2.Cu") (net 22))
  (segment (start 138.406 121.56) (end 128.08 121.56) (width 0.125) (layer "In2.Cu") (net 22))
  (segment (start 122 112.4) (end 122.5 112.9) (width 0.125) (layer "In2.Cu") (net 22))
  (segment (start 140.666 119.3) (end 138.406 121.56) (width 0.125) (layer "In2.Cu") (net 22))
  (segment (start 143.274999 121.134999) (end 141.44 119.3) (width 0.125) (layer "In2.Cu") (net 22))
  (segment (start 141.44 119.3) (end 140.666 119.3) (width 0.125) (layer "In2.Cu") (net 22))
  (segment (start 120.49 110.248) (end 120.49 104.99) (width 0.125) (layer "In2.Cu") (net 22))
  (segment (start 122.5 114.71) (end 122.5 112.9) (width 0.125) (layer "In2.Cu") (net 22))
  (segment (start 146.94 121.19) (end 146.884999 121.134999) (width 0.125) (layer "In2.Cu") (net 22))
  (segment (start 124.75 115.75) (end 124 115) (width 0.125) (layer "In2.Cu") (net 22))
  (segment (start 122 112.4) (end 122 111.758) (width 0.125) (layer "In2.Cu") (net 22))
  (segment (start 124.75 118.23) (end 124.75 115.75) (width 0.125) (layer "In2.Cu") (net 22))
  (segment (start 122.79 115) (end 122.5 114.71) (width 0.125) (layer "In2.Cu") (net 22))
  (segment (start 122 111.758) (end 120.49 110.248) (width 0.125) (layer "In2.Cu") (net 22))
  (segment (start 133.8 104.99) (end 120.49 104.99) (width 0.125) (layer "In3.Cu") (net 22))
  (segment (start 134.75 107.16) (end 134.75 105.94) (width 0.125) (layer "In3.Cu") (net 22))
  (segment (start 134.75 105.94) (end 133.8 104.99) (width 0.125) (layer "In3.Cu") (net 22))
  (segment (start 134.75 107.16) (end 134.165 107.16) (width 0.125) (layer "B.Cu") (net 22))
  (segment (start 120.5 117.9) (end 120 118.4) (width 0.1) (layer "F.Cu") (net 23))
  (segment (start 143.995 121.11) (end 144.495 121.61) (width 0.1) (layer "F.Cu") (net 23))
  (segment (start 144.595 118.165) (end 144.27 118.49) (width 0.1) (layer "F.Cu") (net 23))
  (segment (start 144.27 118.49) (end 144.27 119.9575) (width 0.1) (layer "F.Cu") (net 23))
  (segment (start 144.27 119.9575) (end 143.995 120.2325) (width 0.1) (layer "F.Cu") (net 23))
  (segment (start 143.995 120.2325) (end 143.995 121.11) (width 0.1) (layer "F.Cu") (net 23))
  (segment (start 148 131.265) (end 148 130.75) (width 0.1) (layer "F.Cu") (net 23))
  (segment (start 148 130.75) (end 148 130.22) (width 0.1) (layer "F.Cu") (net 23))
  (via (at 120 118.4) (size 0.55) (drill 0.15) (layers "F.Cu" "B.Cu") (net 23))
  (via (at 148 130.75) (size 0.55) (drill 0.15) (layers "F.Cu" "B.Cu") (net 23))
  (via (at 144.495 121.61) (size 0.55) (drill 0.15) (layers "F.Cu" "B.Cu") (net 23))
  (segment (start 120 122.89) (end 121.51 124.4) (width 0.125) (layer "In2.Cu") (net 23))
  (segment (start 141.705 124.4) (end 144.495 121.61) (width 0.125) (layer "In2.Cu") (net 23))
  (segment (start 121.51 124.4) (end 141.705 124.4) (width 0.125) (layer "In2.Cu") (net 23))
  (segment (start 120 118.4) (end 120 122.89) (width 0.125) (layer "In2.Cu") (net 23))
  (segment (start 148 130.75) (end 148 125.75) (width 0.1) (layer "B.Cu") (net 23))
  (segment (start 144.495 122.245) (end 144.495 121.61) (width 0.1) (layer "B.Cu") (net 23))
  (segment (start 148 125.75) (end 144.495 122.245) (width 0.1) (layer "B.Cu") (net 23))
  (segment (start 118.5 116.9) (end 118 117.4) (width 0.1) (layer "F.Cu") (net 24))
  (segment (start 144.27 120.74) (end 144.27 120.29) (width 0.1) (layer "F.Cu") (net 24))
  (segment (start 145.15 121.62) (end 144.27 120.74) (width 0.1) (layer "F.Cu") (net 24))
  (segment (start 145.36 121.62) (end 145.15 121.62) (width 0.1) (layer "F.Cu") (net 24))
  (segment (start 144.27 120.29) (end 144.595 119.965) (width 0.1) (layer "F.Cu") (net 24))
  (segment (start 149.25 130.75) (end 149.25 130.235) (width 0.1) (layer "F.Cu") (net 24))
  (segment (start 144.595 119.965) (end 144.595 118.815) (width 0.1) (layer "F.Cu") (net 24))
  (segment (start 149.25 131.265) (end 149.25 130.75) (width 0.1) (layer "F.Cu") (net 24))
  (via (at 118 117.4) (size 0.55) (drill 0.15) (layers "F.Cu" "B.Cu") (net 24))
  (via (at 149.25 130.75) (size 0.55) (drill 0.15) (layers "F.Cu" "B.Cu") (net 24))
  (via (at 145.36 121.62) (size 0.55) (drill 0.15) (layers "F.Cu" "B.Cu") (net 24))
  (segment (start 118 117.4) (end 118.450001 117.850001) (width 0.125) (layer "In2.Cu") (net 24))
  (segment (start 142.34 124.65) (end 121.371076 124.65) (width 0.125) (layer "In2.Cu") (net 24))
  (segment (start 145.36 121.62) (end 145.36 121.63) (width 0.125) (layer "In2.Cu") (net 24))
  (segment (start 121.371076 124.65) (end 118.450001 121.728925) (width 0.125) (layer "In2.Cu") (net 24))
  (segment (start 145.36 121.63) (end 142.34 124.65) (width 0.125) (layer "In2.Cu") (net 24))
  (segment (start 118.450001 121.728925) (end 118.450001 117.850001) (width 0.125) (layer "In2.Cu") (net 24))
  (segment (start 145.36 122.36) (end 145.36 121.62) (width 0.1) (layer "B.Cu") (net 24))
  (segment (start 149.25 130.75) (end 149.25 126.25) (width 0.1) (layer "B.Cu") (net 24))
  (segment (start 149.25 126.25) (end 145.36 122.36) (width 0.1) (layer "B.Cu") (net 24))
  (segment (start 131.080412 133.08) (end 132.125206 134.124794) (width 0.15) (layer "F.Cu") (net 25))
  (segment (start 130.525 133.08) (end 131.080412 133.08) (width 0.15) (layer "F.Cu") (net 25))
  (via (at 132.125206 134.124794) (size 0.55) (drill 0.15) (layers "F.Cu" "B.Cu") (net 25))
  (segment (start 131.8 133.799588) (end 132.125206 134.124794) (width 0.15) (layer "B.Cu") (net 25))
  (segment (start 131.8 133.415) (end 131.8 133.799588) (width 0.15) (layer "B.Cu") (net 25))
  (segment (start 116.75 126) (end 116.5 126.25) (width 0.15) (layer "B.Cu") (net 26))
  (segment (start 115.5 134.75) (end 115.96 135.21) (width 0.15) (layer "B.Cu") (net 26))
  (segment (start 116.5 126.25) (end 116.5 131.375) (width 0.15) (layer "B.Cu") (net 26))
  (segment (start 116.5 131.375) (end 115.5 132.375) (width 0.15) (layer "B.Cu") (net 26))
  (segment (start 115.5 132.375) (end 115.5 134.75) (width 0.15) (layer "B.Cu") (net 26))
  (segment (start 116.75 124.485) (end 116.75 126) (width 0.15) (layer "B.Cu") (net 26))
  (segment (start 115.96 135.21) (end 116.8 135.21) (width 0.15) (layer "B.Cu") (net 26))
  (segment (start 107.045 122.23) (end 106.95 122.325) (width 0.54) (layer "F.Cu") (net 27))
  (segment (start 109.96 121.9) (end 108.71 121.9) (width 0.25) (layer "F.Cu") (net 27))
  (segment (start 108.38 122.23) (end 107.045 122.23) (width 0.54) (layer "F.Cu") (net 27))
  (segment (start 108.71 121.9) (end 108.38 122.23) (width 0.25) (layer "F.Cu") (net 27))
  (segment (start 118.749989 132) (end 121.5 132) (width 0.15) (layer "B.Cu") (net 28))
  (segment (start 118.75 124.485) (end 118.75 125) (width 0.15) (layer "B.Cu") (net 28))
  (segment (start 121.5 132) (end 121.88 132.38) (width 0.15) (layer "B.Cu") (net 28))
  (segment (start 117.027 126.723) (end 117.027 130.277011) (width 0.15) (layer "B.Cu") (net 28))
  (segment (start 117.027 130.277011) (end 118.749989 132) (width 0.15) (layer "B.Cu") (net 28))
  (segment (start 118.75 125) (end 117.027 126.723) (width 0.15) (layer "B.Cu") (net 28))
  (segment (start 121.88 132.38) (end 121.88 133.94) (width 0.15) (layer "B.Cu") (net 28))
  (segment (start 121.88 135.21) (end 121.88 133.94) (width 0.15) (layer "B.Cu") (net 28))
  (segment (start 109.96 121.25) (end 108.41 121.25) (width 0.25) (layer "F.Cu") (net 29))
  (segment (start 106.98 121.07) (end 108.38 121.07) (width 0.54) (layer "F.Cu") (net 29))
  (segment (start 106.765 119.52) (end 106.765 120.855) (width 0.25) (layer "F.Cu") (net 29))
  (segment (start 106.765 120.855) (end 106.98 121.07) (width 0.25) (layer "F.Cu") (net 29))
  (segment (start 123.5 119.9) (end 123.5 121.9) (width 0.15) (layer "F.Cu") (net 30))
  (via (at 123.5 121.9) (size 0.55) (drill 0.15) (layers "F.Cu" "B.Cu") (net 30))
  (segment (start 130.5 121.9) (end 131 122.4) (width 0.15) (layer "B.Cu") (net 30))
  (segment (start 123.5 121.9) (end 130.5 121.9) (width 0.15) (layer "B.Cu") (net 30))
  (segment (start 124 119.4) (end 124 121.4) (width 0.15) (layer "F.Cu") (net 31))
  (segment (start 123.5 118.9) (end 124 119.4) (width 0.15) (layer "F.Cu") (net 31))
  (via (at 124 121.4) (size 0.55) (drill 0.15) (layers "F.Cu" "B.Cu") (net 31))
  (segment (start 124 121.4) (end 131 121.4) (width 0.15) (layer "B.Cu") (net 31))
  (segment (start 124.5 119.9) (end 124.5 120.57) (width 0.15) (layer "F.Cu") (net 32))
  (segment (start 124.5 120.57) (end 124.864 120.934) (width 0.15) (layer "F.Cu") (net 32))
  (segment (start 124.864 120.934) (end 124.867 120.934) (width 0.15) (layer "F.Cu") (net 32))
  (via (at 124.867 120.934) (size 0.55) (drill 0.15) (layers "F.Cu" "B.Cu") (net 32))
  (segment (start 131 120.4) (end 130.466 120.934) (width 0.15) (layer "B.Cu") (net 32))
  (segment (start 124.867 120.934) (end 130.466 120.934) (width 0.15) (layer "B.Cu") (net 32))
  (segment (start 125.5 119.9) (end 126 120.4) (width 0.15) (layer "F.Cu") (net 33))
  (segment (start 126 120.4) (end 126.25 120.4) (width 0.15) (layer "F.Cu") (net 33))
  (via (at 126.25 120.4) (size 0.55) (drill 0.15) (layers "F.Cu" "B.Cu") (net 33))
  (segment (start 131 119.4) (end 130 120.4) (width 0.15) (layer "B.Cu") (net 33))
  (segment (start 130 120.4) (end 126.25 120.4) (width 0.15) (layer "B.Cu") (net 33))
  (segment (start 125.06 119.46) (end 128.36 119.46) (width 0.15) (layer "F.Cu") (net 34))
  (segment (start 124.5 118.9) (end 125.06 119.46) (width 0.15) (layer "F.Cu") (net 34))
  (via (at 128.36 119.46) (size 0.55) (drill 0.15) (layers "F.Cu" "B.Cu") (net 34))
  (segment (start 128.36 119.46) (end 129.94 119.46) (width 0.15) (layer "B.Cu") (net 34))
  (segment (start 131 118.4) (end 129.94 119.46) (width 0.15) (layer "B.Cu") (net 34))
  (segment (start 127.37 118.9) (end 127.39 118.92) (width 0.15) (layer "F.Cu") (net 35))
  (segment (start 125.5 118.9) (end 127.37 118.9) (width 0.15) (layer "F.Cu") (net 35))
  (via (at 127.39 118.92) (size 0.55) (drill 0.15) (layers "F.Cu" "B.Cu") (net 35))
  (segment (start 129.48 118.92) (end 127.39 118.92) (width 0.15) (layer "B.Cu") (net 35))
  (segment (start 131 117.4) (end 129.48 118.92) (width 0.15) (layer "B.Cu") (net 35))
  (segment (start 124.5 117.9) (end 125.009998 118.409998) (width 0.15) (layer "F.Cu") (net 36))
  (segment (start 125.009998 118.409998) (end 128.31 118.409998) (width 0.15) (layer "F.Cu") (net 36))
  (via (at 128.31 118.409998) (size 0.55) (drill 0.15) (layers "F.Cu" "B.Cu") (net 36))
  (segment (start 131 116.4) (end 128.990002 118.409998) (width 0.15) (layer "B.Cu") (net 36))
  (segment (start 128.990002 118.409998) (end 128.31 118.409998) (width 0.15) (layer "B.Cu") (net 36))
  (segment (start 127.31 117.9) (end 127.4 117.81) (width 0.15) (layer "F.Cu") (net 37))
  (segment (start 125.5 117.9) (end 127.31 117.9) (width 0.15) (layer "F.Cu") (net 37))
  (via (at 127.4 117.81) (size 0.55) (drill 0.15) (layers "F.Cu" "B.Cu") (net 37))
  (segment (start 131 115.4) (end 129.81 115.4) (width 0.15) (layer "B.Cu") (net 37))
  (segment (start 127.4 117.81) (end 129.81 115.4) (width 0.15) (layer "B.Cu") (net 37))
  (segment (start 124.5 115.9) (end 125.024999 116.424999) (width 0.15) (layer "F.Cu") (net 38))
  (segment (start 127.175 115.745) (end 127.078996 115.745) (width 0.15) (layer "F.Cu") (net 38))
  (segment (start 127.078996 115.745) (end 126.398997 116.424999) (width 0.15) (layer "F.Cu") (net 38))
  (segment (start 126.398997 116.424999) (end 125.024999 116.424999) (width 0.15) (layer "F.Cu") (net 38))
  (via (at 127.175 115.745) (size 0.55) (drill 0.15) (layers "F.Cu" "B.Cu") (net 38))
  (segment (start 127.175 115.745) (end 127.175 115.725) (width 0.15) (layer "B.Cu") (net 38))
  (segment (start 127.175 115.725) (end 128.5 114.4) (width 0.15) (layer "B.Cu") (net 38))
  (segment (start 128.5 114.4) (end 131 114.4) (width 0.15) (layer "B.Cu") (net 38))
  (segment (start 125.5 115.9) (end 126.000006 115.9) (width 0.15) (layer "F.Cu") (net 39))
  (segment (start 126.000006 115.9) (end 126.5 115.400006) (width 0.15) (layer "F.Cu") (net 39))
  (via (at 126.5 115.400006) (size 0.55) (drill 0.15) (layers "F.Cu" "B.Cu") (net 39))
  (segment (start 126.5 115.400006) (end 128.500006 113.4) (width 0.15) (layer "B.Cu") (net 39))
  (segment (start 131 113.4) (end 128.500006 113.4) (width 0.15) (layer "B.Cu") (net 39))
  (segment (start 119.5 106.885) (end 118.5 106.885) (width 0.15) (layer "F.Cu") (net 40))
  (segment (start 118.5 110.9) (end 118.5 106.885) (width 0.15) (layer "F.Cu") (net 40))
  (segment (start 127.875 116.301004) (end 129.236 117.662004) (width 0.15) (layer "F.Cu") (net 41))
  (segment (start 141.75 131.265) (end 141.75 130.75) (width 0.1) (layer "F.Cu") (net 41))
  (segment (start 129.236 117.662004) (end 129.236 119.736) (width 0.15) (layer "F.Cu") (net 41))
  (segment (start 138.014 120.169) (end 139.664 121.819) (width 0.15) (layer "F.Cu") (net 41))
  (segment (start 141.75 130.75) (end 141.75 130.235) (width 0.1) (layer "F.Cu") (net 41))
  (segment (start 127.875 116.22) (end 127.875 116.301004) (width 0.15) (layer "F.Cu") (net 41))
  (segment (start 129.236 119.736) (end 129.669 120.169) (width 0.15) (layer "F.Cu") (net 41))
  (segment (start 129.669 120.169) (end 138.014 120.169) (width 0.15) (layer "F.Cu") (net 41))
  (segment (start 123.996295 118.396295) (end 124.003705 118.396295) (width 0.15) (layer "F.Cu") (net 41))
  (segment (start 143.502 120.442644) (end 143.502 120.627) (width 0.1) (layer "F.Cu") (net 41))
  (segment (start 143.945 118.815) (end 143.945 119.999644) (width 0.1) (layer "F.Cu") (net 41))
  (segment (start 143.945 119.999644) (end 143.502 120.442644) (width 0.1) (layer "F.Cu") (net 41))
  (segment (start 123.5 117.9) (end 123.996295 118.396295) (width 0.15) (layer "F.Cu") (net 41))
  (via (at 127.875 116.22) (size 0.55) (drill 0.15) (layers "F.Cu" "B.Cu") (net 41))
  (via (at 139.664 121.819) (size 0.55) (drill 0.15) (layers "F.Cu" "B.Cu") (net 41))
  (via (at 124.003705 118.396295) (size 0.55) (drill 0.15) (layers "F.Cu" "B.Cu") (net 41))
  (via (at 141.75 130.75) (size 0.55) (drill 0.15) (layers "F.Cu" "B.Cu") (net 41))
  (via (at 143.502 120.627) (size 0.55) (drill 0.15) (layers "F.Cu" "B.Cu") (net 41))
  (segment (start 127.875 116.22) (end 126.52 116.22) (width 0.15) (layer "In3.Cu") (net 41))
  (segment (start 124.343705 118.396295) (end 124.003705 118.396295) (width 0.15) (layer "In3.Cu") (net 41))
  (segment (start 126.52 116.22) (end 124.343705 118.396295) (width 0.15) (layer "In3.Cu") (net 41))
  (segment (start 141.75 123.905) (end 139.664 121.819) (width 0.1) (layer "B.Cu") (net 41))
  (segment (start 143.502 120.627) (end 140.467092 120.627) (width 0.15) (layer "B.Cu") (net 41))
  (segment (start 139.664 121.430092) (end 139.664 121.819) (width 0.15) (layer "B.Cu") (net 41))
  (segment (start 140.467092 120.627) (end 139.664 121.430092) (width 0.15) (layer "B.Cu") (net 41))
  (segment (start 141.75 130.75) (end 141.75 123.905) (width 0.1) (layer "B.Cu") (net 41))
  (segment (start 123.5 115.9) (end 124 116.4) (width 0.15) (layer "F.Cu") (net 42))
  (segment (start 132.355 126.275) (end 132.35 126.27) (width 0.15) (layer "F.Cu") (net 42))
  (segment (start 133.575 126.275) (end 132.355 126.275) (width 0.15) (layer "F.Cu") (net 42))
  (via (at 124 116.4) (size 0.55) (drill 0.15) (layers "F.Cu" "B.Cu") (net 42))
  (via (at 132.35 126.27) (size 0.55) (drill 0.15) (layers "F.Cu" "B.Cu") (net 42))
  (segment (start 123.83 123.88) (end 124.94 124.99) (width 0.15) (layer "B.Cu") (net 42))
  (segment (start 131.832499 126.787501) (end 132.35 126.27) (width 0.15) (layer "B.Cu") (net 42))
  (segment (start 124.94 124.99) (end 124.94 126.112496) (width 0.15) (layer "B.Cu") (net 42))
  (segment (start 123.549999 116.850001) (end 123.549999 119.690001) (width 0.15) (layer "B.Cu") (net 42))
  (segment (start 123.06 123.88) (end 123.83 123.88) (width 0.15) (layer "B.Cu") (net 42))
  (segment (start 125.615005 126.787501) (end 131.832499 126.787501) (width 0.15) (layer "B.Cu") (net 42))
  (segment (start 123.549999 119.690001) (end 122.37 120.87) (width 0.15) (layer "B.Cu") (net 42))
  (segment (start 124 116.4) (end 123.549999 116.850001) (width 0.15) (layer "B.Cu") (net 42))
  (segment (start 124.94 126.112496) (end 125.615005 126.787501) (width 0.15) (layer "B.Cu") (net 42))
  (segment (start 122.37 123.19) (end 123.06 123.88) (width 0.15) (layer "B.Cu") (net 42))
  (segment (start 122.37 120.87) (end 122.37 123.19) (width 0.15) (layer "B.Cu") (net 42))
  (segment (start 123.5 114.9) (end 124 114.4) (width 0.15) (layer "F.Cu") (net 43))
  (segment (start 126.475 126.275) (end 126.47 126.28) (width 0.15) (layer "F.Cu") (net 43))
  (segment (start 127.925 126.275) (end 126.475 126.275) (width 0.15) (layer "F.Cu") (net 43))
  (via (at 124 114.4) (size 0.55) (drill 0.15) (layers "F.Cu" "B.Cu") (net 43))
  (via (at 126.47 126.28) (size 0.55) (drill 0.15) (layers "F.Cu" "B.Cu") (net 43))
  (segment (start 123.99 123.61) (end 125.24 124.86) (width 0.15) (layer "B.Cu") (net 43))
  (segment (start 125.6 118.1) (end 122.660011 121.039989) (width 0.15) (layer "B.Cu") (net 43))
  (segment (start 122.660011 121.039989) (end 122.660011 123.070011) (width 0.15) (layer "B.Cu") (net 43))
  (segment (start 125.54 126.28) (end 126.47 126.28) (width 0.15) (layer "B.Cu") (net 43))
  (segment (start 125.24 124.86) (end 125.24 125.98) (width 0.15) (layer "B.Cu") (net 43))
  (segment (start 124 114.4) (end 125.6 116) (width 0.15) (layer "B.Cu") (net 43))
  (segment (start 125.24 125.98) (end 125.54 126.28) (width 0.15) (layer "B.Cu") (net 43))
  (segment (start 122.660011 123.070011) (end 123.2 123.61) (width 0.15) (layer "B.Cu") (net 43))
  (segment (start 123.2 123.61) (end 123.99 123.61) (width 0.15) (layer "B.Cu") (net 43))
  (segment (start 125.6 116) (end 125.6 118.1) (width 0.15) (layer "B.Cu") (net 43))
  (segment (start 123.5 113.9) (end 124 113.4) (width 0.1) (layer "F.Cu") (net 44))
  (segment (start 146.22 119.86) (end 146.22 118.49) (width 0.1) (layer "F.Cu") (net 44))
  (segment (start 151.75 131.28) (end 151.75 130.75) (width 0.1) (layer "F.Cu") (net 44))
  (segment (start 146.22 118.49) (end 146.545 118.165) (width 0.1) (layer "F.Cu") (net 44))
  (segment (start 147.41 121.74) (end 147.41 121.05) (width 0.1) (layer "F.Cu") (net 44))
  (segment (start 147.41 121.05) (end 146.22 119.86) (width 0.1) (layer "F.Cu") (net 44))
  (segment (start 151.75 130.75) (end 151.75 130.235) (width 0.1) (layer "F.Cu") (net 44))
  (via (at 124 113.4) (size 0.55) (drill 0.15) (layers "F.Cu" "B.Cu") (net 44))
  (via (at 151.75 130.75) (size 0.55) (drill 0.15) (layers "F.Cu" "B.Cu") (net 44))
  (via (at 147.41 121.74) (size 0.55) (drill 0.15) (layers "F.Cu" "B.Cu") (net 44))
  (segment (start 147.41 120.96) (end 146.24 119.79) (width 0.125) (layer "In2.Cu") (net 44))
  (segment (start 124.2 113.4) (end 124 113.4) (width 0.125) (layer "In2.Cu") (net 44))
  (segment (start 133.941 121.06) (end 128.35 121.06) (width 0.125) (layer "In2.Cu") (net 44))
  (segment (start 128.35 121.06) (end 125.300011 118.010011) (width 0.125) (layer "In2.Cu") (net 44))
  (segment (start 136.621 118.38) (end 133.941 121.06) (width 0.125) (layer "In2.Cu") (net 44))
  (segment (start 143.075024 118.38) (end 136.621 118.38) (width 0.125) (layer "In2.Cu") (net 44))
  (segment (start 125.300011 118.010011) (end 125.300011 114.500011) (width 0.125) (layer "In2.Cu") (net 44))
  (segment (start 147.41 121.74) (end 147.41 120.96) (width 0.125) (layer "In2.Cu") (net 44))
  (segment (start 125.300011 114.500011) (end 124.2 113.4) (width 0.125) (layer "In2.Cu") (net 44))
  (segment (start 146.24 119.79) (end 144.485024 119.79) (width 0.125) (layer "In2.Cu") (net 44))
  (segment (start 144.485024 119.79) (end 143.075024 118.38) (width 0.125) (layer "In2.Cu") (net 44))
  (segment (start 147.41 122.91) (end 147.41 121.74) (width 0.1) (layer "B.Cu") (net 44))
  (segment (start 151.75 130.75) (end 151.75 127.25) (width 0.1) (layer "B.Cu") (net 44))
  (segment (start 151.75 127.25) (end 147.41 122.91) (width 0.1) (layer "B.Cu") (net 44))
  (segment (start 122.5 115.9) (end 123 116.4) (width 0.15) (layer "F.Cu") (net 45))
  (segment (start 124.2 125.49) (end 124.2 125.79) (width 0.15) (layer "F.Cu") (net 45))
  (segment (start 127.925 123.025) (end 126.665 123.025) (width 0.15) (layer "F.Cu") (net 45))
  (segment (start 126.665 123.025) (end 124.2 125.49) (width 0.15) (layer "F.Cu") (net 45))
  (via (at 123 116.4) (size 0.55) (drill 0.15) (layers "F.Cu" "B.Cu") (net 45))
  (via (at 124.2 125.79) (size 0.55) (drill 0.15) (layers "F.Cu" "B.Cu") (net 45))
  (segment (start 122.450001 120.379999) (end 122.1 120.73) (width 0.15) (layer "B.Cu") (net 45))
  (segment (start 124.19 124.61) (end 124.19 125.78) (width 0.15) (layer "B.Cu") (net 45))
  (segment (start 122.94 124.15) (end 123.73 124.15) (width 0.15) (layer "B.Cu") (net 45))
  (segment (start 122.1 123.31) (end 122.94 124.15) (width 0.15) (layer "B.Cu") (net 45))
  (segment (start 122.450001 116.949999) (end 122.450001 120.379999) (width 0.15) (layer "B.Cu") (net 45))
  (segment (start 123 116.4) (end 122.450001 116.949999) (width 0.15) (layer "B.Cu") (net 45))
  (segment (start 122.1 120.73) (end 122.1 123.31) (width 0.15) (layer "B.Cu") (net 45))
  (segment (start 123.73 124.15) (end 124.19 124.61) (width 0.15) (layer "B.Cu") (net 45))
  (segment (start 124.19 125.78) (end 124.2 125.79) (width 0.15) (layer "B.Cu") (net 45))
  (segment (start 122.5 114.9) (end 123 114.4) (width 0.15) (layer "F.Cu") (net 46))
  (segment (start 125.935 125.625) (end 125.83 125.73) (width 0.15) (layer "F.Cu") (net 46))
  (segment (start 127.925 125.625) (end 125.935 125.625) (width 0.15) (layer "F.Cu") (net 46))
  (via (at 123 114.4) (size 0.55) (drill 0.15) (layers "F.Cu" "B.Cu") (net 46))
  (via (at 125.83 125.73) (size 0.55) (drill 0.15) (layers "F.Cu" "B.Cu") (net 46))
  (segment (start 122.95 122.93) (end 123.37 123.35) (width 0.15) (layer "B.Cu") (net 46))
  (segment (start 123.37 123.35) (end 124.2 123.35) (width 0.15) (layer "B.Cu") (net 46))
  (segment (start 123 114.4) (end 123.450001 113.949999) (width 0.15) (layer "B.Cu") (net 46))
  (segment (start 122.95 121.17) (end 122.95 122.93) (width 0.15) (layer "B.Cu") (net 46))
  (segment (start 124.621236 113.949999) (end 125.9 115.228763) (width 0.15) (layer "B.Cu") (net 46))
  (segment (start 125.9 118.22) (end 122.95 121.17) (width 0.15) (layer "B.Cu") (net 46))
  (segment (start 125.83 124.98) (end 125.83 125.73) (width 0.15) (layer "B.Cu") (net 46))
  (segment (start 124.2 123.35) (end 125.83 124.98) (width 0.15) (layer "B.Cu") (net 46))
  (segment (start 123.450001 113.949999) (end 124.621236 113.949999) (width 0.15) (layer "B.Cu") (net 46))
  (segment (start 125.9 115.228763) (end 125.9 118.22) (width 0.15) (layer "B.Cu") (net 46))
  (segment (start 122.5 113.9) (end 123 113.4) (width 0.1) (layer "F.Cu") (net 47))
  (segment (start 143.62 118.49) (end 143.62 119.47) (width 0.1) (layer "F.Cu") (net 47))
  (segment (start 143.945 118.165) (end 143.62 118.49) (width 0.1) (layer "F.Cu") (net 47))
  (segment (start 146.75 130.75) (end 146.75 130.235) (width 0.1) (layer "F.Cu") (net 47))
  (segment (start 142.98 120.11) (end 143.62 119.47) (width 0.1) (layer "F.Cu") (net 47))
  (segment (start 146.75 131.265) (end 146.75 130.75) (width 0.1) (layer "F.Cu") (net 47))
  (via (at 123 113.4) (size 0.55) (drill 0.15) (layers "F.Cu" "B.Cu") (net 47))
  (via (at 142.98 120.11) (size 0.55) (drill 0.15) (layers "F.Cu" "B.Cu") (net 47))
  (via (at 146.75 130.75) (size 0.55) (drill 0.15) (layers "F.Cu" "B.Cu") (net 47))
  (segment (start 141.58 118.71) (end 142.98 120.11) (width 0.125) (layer "In2.Cu") (net 47))
  (segment (start 128.22 121.31) (end 134.07 121.31) (width 0.125) (layer "In2.Cu") (net 47))
  (segment (start 125.01 114.71) (end 125.01 118.1) (width 0.125) (layer "In2.Cu") (net 47))
  (segment (start 136.67 118.71) (end 141.58 118.71) (width 0.125) (layer "In2.Cu") (net 47))
  (segment (start 134.07 121.31) (end 136.67 118.71) (width 0.125) (layer "In2.Cu") (net 47))
  (segment (start 123.51 113.91) (end 124.21 113.91) (width 0.125) (layer "In2.Cu") (net 47))
  (segment (start 123 113.4) (end 123.51 113.91) (width 0.125) (layer "In2.Cu") (net 47))
  (segment (start 124.21 113.91) (end 125.01 114.71) (width 0.125) (layer "In2.Cu") (net 47))
  (segment (start 125.01 118.1) (end 128.22 121.31) (width 0.125) (layer "In2.Cu") (net 47))
  (segment (start 144 122.5) (end 144 120.5) (width 0.1) (layer "B.Cu") (net 47))
  (segment (start 144 120.5) (end 143.61 120.11) (width 0.1) (layer "B.Cu") (net 47))
  (segment (start 143.61 120.11) (end 142.98 120.11) (width 0.1) (layer "B.Cu") (net 47))
  (segment (start 146.75 130.75) (end 146.75 125.25) (width 0.1) (layer "B.Cu") (net 47))
  (segment (start 146.75 125.25) (end 144 122.5) (width 0.1) (layer "B.Cu") (net 47))
  (segment (start 122.75 136.5) (end 118.5 136.5) (width 0.15) (layer "F.Cu") (net 49))
  (segment (start 118 135.28) (end 118.07 135.21) (width 0.15) (layer "F.Cu") (net 49))
  (segment (start 123.25 133.25) (end 123.25 136) (width 0.15) (layer "F.Cu") (net 49))
  (segment (start 119.5 132.5) (end 122.5 132.5) (width 0.15) (layer "F.Cu") (net 49))
  (segment (start 120.5 119.9) (end 120.5 121.5) (width 0.15) (layer "F.Cu") (net 49))
  (segment (start 116.83 125.17) (end 116.83 129.83) (width 0.15) (layer "F.Cu") (net 49))
  (segment (start 122.5 132.5) (end 123.25 133.25) (width 0.15) (layer "F.Cu") (net 49))
  (segment (start 123.25 136) (end 122.75 136.5) (width 0.15) (layer "F.Cu") (net 49))
  (segment (start 118 136) (end 118 135.28) (width 0.15) (layer "F.Cu") (net 49))
  (segment (start 116.83 129.83) (end 119.5 132.5) (width 0.15) (layer "F.Cu") (net 49))
  (segment (start 120.5 121.5) (end 116.83 125.17) (width 0.15) (layer "F.Cu") (net 49))
  (segment (start 118.5 136.5) (end 118 136) (width 0.15) (layer "F.Cu") (net 49))
  (segment (start 119.396432 132.75) (end 122.2525 132.75) (width 0.15) (layer "F.Cu") (net 50))
  (segment (start 116.53 129.883568) (end 119.396432 132.75) (width 0.15) (layer "F.Cu") (net 50))
  (segment (start 122.5 136.25) (end 119.75 136.25) (width 0.15) (layer "F.Cu") (net 50))
  (segment (start 119.75 136.25) (end 119.34 135.84) (width 0.15) (layer "F.Cu") (net 50))
  (segment (start 120 121.5) (end 116.53 124.97) (width 0.15) (layer "F.Cu") (net 50))
  (segment (start 116.53 124.97) (end 116.53 129.883568) (width 0.15) (layer "F.Cu") (net 50))
  (segment (start 123 135.75) (end 122.5 136.25) (width 0.15) (layer "F.Cu") (net 50))
  (segment (start 120 119.4) (end 120 121.5) (width 0.15) (layer "F.Cu") (net 50))
  (segment (start 120.5 118.9) (end 120 119.4) (width 0.15) (layer "F.Cu") (net 50))
  (segment (start 122.2525 132.75) (end 123 133.4975) (width 0.15) (layer "F.Cu") (net 50))
  (segment (start 119.34 135.84) (end 119.34 135.21) (width 0.15) (layer "F.Cu") (net 50))
  (segment (start 123 133.4975) (end 123 135.75) (width 0.15) (layer "F.Cu") (net 50))
  (segment (start 118.07 131.82) (end 118.07 133.94) (width 0.15) (layer "F.Cu") (net 51))
  (segment (start 116.778498 122) (end 116.25 122.528498) (width 0.15) (layer "F.Cu") (net 51))
  (segment (start 118.5 121.53) (end 118.03 122) (width 0.15) (layer "F.Cu") (net 51))
  (segment (start 118.03 122) (end 116.778498 122) (width 0.15) (layer "F.Cu") (net 51))
  (segment (start 116.25 130) (end 118.07 131.82) (width 0.15) (layer "F.Cu") (net 51))
  (segment (start 116.25 122.528498) (end 116.25 130) (width 0.15) (layer "F.Cu") (net 51))
  (segment (start 118.5 119.9) (end 118.5 121.53) (width 0.15) (layer "F.Cu") (net 51))
  (segment (start 115.97 122.28) (end 115.97 130.6) (width 0.15) (layer "F.Cu") (net 52))
  (segment (start 116.5 121.75) (end 115.97 122.28) (width 0.15) (layer "F.Cu") (net 52))
  (segment (start 115.97 130.6) (end 117.21 131.84) (width 0.15) (layer "F.Cu") (net 52))
  (segment (start 118 121.5) (end 117.75 121.75) (width 0.15) (layer "F.Cu") (net 52))
  (segment (start 117.75 121.75) (end 116.5 121.75) (width 0.15) (layer "F.Cu") (net 52))
  (segment (start 118.5 118.9) (end 118 119.4) (width 0.15) (layer "F.Cu") (net 52))
  (segment (start 118 119.4) (end 118 121.5) (width 0.15) (layer "F.Cu") (net 52))
  (via (at 117.21 131.84) (size 0.55) (drill 0.15) (layers "F.Cu" "B.Cu") (net 52))
  (segment (start 117.24 131.84) (end 117.21 131.84) (width 0.15) (layer "B.Cu") (net 52))
  (segment (start 119.34 132.92) (end 118.97 132.55) (width 0.15) (layer "B.Cu") (net 52))
  (segment (start 117.95 132.55) (end 117.24 131.84) (width 0.15) (layer "B.Cu") (net 52))
  (segment (start 118.97 132.55) (end 117.95 132.55) (width 0.15) (layer "B.Cu") (net 52))
  (segment (start 119.34 133.94) (end 119.34 132.92) (width 0.15) (layer "B.Cu") (net 52))
  (segment (start 140.5 130.75) (end 140.5 130.235) (width 0.1) (layer "F.Cu") (net 53))
  (segment (start 137.606482 120.46) (end 138.073241 120.926759) (width 0.15) (layer "F.Cu") (net 53))
  (segment (start 127.615973 116.852349) (end 127.892349 116.852349) (width 0.15) (layer "F.Cu") (net 53))
  (segment (start 128.885 117.845) (end 128.885 119.885) (width 0.15) (layer "F.Cu") (net 53))
  (segment (start 127.892349 116.852349) (end 128.885 117.845) (width 0.15) (layer "F.Cu") (net 53))
  (segment (start 129.46 120.46) (end 137.606482 120.46) (width 0.15) (layer "F.Cu") (net 53))
  (segment (start 140.06 117.19) (end 142.97 117.19) (width 0.1) (layer "F.Cu") (net 53))
  (segment (start 142.97 117.19) (end 143.295 117.515) (width 0.1) (layer "F.Cu") (net 53))
  (segment (start 118.5 117.9) (end 118 118.4) (width 0.15) (layer "F.Cu") (net 53))
  (segment (start 118 118.4) (end 117.974991 118.4) (width 0.15) (layer "F.Cu") (net 53))
  (segment (start 128.885 119.885) (end 129.46 120.46) (width 0.15) (layer "F.Cu") (net 53))
  (segment (start 140.5 131.265) (end 140.5 130.75) (width 0.1) (layer "F.Cu") (net 53))
  (segment (start 139.275 117.78) (end 139.47 117.78) (width 0.1) (layer "F.Cu") (net 53))
  (segment (start 139.47 117.78) (end 140.06 117.19) (width 0.1) (layer "F.Cu") (net 53))
  (via (at 138.073241 120.926759) (size 0.55) (drill 0.15) (layers "F.Cu" "B.Cu") (net 53))
  (via (at 139.275 117.78) (size 0.55) (drill 0.15) (layers "F.Cu" "B.Cu") (net 53))
  (via (at 127.615973 116.852349) (size 0.55) (drill 0.15) (layers "F.Cu" "B.Cu") (net 53))
  (via (at 117.974991 118.4) (size 0.55) (drill 0.15) (layers "F.Cu" "B.Cu") (net 53))
  (via (at 140.5 130.75) (size 0.55) (drill 0.15) (layers "F.Cu" "B.Cu") (net 53))
  (segment (start 125.365 119.14) (end 127.615973 116.889027) (width 0.15) (layer "In3.Cu") (net 53))
  (segment (start 118.714991 119.14) (end 125.365 119.14) (width 0.15) (layer "In3.Cu") (net 53))
  (segment (start 138.073241 118.981759) (end 138.073241 120.926759) (width 0.125) (layer "In3.Cu") (net 53))
  (segment (start 139.275 117.78) (end 138.073241 118.981759) (width 0.125) (layer "In3.Cu") (net 53))
  (segment (start 117.974991 118.4) (end 118.714991 119.14) (width 0.15) (layer "In3.Cu") (net 53))
  (segment (start 127.615973 116.889027) (end 127.615973 116.852349) (width 0.15) (layer "In3.Cu") (net 53))
  (segment (start 138.073241 121.823241) (end 138.073241 120.926759) (width 0.1) (layer "B.Cu") (net 53))
  (segment (start 140.5 124.25) (end 138.073241 121.823241) (width 0.1) (layer "B.Cu") (net 53))
  (segment (start 140.5 130.75) (end 140.5 124.25) (width 0.1) (layer "B.Cu") (net 53))
  (segment (start 150.5 130.75) (end 150.5 130.25) (width 0.1) (layer "F.Cu") (net 54))
  (segment (start 145.57 120.115) (end 146.495 121.04) (width 0.1) (layer "F.Cu") (net 54))
  (segment (start 145.57 120.115) (end 145.57 118.49) (width 0.1) (layer "F.Cu") (net 54))
  (segment (start 117.5 119.9) (end 117.5 120.894236) (width 0.15) (layer "F.Cu") (net 54))
  (segment (start 117.5 120.894236) (end 117.502882 120.897118) (width 0.1) (layer "F.Cu") (net 54))
  (segment (start 145.57 118.49) (end 145.895 118.165) (width 0.1) (layer "F.Cu") (net 54))
  (segment (start 146.495 121.74) (end 146.495 121.04) (width 0.1) (layer "F.Cu") (net 54))
  (segment (start 150.5 131.28) (end 150.5 130.75) (width 0.1) (layer "F.Cu") (net 54))
  (via (at 117.502882 120.897118) (size 0.55) (drill 0.15) (layers "F.Cu" "B.Cu") (net 54))
  (via (at 146.495 121.74) (size 0.55) (drill 0.15) (layers "F.Cu" "B.Cu") (net 54))
  (via (at 150.5 130.75) (size 0.55) (drill 0.15) (layers "F.Cu" "B.Cu") (net 54))
  (segment (start 145.978507 121.74) (end 142.818507 124.9) (width 0.125) (layer "In2.Cu") (net 54))
  (segment (start 117.5 121.25) (end 117.502882 121.247118) (width 0.125) (layer "In2.Cu") (net 54))
  (segment (start 121.15 124.9) (end 117.5 121.25) (width 0.125) (layer "In2.Cu") (net 54))
  (segment (start 117.502882 121.247118) (end 117.502882 120.897118) (width 0.125) (layer "In2.Cu") (net 54))
  (segment (start 146.495 121.74) (end 145.978507 121.74) (width 0.125) (layer "In2.Cu") (net 54))
  (segment (start 142.818507 124.9) (end 121.15 124.9) (width 0.125) (layer "In2.Cu") (net 54))
  (segment (start 150.5 126.75) (end 146.495 122.745) (width 0.1) (layer "B.Cu") (net 54))
  (segment (start 150.5 130.75) (end 150.5 126.75) (width 0.1) (layer "B.Cu") (net 54))
  (segment (start 146.495 122.745) (end 146.495 121.74) (width 0.1) (layer "B.Cu") (net 54))
  (segment (start 139.25 130.75) (end 139.25 130.25) (width 0.1) (layer "F.Cu") (net 55))
  (segment (start 112.25 119) (end 112.25 118.04) (width 0.15) (layer "F.Cu") (net 55))
  (segment (start 139.25 131.295) (end 139.25 130.75) (width 0.1) (layer "F.Cu") (net 55))
  (segment (start 114.91 118.76) (end 113.69 118.76) (width 0.15) (layer "F.Cu") (net 55))
  (segment (start 112.25 118.04) (end 112.26 118.03) (width 0.15) (layer "F.Cu") (net 55))
  (segment (start 113.69 118.76) (end 112.96 118.03) (width 0.15) (layer "F.Cu") (net 55))
  (segment (start 112.96 118.03) (end 112.26 118.03) (width 0.15) (layer "F.Cu") (net 55))
  (segment (start 115.27 118.4) (end 114.91 118.76) (width 0.15) (layer "F.Cu") (net 55))
  (segment (start 117 118.4) (end 115.27 118.4) (width 0.15) (layer "F.Cu") (net 55))
  (segment (start 117.5 118.9) (end 117 118.4) (width 0.15) (layer "F.Cu") (net 55))
  (via (at 139.25 130.75) (size 0.55) (drill 0.15) (layers "F.Cu" "B.Cu") (net 55))
  (via (at 112.26 118.03) (size 0.55) (drill 0.15) (layers "F.Cu" "B.Cu") (net 55))
  (segment (start 114.5 134.75) (end 116.5 136.75) (width 0.1) (layer "B.Cu") (net 55))
  (segment (start 139.25 131.75) (end 139.25 130.75) (width 0.1) (layer "B.Cu") (net 55))
  (segment (start 114.5 127) (end 114.5 134.75) (width 0.1) (layer "B.Cu") (net 55))
  (segment (start 112.26 118.03) (end 111.53 118.03) (width 0.1) (layer "B.Cu") (net 55))
  (segment (start 139.75 134.25) (end 139.75 132.25) (width 0.1) (layer "B.Cu") (net 55))
  (segment (start 110.5 117) (end 109 117) (width 0.1) (layer "B.Cu") (net 55))
  (segment (start 108.5 117.5) (end 108.5 121) (width 0.1) (layer "B.Cu") (net 55))
  (segment (start 116.5 136.75) (end 137.25 136.75) (width 0.1) (layer "B.Cu") (net 55))
  (segment (start 139.75 132.25) (end 139.25 131.75) (width 0.1) (layer "B.Cu") (net 55))
  (segment (start 137.25 136.75) (end 139.75 134.25) (width 0.1) (layer "B.Cu") (net 55))
  (segment (start 109 117) (end 108.5 117.5) (width 0.1) (layer "B.Cu") (net 55))
  (segment (start 111.53 118.03) (end 110.5 117) (width 0.1) (layer "B.Cu") (net 55))
  (segment (start 108.5 121) (end 114.5 127) (width 0.1) (layer "B.Cu") (net 55))
  (segment (start 129 106.915) (end 129 105.15) (width 0.15) (layer "F.Cu") (net 56))
  (segment (start 108.38 119.67) (end 108.38 118.185) (width 0.25) (layer "F.Cu") (net 57))
  (segment (start 110.2 117.785) (end 110.2 118.81) (width 0.15) (layer "F.Cu") (net 57))
  (segment (start 109.91 124.115) (end 109.91 123.328) (width 0.25) (layer "F.Cu") (net 57))
  (segment (start 108.865 124.115) (end 108.38 123.63) (width 0.25) (layer "F.Cu") (net 57))
  (segment (start 114.803 124.284) (end 114.801 124.282) (width 0.15) (layer "F.Cu") (net 57))
  (segment (start 110.215 117.77) (end 110.2 117.785) (width 0.15) (layer "F.Cu") (net 57))
  (segment (start 110.2 118.81) (end 109.96 119.05) (width 0.15) (layer "F.Cu") (net 57))
  (segment (start 109.96 119.05) (end 109.96 119.95) (width 0.15) (layer "F.Cu") (net 57))
  (segment (start 109.25 118.5) (end 108.93 118.18) (width 0.25) (layer "F.Cu") (net 57))
  (segment (start 108.38 118.185) (end 108.375 118.18) (width 0.25) (layer "F.Cu") (net 57))
  (segment (start 114.801 124.282) (end 114.801 123.37) (width 0.15) (layer "F.Cu") (net 57))
  (segment (start 109.25 118.75) (end 109.25 118.5) (width 0.25) (layer "F.Cu") (net 57))
  (segment (start 109.91 124.115) (end 108.865 124.115) (width 0.25) (layer "F.Cu") (net 57))
  (segment (start 110.215 117.77) (end 109.42 117.77) (width 0.15) (layer "F.Cu") (net 57))
  (segment (start 109.91 123.328) (end 109.912 123.326) (width 0.15) (layer "F.Cu") (net 57))
  (segment (start 114.801 123.37) (end 114.8 123.369) (width 0.15) (layer "F.Cu") (net 57))
  (segment (start 108.93 118.18) (end 108.375 118.18) (width 0.25) (layer "F.Cu") (net 57))
  (segment (start 114.803 125.277) (end 114.803 124.284) (width 0.15) (layer "F.Cu") (net 57))
  (via (at 112.75 133) (size 0.55) (drill 0.15) (layers "F.Cu" "B.Cu") (net 57))
  (via (at 109.25 118.75) (size 0.55) (drill 0.15) (layers "F.Cu" "B.Cu") (net 57))
  (via (at 111.75 133) (size 0.55) (drill 0.15) (layers "F.Cu" "B.Cu") (net 57))
  (via (at 109.42 117.77) (size 0.55) (drill 0.15) (layers "F.Cu" "B.Cu") (net 57))
  (via (at 109.912 123.326) (size 0.55) (drill 0.15) (layers "F.Cu" "B.Cu") (net 57))
  (via (at 114.8 123.369) (size 0.55) (drill 0.15) (layers "F.Cu" "B.Cu") (net 57))
  (via (at 113.75 133) (size 0.55) (drill 0.15) (layers "F.Cu" "B.Cu") (net 57))
  (segment (start 113.75 133.79) (end 113.75 133) (width 0.15) (layer "B.Cu") (net 57))
  (segment (start 111.555 118.925) (end 110.4 117.77) (width 0.15) (layer "B.Cu") (net 57))
  (segment (start 112.75 133.79) (end 112.75 133) (width 0.15) (layer "B.Cu") (net 57))
  (segment (start 111.75 133.79) (end 111.75 133) (width 0.15) (layer "B.Cu") (net 57))
  (segment (start 110.4 117.77) (end 109.42 117.77) (width 0.15) (layer "B.Cu") (net 57))
  (segment (start 113.96 118.925) (end 111.555 118.925) (width 0.15) (layer "B.Cu") (net 57))
  (segment (start 146.545 116.215) (end 146.7075 116.215) (width 0.1) (layer "F.Cu") (net 58))
  (segment (start 146.7075 116.215) (end 147.195 116.7025) (width 0.1) (layer "F.Cu") (net 58))
  (via (at 147.195 116.7025) (size 0.55) (drill 0.15) (layers "F.Cu" "B.Cu") (net 58))
  (via (at 149.065 108.375) (size 0.55) (drill 0.15) (layers "F.Cu" "B.Cu") (net 58))
  (segment (start 148.11 107.53) (end 148.11 106.5) (width 0.25) (layer "B.Cu") (net 58))
  (segment (start 147.6925 116.7025) (end 147.97 116.425) (width 0.15) (layer "B.Cu") (net 58))
  (segment (start 147.575 105.965) (end 145.995 105.965) (width 0.25) (layer "B.Cu") (net 58))
  (segment (start 148.1 107.52) (end 148.82 107.52) (width 0.15) (layer "B.Cu") (net 58))
  (segment (start 147.195 116.7025) (end 147.6925 116.7025) (width 0.15) (layer "B.Cu") (net 58))
  (segment (start 149.065 107.765) (end 149.065 108.375) (width 0.15) (layer "B.Cu") (net 58))
  (segment (start 148.82 107.52) (end 149.065 107.765) (width 0.15) (layer "B.Cu") (net 58))
  (segment (start 148.11 106.5) (end 147.575 105.965) (width 0.25) (layer "B.Cu") (net 58))
  (segment (start 144.595 116.865) (end 143.945 117.515) (width 0.25) (layer "F.Cu") (net 59))
  (via (at 143.945 117.515) (size 0.55) (drill 0.15) (layers "F.Cu" "B.Cu") (net 59))
  (via (at 138.513 117.399) (size 0.625) (drill 0.15) (layers "F.Cu" "B.Cu") (net 59))
  (segment (start 139.021 118.415) (end 143.045 118.415) (width 0.25) (layer "In1.Cu") (net 59))
  (segment (start 138.513 117.399) (end 138.513 117.907) (width 0.25) (layer "In1.Cu") (net 59))
  (segment (start 138.513 117.907) (end 139.021 118.415) (width 0.25) (layer "In1.Cu") (net 59))
  (segment (start 143.045 118.415) (end 143.945 117.515) (width 0.25) (layer "In1.Cu") (net 59))
  (segment (start 144.995 105.965) (end 139.66 105.965) (width 0.25) (layer "B.Cu") (net 59))
  (segment (start 143.615 117.185) (end 143.945 117.515) (width 0.15) (layer "B.Cu") (net 59))
  (segment (start 142.46 116.765) (end 142.88 117.185) (width 0.15) (layer "B.Cu") (net 59))
  (segment (start 138.132 115.40687) (end 138.64 115.91487) (width 0.25) (layer "B.Cu") (net 59))
  (segment (start 142.14 116.765) (end 141.14 116.765) (width 0.25) (layer "B.Cu") (net 59))
  (segment (start 138.64 117.272) (end 138.513 117.399) (width 0.25) (layer "B.Cu") (net 59))
  (segment (start 142.88 117.185) (end 143.615 117.185) (width 0.15) (layer "B.Cu") (net 59))
  (segment (start 138.132 107.493) (end 138.132 115.40687) (width 0.25) (layer "B.Cu") (net 59))
  (segment (start 142.14 116.765) (end 142.46 116.765) (width 0.15) (layer "B.Cu") (net 59))
  (segment (start 138.64 115.91487) (end 138.64 117.272) (width 0.25) (layer "B.Cu") (net 59))
  (segment (start 139.66 105.965) (end 138.132 107.493) (width 0.25) (layer "B.Cu") (net 59))
  (segment (start 120 132.25) (end 120.61 132.86) (width 0.15) (layer "B.Cu") (net 60))
  (segment (start 120.61 135.21) (end 120.61 133.94) (width 0.15) (layer "B.Cu") (net 60))
  (segment (start 120.61 132.86) (end 120.61 133.94) (width 0.15) (layer "B.Cu") (net 60))
  (segment (start 116.773 130.432) (end 118.591 132.25) (width 0.15) (layer "B.Cu") (net 60))
  (segment (start 116.773 126.477) (end 116.773 130.432) (width 0.15) (layer "B.Cu") (net 60))
  (segment (start 117.75 125.5) (end 116.773 126.477) (width 0.15) (layer "B.Cu") (net 60))
  (segment (start 118.591 132.25) (end 120 132.25) (width 0.15) (layer "B.Cu") (net 60))
  (segment (start 117.75 124.485) (end 117.75 125.5) (width 0.15) (layer "B.Cu") (net 60))
  (segment (start 154.642 107.62) (end 154.642 109.004553) (width 0.15) (layer "F.Cu") (net 61))
  (segment (start 156.035 109.355) (end 156.46 109.78) (width 0.15) (layer "F.Cu") (net 61))
  (segment (start 154.388 107.366) (end 154.642 107.62) (width 0.15) (layer "F.Cu") (net 61))
  (segment (start 125.59 128.19) (end 126.435 128.19) (width 0.15) (layer "F.Cu") (net 61))
  (segment (start 119.856 100.255) (end 119.856 100.713) (width 0.15) (layer "F.Cu") (net 61))
  (segment (start 119.311 99.71) (end 119.856 100.255) (width 0.15) (layer "F.Cu") (net 61))
  (segment (start 127.925 127.575) (end 127.05 127.575) (width 0.15) (layer "F.Cu") (net 61))
  (segment (start 156.46 109.78) (end 156.46 110.1) (width 0.15) (layer "F.Cu") (net 61))
  (segment (start 117.35 99.71) (end 119.311 99.71) (width 0.15) (layer "F.Cu") (net 61))
  (segment (start 154.642 109.004553) (end 154.992447 109.355) (width 0.15) (layer "F.Cu") (net 61))
  (segment (start 154.992447 109.355) (end 156.035 109.355) (width 0.15) (layer "F.Cu") (net 61))
  (segment (start 127.05 127.575) (end 126.435 128.19) (width 0.15) (layer "F.Cu") (net 61))
  (via (at 119.856 100.713) (size 0.55) (drill 0.15) (layers "F.Cu" "B.Cu") (net 61))
  (via (at 154.388 107.366) (size 0.625) (drill 0.15) (layers "F.Cu" "B.Cu") (net 61))
  (via (at 125.59 128.19) (size 0.55) (drill 0.15) (layers "F.Cu" "B.Cu") (net 61))
  (segment (start 157.182 124.892) (end 154.388 127.686) (width 0.15) (layer "In2.Cu") (net 61))
  (segment (start 129.5 128.19) (end 125.59 128.19) (width 0.15) (layer "In2.Cu") (net 61))
  (segment (start 154.388 107.366) (end 153.88 107.366) (width 0.15) (layer "In2.Cu") (net 61))
  (segment (start 138.069 127.15) (end 136.323603 127.15) (width 0.15) (layer "In2.Cu") (net 61))
  (segment (start 138.605 127.686) (end 154.388 127.686) (width 0.15) (layer "In2.Cu") (net 61))
  (segment (start 136.323603 127.15) (end 136.295603 127.178) (width 0.15) (layer "In2.Cu") (net 61))
  (segment (start 156.42 106.858) (end 157.182 107.62) (width 0.15) (layer "In2.Cu") (net 61))
  (segment (start 130.512 127.178) (end 129.5 128.19) (width 0.15) (layer "In2.Cu") (net 61))
  (segment (start 154.388 107.366) (end 154.896 106.858) (width 0.15) (layer "In2.Cu") (net 61))
  (segment (start 136.295603 127.178) (end 130.512 127.178) (width 0.15) (layer "In2.Cu") (net 61))
  (segment (start 154.896 106.858) (end 156.42 106.858) (width 0.15) (layer "In2.Cu") (net 61))
  (segment (start 146.805 100.291) (end 120.278 100.291) (width 0.15) (layer "In2.Cu") (net 61))
  (segment (start 138.605 127.686) (end 138.069 127.15) (width 0.15) (layer "In2.Cu") (net 61))
  (segment (start 120.278 100.291) (end 119.856 100.713) (width 0.15) (layer "In2.Cu") (net 61))
  (segment (start 157.182 107.62) (end 157.182 124.892) (width 0.15) (layer "In2.Cu") (net 61))
  (segment (start 153.88 107.366) (end 146.805 100.291) (width 0.15) (layer "In2.Cu") (net 61))
  (segment (start 154.388 107.366) (end 154.388 107.697) (width 0.15) (layer "B.Cu") (net 61))
  (segment (start 154.388 107.697) (end 153.285 108.8) (width 0.15) (layer "B.Cu") (net 61))
  (segment (start 127.925 126.925) (end 126.545 126.925) (width 0.15) (layer "F.Cu") (net 62))
  (segment (start 118.58 100.98) (end 118.86 100.7) (width 0.15) (layer "F.Cu") (net 62))
  (segment (start 154.73 112.96) (end 154.845 113.075) (width 0.15) (layer "F.Cu") (net 62))
  (segment (start 155.885 113.075) (end 156.46 112.5) (width 0.15) (layer "F.Cu") (net 62))
  (segment (start 126.545 126.925) (end 126.08 127.39) (width 0.15) (layer "F.Cu") (net 62))
  (segment (start 154.845 113.075) (end 155.885 113.075) (width 0.15) (layer "F.Cu") (net 62))
  (segment (start 117.35 100.98) (end 118.58 100.98) (width 0.15) (layer "F.Cu") (net 62))
  (via (at 154.73 112.96) (size 0.55) (drill 0.15) (layers "F.Cu" "B.Cu") (net 62))
  (via (at 118.86 100.7) (size 0.55) (drill 0.15) (layers "F.Cu" "B.Cu") (net 62))
  (via (at 126.08 127.39) (size 0.55) (drill 0.15) (layers "F.Cu" "B.Cu") (net 62))
  (segment (start 154.261 127.305) (end 138.767 127.305) (width 0.15) (layer "In2.Cu") (net 62))
  (segment (start 156.674 107.62) (end 156.674 112.223647) (width 0.15) (layer "In2.Cu") (net 62))
  (segment (start 156.674 112.223647) (end 155.881397 113.01625) (width 0.15) (layer "In2.Cu") (net 62))
  (segment (start 154.78625 113.01625) (end 154.73 112.96) (width 0.15) (layer "In2.Cu") (net 62))
  (segment (start 126.503 127.813) (end 126.08 127.39) (width 0.15) (layer "In2.Cu") (net 62))
  (segment (start 138.767 127.305) (end 138.259 126.797) (width 0.15) (layer "In2.Cu") (net 62))
  (segment (start 156.801 112.350647) (end 156.801 124.765) (width 0.15) (layer "In2.Cu") (net 62))
  (segment (start 156.293 107.239) (end 156.674 107.62) (width 0.15) (layer "In2.Cu") (net 62))
  (segment (start 138.259 126.797) (end 130.385 126.797) (width 0.15) (layer "In2.Cu") (net 62))
  (segment (start 120.606 100.762) (end 146.768 100.762) (width 0.15) (layer "In2.Cu") (net 62))
  (segment (start 154.515 108.128) (end 155.404 107.239) (width 0.15) (layer "In2.Cu") (net 62))
  (segment (start 154.134 108.128) (end 154.515 108.128) (width 0.15) (layer "In2.Cu") (net 62))
  (segment (start 129.369 127.813) (end 126.503 127.813) (width 0.15) (layer "In2.Cu") (net 62))
  (segment (start 130.385 126.797) (end 129.369 127.813) (width 0.15) (layer "In2.Cu") (net 62))
  (segment (start 156.801 124.765) (end 154.261 127.305) (width 0.15) (layer "In2.Cu") (net 62))
  (segment (start 118.86 100.7) (end 119.323 101.163) (width 0.15) (layer "In2.Cu") (net 62))
  (segment (start 120.205 101.163) (end 120.606 100.762) (width 0.15) (layer "In2.Cu") (net 62))
  (segment (start 155.404 107.239) (end 156.293 107.239) (width 0.15) (layer "In2.Cu") (net 62))
  (segment (start 155.881397 113.01625) (end 154.78625 113.01625) (width 0.15) (layer "In2.Cu") (net 62))
  (segment (start 119.323 101.163) (end 120.205 101.163) (width 0.15) (layer "In2.Cu") (net 62))
  (segment (start 146.768 100.762) (end 154.134 108.128) (width 0.15) (layer "In2.Cu") (net 62))
  (segment (start 156.674 112.223647) (end 156.801 112.350647) (width 0.15) (layer "In2.Cu") (net 62))
  (segment (start 154.585 110.535) (end 154.05 110) (width 0.15) (layer "B.Cu") (net 62))
  (segment (start 154.73 112.96) (end 154.585 112.815) (width 0.15) (layer "B.Cu") (net 62))
  (segment (start 154.585 112.815) (end 154.585 110.535) (width 0.15) (layer "B.Cu") (net 62))
  (segment (start 154.05 110) (end 153.285 110) (width 0.15) (layer "B.Cu") (net 62))
  (segment (start 119.5 121.5) (end 118.25 122.75) (width 0.15) (layer "F.Cu") (net 63))
  (segment (start 118.25 122.75) (end 116.75 122.75) (width 0.15) (layer "F.Cu") (net 63))
  (segment (start 119.5 121.5) (end 119.5 119.9) (width 0.15) (layer "F.Cu") (net 63))
  (via (at 116.75 122.75) (size 0.55) (drill 0.15) (layers "F.Cu" "B.Cu") (net 63))
  (segment (start 116.75 122.75) (end 116.75 123.515) (width 0.15) (layer "B.Cu") (net 63))
  (segment (start 119 119.4) (end 119.5 118.9) (width 0.15) (layer "F.Cu") (net 64))
  (segment (start 119 119.4) (end 119 120.9) (width 0.15) (layer "F.Cu") (net 64))
  (via (at 119 120.9) (size 0.55) (drill 0.15) (layers "F.Cu" "B.Cu") (net 64))
  (segment (start 118.75 121.15) (end 118.75 123.465) (width 0.15) (layer "B.Cu") (net 64))
  (segment (start 119 120.9) (end 118.75 121.15) (width 0.15) (layer "B.Cu") (net 64))
  (segment (start 106.95 124.95) (end 106.95 123.295) (width 0.54) (layer "F.Cu") (net 65))
  (segment (start 119.5 117.9) (end 119 118.4) (width 0.15) (layer "F.Cu") (net 66))
  (via (at 119 118.4) (size 0.55) (drill 0.15) (layers "F.Cu" "B.Cu") (net 66))
  (segment (start 119 118.4) (end 119 120.15) (width 0.15) (layer "B.Cu") (net 66))
  (segment (start 119 120.15) (end 117.75 121.4) (width 0.15) (layer "B.Cu") (net 66))
  (segment (start 117.75 121.4) (end 117.75 123.5) (width 0.15) (layer "B.Cu") (net 66))
  (segment (start 113.91 119.95) (end 114.88 119.95) (width 0.15) (layer "F.Cu") (net 67))
  (via (at 114.88 119.95) (size 0.55) (drill 0.15) (layers "F.Cu" "B.Cu") (net 67))
  (segment (start 114.88 119.95) (end 113.91 119.95) (width 0.15) (layer "B.Cu") (net 67))
  (segment (start 105.58 122.285) (end 105.54 122.325) (width 0.54) (layer "F.Cu") (net 68))
  (segment (start 105.795 120.855) (end 105.58 121.07) (width 0.25) (layer "F.Cu") (net 68))
  (segment (start 105.795 119.52) (end 105.795 120.855) (width 0.25) (layer "F.Cu") (net 68))
  (segment (start 105.58 121.07) (end 105.58 122.285) (width 0.54) (layer "F.Cu") (net 68))
  (segment (start 99 107) (end 109.07 107) (width 0.54) (layer "F.Cu") (net 69))
  (segment (start 111.44 111.5) (end 109.47 111.5) (width 0.25) (layer "F.Cu") (net 69))
  (segment (start 111.44 109.37) (end 109.07 107) (width 0.54) (layer "F.Cu") (net 69))
  (segment (start 111.44 111.5) (end 111.44 109.37) (width 0.54) (layer "F.Cu") (net 69))
  (segment (start 113.355 112.9) (end 111.44 112.9) (width 0.54) (layer "F.Cu") (net 70))
  (segment (start 111.44 112.9) (end 109.47 112.9) (width 0.25) (layer "F.Cu") (net 70))
  (segment (start 113.355 112.9) (end 113.355 111.695) (width 0.54) (layer "F.Cu") (net 70))
  (segment (start 130.942092 133.58) (end 132.444092 135.082) (width 0.15) (layer "F.Cu") (net 71))
  (segment (start 132.448092 135.082) (end 132.837 135.082) (width 0.15) (layer "F.Cu") (net 71))
  (segment (start 130.525 133.58) (end 130.942092 133.58) (width 0.15) (layer "F.Cu") (net 71))
  (segment (start 132.444092 135.082) (end 132.448092 135.082) (width 0.15) (layer "F.Cu") (net 71))
  (via (at 132.837 135.082) (size 0.55) (drill 0.15) (layers "F.Cu" "B.Cu") (net 71))
  (segment (start 133.615 136.08) (end 133.615 135.08) (width 0.15) (layer "B.Cu") (net 71))
  (segment (start 132.839 135.08) (end 132.837 135.082) (width 0.15) (layer "B.Cu") (net 71))
  (segment (start 133.615 135.08) (end 132.839 135.08) (width 0.15) (layer "B.Cu") (net 71))
  (segment (start 127.925 124.325) (end 130.025 124.325) (width 0.15) (layer "F.Cu") (net 72))
  (segment (start 130.839 127.049) (end 130.839 125.139) (width 0.15) (layer "F.Cu") (net 72))
  (segment (start 130.839 125.139) (end 130.025 124.325) (width 0.15) (layer "F.Cu") (net 72))
  (segment (start 131.69 127.9) (end 130.839 127.049) (width 0.15) (layer "F.Cu") (net 72))
  (segment (start 131.7 127.9) (end 131.69 127.9) (width 0.15) (layer "F.Cu") (net 72))
  (via (at 131.7 127.9) (size 0.55) (drill 0.15) (layers "F.Cu" "B.Cu") (net 72))
  (segment (start 130.885 127.9) (end 131.7 127.9) (width 0.15) (layer "B.Cu") (net 72))
  (segment (start 113.258 124.282) (end 112.91 123.934) (width 0.15) (layer "F.Cu") (net 73))
  (segment (start 113.831 124.282) (end 113.258 124.282) (width 0.15) (layer "F.Cu") (net 73))
  (segment (start 112.91 123.934) (end 112.91 122.9) (width 0.15) (layer "F.Cu") (net 73))
  (segment (start 133.575 124.325) (end 135.047 124.325) (width 0.15) (layer "F.Cu") (net 74))
  (segment (start 135.047 124.325) (end 136.545 125.823) (width 0.15) (layer "F.Cu") (net 74))
  (via (at 136.545 125.823) (size 0.55) (drill 0.15) (layers "F.Cu" "B.Cu") (net 74))
  (segment (start 135.654 124.932) (end 136.545 125.823) (width 0.15) (layer "B.Cu") (net 74))
  (segment (start 134.130001 124.932) (end 135.654 124.932) (width 0.15) (layer "B.Cu") (net 74))
  (segment (start 135.285 123.675) (end 135.57 123.39) (width 0.15) (layer "F.Cu") (net 75))
  (segment (start 133.575 123.675) (end 135.285 123.675) (width 0.15) (layer "F.Cu") (net 75))
  (via (at 135.57 123.39) (size 0.55) (drill 0.15) (layers "F.Cu" "B.Cu") (net 75))
  (segment (start 135.028 123.932) (end 135.57 123.39) (width 0.15) (layer "B.Cu") (net 75))
  (segment (start 134.130001 123.932) (end 135.028 123.932) (width 0.15) (layer "B.Cu") (net 75))
  (segment (start 139.25 128.5) (end 139.25 129.28) (width 0.125) (layer "F.Cu") (net 76))
  (segment (start 146.75 128.5) (end 148 128.5) (width 0.125) (layer "F.Cu") (net 76))
  (segment (start 132.8 130.2) (end 133.5 129.5) (width 0.125) (layer "F.Cu") (net 76))
  (segment (start 136.25 129.5) (end 137.25 128.5) (width 0.125) (layer "F.Cu") (net 76))
  (segment (start 141.75 128.5) (end 143 128.5) (width 0.125) (layer "F.Cu") (net 76))
  (segment (start 151.44 128.5) (end 151.75 128.81) (width 0.125) (layer "F.Cu") (net 76))
  (segment (start 132.8 130.2) (end 132.8 130.8) (width 0.125) (layer "F.Cu") (net 76))
  (segment (start 125.5 116.9) (end 126.61 116.9) (width 0.15) (layer "F.Cu") (net 76))
  (segment (start 148 128.5) (end 148 129.265) (width 0.125) (layer "F.Cu") (net 76))
  (segment (start 140.5 128.5) (end 140.5 129.265) (width 0.125) (layer "F.Cu") (net 76))
  (segment (start 145.5 128.5) (end 145.5 129.265) (width 0.125) (layer "F.Cu") (net 76))
  (segment (start 133.5 129.5) (end 136.25 129.5) (width 0.125) (layer "F.Cu") (net 76))
  (segment (start 149.25 128.5) (end 149.25 129.265) (width 0.125) (layer "F.Cu") (net 76))
  (segment (start 126.61 116.9) (end 126.73 116.78) (width 0.15) (layer "F.Cu") (net 76))
  (segment (start 123.366 123.361) (end 125.17 123.361) (width 0.15) (layer "F.Cu") (net 76))
  (segment (start 145.5 128.5) (end 146.75 128.5) (width 0.125) (layer "F.Cu") (net 76))
  (segment (start 149.25 128.5) (end 150.5 128.5) (width 0.125) (layer "F.Cu") (net 76))
  (segment (start 146.75 128.5) (end 146.75 129.265) (width 0.125) (layer "F.Cu") (net 76))
  (segment (start 138 129.265) (end 138 128.5) (width 0.125) (layer "F.Cu") (net 76))
  (segment (start 122.5 119.9) (end 122.5 122.495) (width 0.15) (layer "F.Cu") (net 76))
  (segment (start 138 128.5) (end 137.25 128.5) (width 0.125) (layer "F.Cu") (net 76))
  (segment (start 151.75 128.81) (end 151.75 129.265) (width 0.125) (layer "F.Cu") (net 76))
  (segment (start 148 128.5) (end 149.25 128.5) (width 0.125) (layer "F.Cu") (net 76))
  (segment (start 122.5 110.9) (end 122.5 109.4) (width 0.15) (layer "F.Cu") (net 76))
  (segment (start 125.5 113.9) (end 126.840002 113.9) (width 0.15) (layer "F.Cu") (net 76))
  (segment (start 144.25 128.5) (end 144.25 129.265) (width 0.125) (layer "F.Cu") (net 76))
  (segment (start 122.5 122.495) (end 123.366 123.361) (width 0.15) (layer "F.Cu") (net 76))
  (segment (start 140.5 128.5) (end 141.75 128.5) (width 0.125) (layer "F.Cu") (net 76))
  (segment (start 143 128.5) (end 144.25 128.5) (width 0.125) (layer "F.Cu") (net 76))
  (segment (start 139.25 128.5) (end 140.5 128.5) (width 0.125) (layer "F.Cu") (net 76))
  (segment (start 138 128.5) (end 139.25 128.5) (width 0.125) (layer "F.Cu") (net 76))
  (segment (start 144.25 128.5) (end 145.5 128.5) (width 0.125) (layer "F.Cu") (net 76))
  (segment (start 150.5 128.5) (end 151.44 128.5) (width 0.125) (layer "F.Cu") (net 76))
  (segment (start 143 128.5) (end 143 129.265) (width 0.125) (layer "F.Cu") (net 76))
  (segment (start 150.5 128.5) (end 150.5 129.265) (width 0.125) (layer "F.Cu") (net 76))
  (segment (start 141.75 128.5) (end 141.75 129.265) (width 0.125) (layer "F.Cu") (net 76))
  (via (at 125.17 123.361) (size 0.55) (drill 0.15) (layers "F.Cu" "B.Cu") (net 76))
  (via (at 126.73 116.78) (size 0.55) (drill 0.15) (layers "F.Cu" "B.Cu") (net 76))
  (via (at 131.75 129.025) (size 0.55) (drill 0.15) (layers "F.Cu" "B.Cu") (net 76))
  (via (at 122.5 109.4) (size 0.55) (drill 0.15) (layers "F.Cu" "B.Cu") (net 76))
  (via (at 126.840002 113.9) (size 0.55) (drill 0.15) (layers "F.Cu" "B.Cu") (net 76))
  (via (at 128.51 109.44) (size 0.55) (drill 0.15) (layers "F.Cu" "B.Cu") (net 76))
  (via (at 132.8 130.8) (size 0.55) (drill 0.15) (layers "F.Cu" "B.Cu") (net 76))
  (segment (start 122.5 110.415) (end 122.53 110.415) (width 0.15) (layer "B.Cu") (net 76))
  (segment (start 126.5 111.385) (end 126.53 111.385) (width 0.15) (layer "B.Cu") (net 76))
  (segment (start 122.5 110.415) (end 122.5 109.4) (width 0.15) (layer "B.Cu") (net 76))
  (segment (start 128.46 109.44) (end 128.51 109.44) (width 0.15) (layer "B.Cu") (net 76))
  (segment (start 127.5 110.415) (end 127.5 110.4) (width 0.15) (layer "B.Cu") (net 76))
  (segment (start 126.53 111.385) (end 127.5 110.415) (width 0.15) (layer "B.Cu") (net 76))
  (segment (start 127.5 110.4) (end 128.46 109.44) (width 0.15) (layer "B.Cu") (net 76))
  (segment (start 125.5 111.385) (end 126.5 111.385) (width 0.15) (layer "B.Cu") (net 76))
  (segment (start 122.53 110.415) (end 123.5 111.385) (width 0.15) (layer "B.Cu") (net 76))
  (segment (start 123.5 111.385) (end 124.5 111.385) (width 0.15) (layer "B.Cu") (net 76))
  (segment (start 130.885 129.025) (end 131.75 129.025) (width 0.15) (layer "B.Cu") (net 76))
  (via (at 140.634 107.924) (size 0.55) (drill 0.15) (layers "F.Cu" "B.Cu") (net 77))
  (via (at 149.75 111.5) (size 0.55) (drill 0.15) (layers "F.Cu" "B.Cu") (net 77))
  (via (at 149.145 121.255) (size 0.55) (drill 0.15) (layers "F.Cu" "B.Cu") (net 77))
  (via (at 148.345 111.075) (size 0.55) (drill 0.15) (layers "F.Cu" "B.Cu") (net 77))
  (segment (start 143.32 117.63) (end 143.32 114.22) (width 0.125) (layer "In2.Cu") (net 77))
  (segment (start 149.145 120.485) (end 147.81 119.15) (width 0.125) (layer "In2.Cu") (net 77))
  (segment (start 143.32 114.22) (end 143.9 113.64) (width 0.125) (layer "In2.Cu") (net 77))
  (segment (start 145.78 113.64) (end 148.345 111.075) (width 0.125) (layer "In2.Cu") (net 77))
  (segment (start 147.81 119.15) (end 144.84 119.15) (width 0.125) (layer "In2.Cu") (net 77))
  (segment (start 144.84 119.15) (end 143.32 117.63) (width 0.125) (layer "In2.Cu") (net 77))
  (segment (start 143.9 113.64) (end 145.78 113.64) (width 0.125) (layer "In2.Cu") (net 77))
  (segment (start 149.145 121.255) (end 149.145 120.485) (width 0.125) (layer "In2.Cu") (net 77))
  (segment (start 145.445 120.115) (end 144.83 119.5) (width 0.15) (layer "B.Cu") (net 77))
  (segment (start 148.445 114.015) (end 148.015 114.445) (width 0.15) (layer "B.Cu") (net 77))
  (segment (start 148.21 110.94) (end 148.21 109.74) (width 0.15) (layer "B.Cu") (net 77))
  (segment (start 140.21 111.01) (end 140.21 108.348) (width 0.15) (layer "B.Cu") (net 77))
  (segment (start 148.345 111.075) (end 148.21 110.94) (width 0.15) (layer "B.Cu") (net 77))
  (segment (start 147.925 112.44) (end 146.905 112.44) (width 0.15) (layer "B.Cu") (net 77))
  (segment (start 148.21 109.74) (end 148.21 109.62) (width 0.15) (layer "B.Cu") (net 77))
  (segment (start 144.83 119.5) (end 144.83 119.295) (width 0.15) (layer "B.Cu") (net 77))
  (segment (start 148.115 109.645) (end 148.21 109.74) (width 0.15) (layer "B.Cu") (net 77))
  (segment (start 149.245 121.155) (end 149.245 120.635) (width 0.15) (layer "B.Cu") (net 77))
  (segment (start 140.955 111.755) (end 140.21 111.01) (width 0.15) (layer "B.Cu") (net 77))
  (segment (start 148.005 121.255) (end 146.865 120.115) (width 0.15) (layer "B.Cu") (net 77))
  (segment (start 149.75 111.5) (end 149.41 111.84) (width 0.15) (layer "B.Cu") (net 77))
  (segment (start 148.025 117.395) (end 147.97 117.395) (width 0.15) (layer "B.Cu") (net 77))
  (segment (start 148.17 111.84) (end 147.925 112.085) (width 0.15) (layer "B.Cu") (net 77))
  (segment (start 140.21 108.348) (end 140.634 107.924) (width 0.15) (layer "B.Cu") (net 77))
  (segment (start 146.905 112.44) (end 146.885 112.46) (width 0.15) (layer "B.Cu") (net 77))
  (segment (start 147.92 112.42) (end 148.445 112.945) (width 0.15) (layer "B.Cu") (net 77))
  (segment (start 149.41 111.84) (end 148.17 111.84) (width 0.15) (layer "B.Cu") (net 77))
  (segment (start 147.925 112.085) (end 147.925 112.44) (width 0.15) (layer "B.Cu") (net 77))
  (segment (start 148.48 119.87) (end 148.48 117.85) (width 0.15) (layer "B.Cu") (net 77))
  (segment (start 149.145 121.255) (end 148.005 121.255) (width 0.15) (layer "B.Cu") (net 77))
  (segment (start 149.245 120.635) (end 148.48 119.87) (width 0.15) (layer "B.Cu") (net 77))
  (segment (start 148.015 114.445) (end 147.96 114.445) (width 0.15) (layer "B.Cu") (net 77))
  (segment (start 149.145 121.255) (end 149.245 121.155) (width 0.15) (layer "B.Cu") (net 77))
  (segment (start 148.445 112.945) (end 148.445 114.015) (width 0.15) (layer "B.Cu") (net 77))
  (segment (start 146.865 120.115) (end 145.445 120.115) (width 0.15) (layer "B.Cu") (net 77))
  (segment (start 148.48 117.85) (end 148.025 117.395) (width 0.15) (layer "B.Cu") (net 77))
  (segment (start 141.905 111.755) (end 140.955 111.755) (width 0.15) (layer "B.Cu") (net 77))
  (segment (start 148.115 108.49) (end 148.115 109.645) (width 0.15) (layer "B.Cu") (net 77))
  (segment (start 119.5 110.9) (end 119.5 109.4) (width 0.15) (layer "F.Cu") (net 78))
  (via (at 119.5 109.4) (size 0.55) (drill 0.15) (layers "F.Cu" "B.Cu") (net 78))
  (segment (start 120.155 110.26) (end 120 110.415) (width 0.15) (layer "B.Cu") (net 78))
  (segment (start 120 110.415) (end 120 109.9) (width 0.15) (layer "B.Cu") (net 78))
  (segment (start 120 109.9) (end 119.5 109.4) (width 0.15) (layer "B.Cu") (net 78))
  (segment (start 121.14 110.26) (end 120.155 110.26) (width 0.15) (layer "B.Cu") (net 78))
  (segment (start 121.25 110.15) (end 121.14 110.26) (width 0.15) (layer "B.Cu") (net 78))
  (segment (start 145.245 117.025) (end 144.7575 117.5125) (width 0.1) (layer "F.Cu") (net 79))
  (segment (start 144.92 116.54) (end 144.1075 116.54) (width 0.1) (layer "F.Cu") (net 79))
  (segment (start 145.245 116.865) (end 145.245 117.025) (width 0.1) (layer "F.Cu") (net 79))
  (segment (start 145.245 115.565) (end 144.92 115.24) (width 0.1) (layer "F.Cu") (net 79))
  (segment (start 144.92 115.24) (end 144.92 114.4275) (width 0.1) (layer "F.Cu") (net 79))
  (segment (start 144.1075 116.54) (end 143.945 116.7025) (width 0.1) (layer "F.Cu") (net 79))
  (segment (start 144.92 114.4275) (end 144.7575 114.265) (width 0.1) (layer "F.Cu") (net 79))
  (segment (start 145.245 114.915) (end 145.245 114.59) (width 0.1) (layer "F.Cu") (net 79))
  (segment (start 144.595 114.915) (end 143.945 114.265) (width 0.1) (layer "F.Cu") (net 79))
  (segment (start 144.7575 117.5125) (end 144.7575 117.515) (width 0.1) (layer "F.Cu") (net 79))
  (segment (start 145.245 114.59) (end 145.57 114.265) (width 0.1) (layer "F.Cu") (net 79))
  (segment (start 145.245 116.215) (end 144.92 116.54) (width 0.1) (layer "F.Cu") (net 79))
  (via (at 144.7575 114.265) (size 0.55) (drill 0.15) (layers "F.Cu" "B.Cu") (net 79))
  (via (at 143.945 114.265) (size 0.55) (drill 0.15) (layers "F.Cu" "B.Cu") (net 79))
  (via (at 145.57 114.265) (size 0.55) (drill 0.15) (layers "F.Cu" "B.Cu") (net 79))
  (via (at 143.945 116.7025) (size 0.55) (drill 0.15) (layers "F.Cu" "B.Cu") (net 79))
  (via (at 144.7575 117.515) (size 0.55) (drill 0.15) (layers "F.Cu" "B.Cu") (net 79))
  (via (at 140.7 110.09) (size 0.55) (drill 0.15) (layers "F.Cu" "B.Cu") (net 79))
  (via (at 141.119472 110.76) (size 0.55) (drill 0.15) (layers "F.Cu" "B.Cu") (net 79))
  (segment (start 142.975 111.425) (end 142.31 110.76) (width 0.15) (layer "B.Cu") (net 79))
  (segment (start 144.755 117.5175) (end 144.7575 117.515) (width 0.15) (layer "B.Cu") (net 79))
  (segment (start 143.945 114.265) (end 143.25 114.265) (width 0.15) (layer "B.Cu") (net 79))
  (segment (start 142.31 110.76) (end 141.119472 110.76) (width 0.15) (layer "B.Cu") (net 79))
  (segment (start 143.2525 116.7025) (end 143.25 116.705) (width 0.15) (layer "B.Cu") (net 79))
  (segment (start 145.47 110) (end 144.2875 110) (width 0.15) (layer "B.Cu") (net 79))
  (segment (start 142.975 112.905) (end 142.975 111.425) (width 0.15) (layer "B.Cu") (net 79))
  (segment (start 143.105 110) (end 144.2875 110) (width 0.15) (layer "B.Cu") (net 79))
  (segment (start 143 112.93) (end 142.975 112.905) (width 0.15) (layer "B.Cu") (net 79))
  (segment (start 144.7575 114.9475) (end 144.77 114.96) (width 0.15) (layer "B.Cu") (net 79))
  (segment (start 144.755 118.21) (end 144.755 117.5175) (width 0.15) (layer "B.Cu") (net 79))
  (segment (start 145.925 114.175) (end 145.925 113.49) (width 0.15) (layer "B.Cu") (net 79))
  (segment (start 145.57 114.265) (end 145.835 114.265) (width 0.15) (layer "B.Cu") (net 79))
  (segment (start 140.79 110) (end 140.7 110.09) (width 0.15) (layer "B.Cu") (net 79))
  (segment (start 143.945 116.7025) (end 143.2525 116.7025) (width 0.15) (layer "B.Cu") (net 79))
  (segment (start 145.835 114.265) (end 145.925 114.175) (width 0.15) (layer "B.Cu") (net 79))
  (segment (start 143.105 110) (end 140.79 110) (width 0.15) (layer "B.Cu") (net 79))
  (segment (start 144.7575 114.265) (end 144.7575 114.9475) (width 0.15) (layer "B.Cu") (net 79))
  (segment (start 158 107.7) (end 157.43 107.7) (width 0.15) (layer "F.Cu") (net 80))
  (segment (start 162.6 108.45) (end 158.75 108.45) (width 0.15) (layer "F.Cu") (net 80))
  (segment (start 158.75 108.45) (end 158 107.7) (width 0.15) (layer "F.Cu") (net 80))
  (segment (start 157.48 108.95) (end 162.6 108.95) (width 0.15) (layer "F.Cu") (net 81))
  (segment (start 157.43 108.9) (end 157.48 108.95) (width 0.15) (layer "F.Cu") (net 81))
  (segment (start 158.735 110.645) (end 159.965 110.645) (width 0.15) (layer "F.Cu") (net 82))
  (segment (start 157.43 110.1) (end 158.19 110.1) (width 0.15) (layer "F.Cu") (net 82))
  (segment (start 161.16 109.45) (end 162.6 109.45) (width 0.15) (layer "F.Cu") (net 82))
  (segment (start 159.965 110.645) (end 161.16 109.45) (width 0.15) (layer "F.Cu") (net 82))
  (segment (start 158.735 110.645) (end 158.08 111.3) (width 0.15) (layer "F.Cu") (net 82))
  (segment (start 158.19 110.1) (end 158.735 110.645) (width 0.15) (layer "F.Cu") (net 82))
  (segment (start 158.08 111.3) (end 157.43 111.3) (width 0.15) (layer "F.Cu") (net 82))
  (segment (start 160.093 110.927) (end 161.07 109.95) (width 0.15) (layer "F.Cu") (net 83))
  (segment (start 158.745 113.055) (end 159.205 113.055) (width 0.15) (layer "F.Cu") (net 83))
  (segment (start 158.1 113.7) (end 157.43 113.7) (width 0.15) (layer "F.Cu") (net 83))
  (segment (start 158.745 113.055) (end 158.1 113.7) (width 0.15) (layer "F.Cu") (net 83))
  (segment (start 157.43 112.5) (end 158.19 112.5) (width 0.15) (layer "F.Cu") (net 83))
  (segment (start 161.07 109.95) (end 162.6 109.95) (width 0.15) (layer "F.Cu") (net 83))
  (segment (start 159.205 113.055) (end 160.093 112.167) (width 0.15) (layer "F.Cu") (net 83))
  (segment (start 160.093 112.167) (end 160.093 110.927) (width 0.15) (layer "F.Cu") (net 83))
  (segment (start 158.19 112.5) (end 158.745 113.055) (width 0.15) (layer "F.Cu") (net 83))
  (segment (start 133.575 123.025) (end 132.345 123.025) (width 0.125) (layer "F.Cu") (net 84))
  (segment (start 132.345 123.025) (end 132.12 123.25) (width 0.125) (layer "F.Cu") (net 84))
  (via (at 132.12 123.25) (size 0.55) (drill 0.15) (layers "F.Cu" "B.Cu") (net 84))
  (segment (start 133.067001 123.025) (end 132.345 123.025) (width 0.15) (layer "B.Cu") (net 84))
  (segment (start 133.160001 122.932) (end 133.067001 123.025) (width 0.125) (layer "B.Cu") (net 84))
  (segment (start 132.345 123.025) (end 132.12 123.25) (width 0.15) (layer "B.Cu") (net 84))
  (segment (start 146.545 114.915) (end 147.195 114.265) (width 0.1) (layer "F.Cu") (net 85))
  (segment (start 146.545 113.615) (end 147.195 114.265) (width 0.1) (layer "F.Cu") (net 85))
  (via (at 147.195 114.265) (size 0.55) (drill 0.15) (layers "F.Cu" "B.Cu") (net 85))
  (segment (start 147.925 113.535) (end 147.925 113.41) (width 0.15) (layer "B.Cu") (net 85))
  (segment (start 147.195 114.265) (end 147.925 113.535) (width 0.15) (layer "B.Cu") (net 85))
  (segment (start 131 106.915) (end 131 105.15) (width 0.15) (layer "F.Cu") (net 86))
  (segment (start 145.57 111.488908) (end 146.16 110.898908) (width 0.1) (layer "F.Cu") (net 87))
  (segment (start 145.57 113.29) (end 145.57 111.488908) (width 0.1) (layer "F.Cu") (net 87))
  (segment (start 145.895 113.615) (end 145.57 113.29) (width 0.1) (layer "F.Cu") (net 87))
  (segment (start 146.16 110.898908) (end 146.16 110.51) (width 0.1) (layer "F.Cu") (net 87))
  (segment (start 130 106.915) (end 130 104.25) (width 0.15) (layer "F.Cu") (net 87))
  (via (at 130 104.25) (size 0.55) (drill 0.15) (layers "F.Cu" "B.Cu") (net 87))
  (via (at 146.16 110.51) (size 0.55) (drill 0.15) (layers "F.Cu" "B.Cu") (net 87))
  (segment (start 140.864 104.25) (end 146.16 109.546) (width 0.125) (layer "In2.Cu") (net 87))
  (segment (start 146.16 109.546) (end 146.16 110.51) (width 0.125) (layer "In2.Cu") (net 87))
  (segment (start 130 104.25) (end 140.864 104.25) (width 0.125) (layer "In2.Cu") (net 87))
  (segment (start 131 107.885) (end 139.535 107.885) (width 0.15) (layer "F.Cu") (net 88))
  (segment (start 142.2525 113.0625) (end 141.245 112.055) (width 0.15) (layer "F.Cu") (net 88))
  (segment (start 136.455 112.055) (end 132.285 107.885) (width 0.15) (layer "F.Cu") (net 88))
  (segment (start 132.285 107.885) (end 131 107.885) (width 0.15) (layer "F.Cu") (net 88))
  (segment (start 142.714092 108.29) (end 143.103 108.29) (width 0.15) (layer "F.Cu") (net 88))
  (segment (start 140.024001 108.374001) (end 142.630091 108.374001) (width 0.15) (layer "F.Cu") (net 88))
  (segment (start 143.295 113.615) (end 142.97 113.29) (width 0.1) (layer "F.Cu") (net 88))
  (segment (start 142.97 113.29) (end 142.48 113.29) (width 0.1) (layer "F.Cu") (net 88))
  (segment (start 141.245 112.055) (end 136.455 112.055) (width 0.15) (layer "F.Cu") (net 88))
  (segment (start 139.535 107.885) (end 140.024001 108.374001) (width 0.15) (layer "F.Cu") (net 88))
  (segment (start 142.48 113.29) (end 142.2525 113.0625) (width 0.1) (layer "F.Cu") (net 88))
  (segment (start 142.630091 108.374001) (end 142.714092 108.29) (width 0.15) (layer "F.Cu") (net 88))
  (via (at 143.103 108.29) (size 0.55) (drill 0.15) (layers "F.Cu" "B.Cu") (net 88))
  (segment (start 143.105 109.03) (end 143.105 108.292) (width 0.15) (layer "B.Cu") (net 88))
  (segment (start 143.105 108.292) (end 143.103 108.29) (width 0.15) (layer "B.Cu") (net 88))
  (segment (start 144.27 116.215) (end 143.945 115.89) (width 0.1) (layer "F.Cu") (net 89))
  (segment (start 144.595 116.215) (end 144.27 116.215) (width 0.1) (layer "F.Cu") (net 89))
  (via (at 143.945 115.89) (size 0.55) (drill 0.15) (layers "F.Cu" "B.Cu") (net 89))
  (segment (start 140.669 117.709) (end 140.44 117.48) (width 0.15) (layer "B.Cu") (net 89))
  (segment (start 140.44 116.08) (end 140.725 115.795) (width 0.15) (layer "B.Cu") (net 89))
  (segment (start 142.225 115.88) (end 143.935 115.88) (width 0.15) (layer "B.Cu") (net 89))
  (segment (start 140.725 115.795) (end 142.14 115.795) (width 0.15) (layer "B.Cu") (net 89))
  (segment (start 142.14 115.795) (end 142.225 115.88) (width 0.15) (layer "B.Cu") (net 89))
  (segment (start 143.935 115.88) (end 143.945 115.89) (width 0.15) (layer "B.Cu") (net 89))
  (segment (start 140.44 117.48) (end 140.44 116.08) (width 0.15) (layer "B.Cu") (net 89))
  (segment (start 141.65 117.709) (end 140.669 117.709) (width 0.15) (layer "B.Cu") (net 89))
  (segment (start 116.5 112.9) (end 115.9 112.9) (width 0.25) (layer "F.Cu") (net 90))
  (segment (start 115.9 112.9) (end 114.305 112.9) (width 0.54) (layer "F.Cu") (net 90))
  (segment (start 127 106.915) (end 127 105.15) (width 0.15) (layer "F.Cu") (net 91))
  (segment (start 116.5 113.9) (end 115.9 113.9) (width 0.25) (layer "F.Cu") (net 92))
  (segment (start 115.9 113.9) (end 114.305 113.9) (width 0.54) (layer "F.Cu") (net 92))
  (segment (start 115.575 121.425) (end 116.5 120.5) (width 0.15) (layer "F.Cu") (net 93))
  (segment (start 113.91 121.25) (end 114.235 121.25) (width 0.15) (layer "F.Cu") (net 93))
  (segment (start 116.5 120.5) (end 116.5 119.9) (width 0.15) (layer "F.Cu") (net 93))
  (segment (start 114.41 121.425) (end 115.575 121.425) (width 0.15) (layer "F.Cu") (net 93))
  (segment (start 114.235 121.25) (end 114.41 121.425) (width 0.15) (layer "F.Cu") (net 93))
  (segment (start 113.91 121.9) (end 114.235 121.9) (width 0.15) (layer "F.Cu") (net 94))
  (segment (start 114.41 121.725) (end 115.775 121.725) (width 0.15) (layer "F.Cu") (net 94))
  (segment (start 117 120.5) (end 117 119.4) (width 0.15) (layer "F.Cu") (net 94))
  (segment (start 114.235 121.9) (end 114.41 121.725) (width 0.15) (layer "F.Cu") (net 94))
  (segment (start 115.775 121.725) (end 117 120.5) (width 0.15) (layer "F.Cu") (net 94))
  (segment (start 117 119.4) (end 116.5 118.9) (width 0.15) (layer "F.Cu") (net 94))
  (segment (start 133 106.25) (end 133 105.15) (width 0.15) (layer "F.Cu") (net 95))
  (via (at 132.999998 106.25) (size 0.55) (drill 0.15) (layers "F.Cu" "B.Cu") (net 95))
  (segment (start 133.195 107.16) (end 133 106.965) (width 0.15) (layer "B.Cu") (net 95))
  (segment (start 133 106.965) (end 133 106.250002) (width 0.15) (layer "B.Cu") (net 95))
  (segment (start 133 106.250002) (end 132.999998 106.25) (width 0.15) (layer "B.Cu") (net 95))
  (segment (start 139.7605 110.0805) (end 142.645 112.965) (width 0.1) (layer "F.Cu") (net 96))
  (segment (start 139.7605 109.5) (end 139.7605 110.0805) (width 0.1) (layer "F.Cu") (net 96))
  (via (at 139.7605 109.5) (size 0.55) (drill 0.15) (layers "F.Cu" "B.Cu") (net 96))
  (segment (start 139.7605 107.2615) (end 141.472 105.55) (width 0.125) (layer "In3.Cu") (net 96))
  (segment (start 155.38 103.7) (end 155.38 97.87) (width 0.125) (layer "In3.Cu") (net 96))
  (segment (start 159.67 97.06) (end 159.67 98.58) (width 0.125) (layer "In3.Cu") (net 96))
  (segment (start 156.63 96.62) (end 159.23 96.62) (width 0.125) (layer "In3.Cu") (net 96))
  (segment (start 141.472 105.55) (end 153.53 105.55) (width 0.125) (layer "In3.Cu") (net 96))
  (segment (start 159.31 98.94) (end 158.5 98.94) (width 0.125) (layer "In3.Cu") (net 96))
  (segment (start 153.53 105.55) (end 155.38 103.7) (width 0.125) (layer "In3.Cu") (net 96))
  (segment (start 159.23 96.62) (end 159.67 97.06) (width 0.125) (layer "In3.Cu") (net 96))
  (segment (start 139.7605 109.5) (end 139.7605 107.2615) (width 0.125) (layer "In3.Cu") (net 96))
  (segment (start 159.67 98.58) (end 159.31 98.94) (width 0.125) (layer "In3.Cu") (net 96))
  (segment (start 155.38 97.87) (end 156.63 96.62) (width 0.125) (layer "In3.Cu") (net 96))
  (segment (start 144.595 112.025) (end 144.595 112.965) (width 0.1) (layer "F.Cu") (net 97))
  (segment (start 144.482 111.018) (end 144.38 111.12) (width 0.1) (layer "F.Cu") (net 97))
  (segment (start 144.38 111.12) (end 144.38 111.81) (width 0.1) (layer "F.Cu") (net 97))
  (segment (start 144.38 111.81) (end 144.595 112.025) (width 0.1) (layer "F.Cu") (net 97))
  (segment (start 149.24 106.99) (end 146.73 109.5) (width 0.1) (layer "F.Cu") (net 97))
  (segment (start 144.888 109.5) (end 144.482 109.906) (width 0.1) (layer "F.Cu") (net 97))
  (segment (start 149.24 106.604) (end 149.24 106.99) (width 0.1) (layer "F.Cu") (net 97))
  (segment (start 146.73 109.5) (end 144.888 109.5) (width 0.1) (layer "F.Cu") (net 97))
  (segment (start 144.482 109.906) (end 144.482 111.018) (width 0.1) (layer "F.Cu") (net 97))
  (via (at 149.24 106.604) (size 0.55) (drill 0.15) (layers "F.Cu" "B.Cu") (net 97))
  (segment (start 159.98 103.45) (end 158.44 104.99) (width 0.125) (layer "B.Cu") (net 97))
  (segment (start 159.24 100.21) (end 159.98 100.95) (width 0.125) (layer "B.Cu") (net 97))
  (segment (start 150.764 105.08) (end 158.35 105.08) (width 0.15) (layer "B.Cu") (net 97))
  (segment (start 159.98 100.95) (end 159.98 103.45) (width 0.125) (layer "B.Cu") (net 97))
  (segment (start 158.35 105.08) (end 158.44 104.99) (width 0.15) (layer "B.Cu") (net 97))
  (segment (start 149.24 106.604) (end 150.764 105.08) (width 0.15) (layer "B.Cu") (net 97))
  (segment (start 158.5 100.21) (end 159.24 100.21) (width 0.125) (layer "B.Cu") (net 97))
  (segment (start 152.315 106.4) (end 152.315 107.6) (width 0.15) (layer "B.Cu") (net 98))
  (segment (start 150.705 110) (end 150.695 109.99) (width 0.15) (layer "B.Cu") (net 98))
  (segment (start 152.315 110) (end 150.705 110) (width 0.15) (layer "B.Cu") (net 98))
  (segment (start 152.315 110) (end 152.315 108.8) (width 0.15) (layer "B.Cu") (net 98))
  (segment (start 152.315 107.6) (end 152.315 108.8) (width 0.15) (layer "B.Cu") (net 98))
  (segment (start 143.335 110.735) (end 143.945 111.345) (width 0.1) (layer "F.Cu") (net 99))
  (segment (start 155.48 111.3) (end 156.46 111.3) (width 0.15) (layer "F.Cu") (net 99))
  (segment (start 156.46 106.39) (end 156.46 107.7) (width 0.15) (layer "F.Cu") (net 99))
  (segment (start 158.5 97.67) (end 159.83 97.67) (width 0.15) (layer "F.Cu") (net 99))
  (segment (start 155.365 111.185) (end 155.48 111.3) (width 0.15) (layer "F.Cu") (net 99))
  (segment (start 155.822 105.752) (end 156.46 106.39) (width 0.15) (layer "F.Cu") (net 99))
  (segment (start 155.20392 105.752) (end 155.822 105.752) (width 0.15) (layer "F.Cu") (net 99))
  (segment (start 143.945 111.345) (end 143.945 112.965) (width 0.1) (layer "F.Cu") (net 99))
  (segment (start 159.83 97.67) (end 160.44 98.28) (width 0.15) (layer "F.Cu") (net 99))
  (segment (start 143.015 110.735) (end 143.335 110.735) (width 0.1) (layer "F.Cu") (net 99))
  (via (at 155.365 111.185) (size 0.55) (drill 0.15) (layers "F.Cu" "B.Cu") (net 99))
  (via (at 160.44 98.28) (size 0.55) (drill 0.15) (layers "F.Cu" "B.Cu") (net 99))
  (via (at 141.508 107.919) (size 0.55) (drill 0.15) (layers "F.Cu" "B.Cu") (net 99))
  (via (at 143.015 110.735) (size 0.55) (drill 0.15) (layers "F.Cu" "B.Cu") (net 99))
  (via (at 155.20392 105.752) (size 0.55) (drill 0.15) (layers "F.Cu" "B.Cu") (net 99))
  (segment (start 141.511 107.922) (end 141.508 107.919) (width 0.15) (layer "In2.Cu") (net 99))
  (segment (start 141.511 109.231) (end 141.511 107.922) (width 0.15) (layer "In2.Cu") (net 99))
  (segment (start 143.015 110.735) (end 141.511 109.231) (width 0.15) (layer "In2.Cu") (net 99))
  (segment (start 155.20392 105.752) (end 154.478 105.752) (width 0.15) (layer "In3.Cu") (net 99))
  (segment (start 146.7415 106.1225) (end 145.664 107.2) (width 0.15) (layer "In3.Cu") (net 99))
  (segment (start 160.44 102.584) (end 160.44 98.28) (width 0.15) (layer "In3.Cu") (net 99))
  (segment (start 155.62192 105.334) (end 157.69 105.334) (width 0.15) (layer "In3.Cu") (net 99))
  (segment (start 155.20392 105.752) (end 155.62192 105.334) (width 0.15) (layer "In3.Cu") (net 99))
  (segment (start 142.0405 107.2) (end 141.508 107.7325) (width 0.15) (layer "In3.Cu") (net 99))
  (segment (start 154.478 105.752) (end 154.1075 106.1225) (width 0.15) (layer "In3.Cu") (net 99))
  (segment (start 157.69 105.334) (end 160.44 102.584) (width 0.15) (layer "In3.Cu") (net 99))
  (segment (start 154.1075 106.1225) (end 146.7415 106.1225) (width 0.15) (layer "In3.Cu") (net 99))
  (segment (start 141.508 107.7325) (end 141.508 107.919) (width 0.15) (layer "In3.Cu") (net 99))
  (segment (start 145.664 107.2) (end 142.0405 107.2) (width 0.15) (layer "In3.Cu") (net 99))
  (segment (start 156.166 106.296078) (end 156.166 106.604) (width 0.15) (layer "B.Cu") (net 99))
  (segment (start 155.19 111.01) (end 155.365 111.185) (width 0.15) (layer "B.Cu") (net 99))
  (segment (start 155.20392 105.752) (end 153.933 105.752) (width 0.15) (layer "B.Cu") (net 99))
  (segment (start 155.621922 105.752) (end 156.166 106.296078) (width 0.15) (layer "B.Cu") (net 99))
  (segment (start 141.855 109.03) (end 141.855 108.266) (width 0.15) (layer "B.Cu") (net 99))
  (segment (start 141.855 108.266) (end 141.508 107.919) (width 0.15) (layer "B.Cu") (net 99))
  (segment (start 156.166 106.604) (end 155.19 107.58) (width 0.15) (layer "B.Cu") (net 99))
  (segment (start 155.20392 105.752) (end 155.621922 105.752) (width 0.15) (layer "B.Cu") (net 99))
  (segment (start 155.19 107.58) (end 155.19 111.01) (width 0.15) (layer "B.Cu") (net 99))
  (segment (start 153.933 105.752) (end 153.285 106.4) (width 0.15) (layer "B.Cu") (net 99))
  (segment (start 138.2765 110.033) (end 139.334499 108.975001) (width 0.1) (layer "F.Cu") (net 100))
  (segment (start 141.675 110.925) (end 141.58 110.83) (width 0.1) (layer "F.Cu") (net 100))
  (segment (start 139.334499 108.975001) (end 140.445001 108.975001) (width 0.1) (layer "F.Cu") (net 100))
  (segment (start 142.545 110.925) (end 141.675 110.925) (width 0.1) (layer "F.Cu") (net 100))
  (segment (start 135.1 127.575) (end 135.1 127.9) (width 0.15) (layer "F.Cu") (net 100))
  (segment (start 136.2375 109.8875) (end 136.383 110.033) (width 0.1) (layer "F.Cu") (net 100))
  (segment (start 133.575 126.925) (end 134.45 126.925) (width 0.15) (layer "F.Cu") (net 100))
  (segment (start 141.58 110.11) (end 140.72 109.25) (width 0.1) (layer "F.Cu") (net 100))
  (segment (start 143.62 113.29) (end 143.62 112) (width 0.1) (layer "F.Cu") (net 100))
  (segment (start 141.58 110.83) (end 141.58 110.11) (width 0.1) (layer "F.Cu") (net 100))
  (segment (start 143.945 113.615) (end 143.62 113.29) (width 0.1) (layer "F.Cu") (net 100))
  (segment (start 140.445001 108.975001) (end 140.72 109.25) (width 0.1) (layer "F.Cu") (net 100))
  (segment (start 136.383 110.033) (end 138.2765 110.033) (width 0.1) (layer "F.Cu") (net 100))
  (segment (start 143.62 112) (end 142.545 110.925) (width 0.1) (layer "F.Cu") (net 100))
  (segment (start 134.45 126.925) (end 135.1 127.575) (width 0.15) (layer "F.Cu") (net 100))
  (via (at 135.1 127.9) (size 0.625) (drill 0.15) (layers "F.Cu" "B.Cu") (net 100))
  (via (at 140.72 109.25) (size 0.55) (drill 0.15) (layers "F.Cu" "B.Cu") (net 100))
  (via (at 136.2375 109.9) (size 0.55) (drill 0.15) (layers "F.Cu" "B.Cu") (net 100))
  (via (at 145 106.75) (size 0.55) (drill 0.15) (layers "F.Cu" "B.Cu") (net 100))
  (segment (start 145.908 105.842) (end 145 106.75) (width 0.125) (layer "In3.Cu") (net 100))
  (segment (start 153.626 105.842) (end 145.908 105.842) (width 0.125) (layer "In3.Cu") (net 100))
  (segment (start 157.23 98.94) (end 156.96 98.94) (width 0.125) (layer "In3.Cu") (net 100))
  (segment (start 156.96 98.94) (end 155.8 100.1) (width 0.125) (layer "In3.Cu") (net 100))
  (segment (start 155.8 100.1) (end 155.8 103.668) (width 0.125) (layer "In3.Cu") (net 100))
  (segment (start 155.8 103.668) (end 153.626 105.842) (width 0.125) (layer "In3.Cu") (net 100))
  (segment (start 131.6 122) (end 131.6 124.8) (width 0.15) (layer "B.Cu") (net 100))
  (segment (start 133 126.2) (end 133.841941 126.2) (width 0.15) (layer "B.Cu") (net 100))
  (segment (start 144.2875 109.03) (end 144.2875 107.8675) (width 0.15) (layer "B.Cu") (net 100))
  (segment (start 131.6 124.8) (end 133 126.2) (width 0.15) (layer "B.Cu") (net 100))
  (segment (start 144.295 107.86) (end 144.295 107.54) (width 0.15) (layer "B.Cu") (net 100))
  (segment (start 133.841941 126.2) (end 135.1 127.458059) (width 0.15) (layer "B.Cu") (net 100))
  (segment (start 136.2375 109.8875) (end 136.2 109.925) (width 0.15) (layer "B.Cu") (net 100))
  (segment (start 144.295 107.54) (end 145 106.835) (width 0.15) (layer "B.Cu") (net 100))
  (segment (start 136.2 117.4) (end 131.6 122) (width 0.15) (layer "B.Cu") (net 100))
  (segment (start 136.2 109.925) (end 136.2 117.4) (width 0.15) (layer "B.Cu") (net 100))
  (segment (start 144.2875 109.03) (end 144.2875 109.325) (width 0.15) (layer "B.Cu") (net 100))
  (segment (start 144.2875 109.325) (end 144.087501 109.524999) (width 0.15) (layer "B.Cu") (net 100))
  (segment (start 144.2875 107.8675) (end 144.295 107.86) (width 0.15) (layer "B.Cu") (net 100))
  (segment (start 145 106.835) (end 145 106.75) (width 0.15) (layer "B.Cu") (net 100))
  (segment (start 135.1 127.458059) (end 135.1 127.9) (width 0.15) (layer "B.Cu") (net 100))
  (segment (start 144.087501 109.524999) (end 140.994999 109.524999) (width 0.15) (layer "B.Cu") (net 100))
  (segment (start 140.994999 109.524999) (end 140.72 109.25) (width 0.15) (layer "B.Cu") (net 100))
  (segment (start 142.245 113.615) (end 141.20499 112.57499) (width 0.125) (layer "F.Cu") (net 101))
  (segment (start 141.20499 112.57499) (end 140.9 112.57499) (width 0.125) (layer "F.Cu") (net 101))
  (segment (start 142.645 113.615) (end 142.245 113.615) (width 0.125) (layer "F.Cu") (net 101))
  (via (at 158.452 107.366) (size 0.625) (drill 0.15) (layers "F.Cu" "B.Cu") (net 101))
  (via (at 140.9 112.57499) (size 0.55) (drill 0.15) (layers "F.Cu" "B.Cu") (net 101))
  (via (at 156.166 104.572) (size 0.625) (drill 0.15) (layers "F.Cu" "B.Cu") (net 101))
  (segment (start 158.452 106.858) (end 156.166 104.572) (width 0.125) (layer "In2.Cu") (net 101))
  (segment (start 158.452 107.366) (end 158.452 106.858) (width 0.125) (layer "In2.Cu") (net 101))
  (segment (start 156.92 101.48) (end 157.23 101.48) (width 0.125) (layer "In3.Cu") (net 101))
  (segment (start 155.15 107.366) (end 154.642 106.858) (width 0.125) (layer "In3.Cu") (net 101))
  (segment (start 154.642 106.858) (end 149.943 106.858) (width 0.125) (layer "In3.Cu") (net 101))
  (segment (start 156.2 102.2) (end 156.92 101.48) (width 0.125) (layer "In3.Cu") (net 101))
  (segment (start 156.2 102.2) (end 156.2 104.538) (width 0.125) (layer "In3.Cu") (net 101))
  (segment (start 147.403 111.303) (end 146.13101 112.57499) (width 0.125) (layer "In3.Cu") (net 101))
  (segment (start 148.673 107.239) (end 147.403 108.509) (width 0.125) (layer "In3.Cu") (net 101))
  (segment (start 147.403 108.509) (end 147.403 111.303) (width 0.125) (layer "In3.Cu") (net 101))
  (segment (start 156.2 104.538) (end 156.166 104.572) (width 0.125) (layer "In3.Cu") (net 101))
  (segment (start 146.13101 112.57499) (end 140.9 112.57499) (width 0.125) (layer "In3.Cu") (net 101))
  (segment (start 149.562 107.239) (end 148.673 107.239) (width 0.125) (layer "In3.Cu") (net 101))
  (segment (start 149.943 106.858) (end 149.562 107.239) (width 0.125) (layer "In3.Cu") (net 101))
  (segment (start 158.452 107.366) (end 155.15 107.366) (width 0.125) (layer "In3.Cu") (net 101))
  (segment (start 156.34375 109.01625) (end 156.46 108.9) (width 0.15) (layer "F.Cu") (net 102))
  (segment (start 152.9 104.54) (end 149.908059 104.54) (width 0.1) (layer "F.Cu") (net 102))
  (segment (start 155.28 113.67) (end 156.22 113.67) (width 0.15) (layer "F.Cu") (net 102))
  (segment (start 144.73 109.15) (end 143.974 109.906) (width 0.1) (layer "F.Cu") (net 102))
  (segment (start 149.908059 104.54) (end 148.62 105.828059) (width 0.1) (layer "F.Cu") (net 102))
  (segment (start 146.55 109.15) (end 144.73 109.15) (width 0.1) (layer "F.Cu") (net 102))
  (segment (start 148.62 105.828059) (end 148.62 107.08) (width 0.1) (layer "F.Cu") (net 102))
  (segment (start 148.62 107.08) (end 146.55 109.15) (width 0.1) (layer "F.Cu") (net 102))
  (segment (start 154.896 107.112) (end 154.896 108.69) (width 0.15) (layer "F.Cu") (net 102))
  (segment (start 154.896 108.69) (end 155.22225 109.01625) (width 0.15) (layer "F.Cu") (net 102))
  (segment (start 156.25 113.7) (end 156.46 113.7) (width 0.15) (layer "F.Cu") (net 102))
  (segment (start 143.974 109.906) (end 142.634 109.906) (width 0.1) (layer "F.Cu") (net 102))
  (segment (start 155.621116 106.386884) (end 154.896 107.112) (width 0.15) (layer "F.Cu") (net 102))
  (segment (start 156.22 113.67) (end 156.25 113.7) (width 0.15) (layer "F.Cu") (net 102))
  (segment (start 142.634 109.906) (end 142.1 110.44) (width 0.1) (layer "F.Cu") (net 102))
  (segment (start 155.22225 109.01625) (end 156.34375 109.01625) (width 0.15) (layer "F.Cu") (net 102))
  (via (at 152.9 104.54) (size 0.55) (drill 0.15) (layers "F.Cu" "B.Cu") (net 102))
  (via (at 155.28 113.67) (size 0.55) (drill 0.15) (layers "F.Cu" "B.Cu") (net 102))
  (via (at 155.621116 106.386884) (size 0.55) (drill 0.15) (layers "F.Cu" "B.Cu") (net 102))
  (segment (start 153.4 104.04) (end 159.4 104.04) (width 0.15) (layer "In2.Cu") (net 102))
  (segment (start 154.678884 106.386884) (end 152.9 104.608) (width 0.15) (layer "In2.Cu") (net 102))
  (segment (start 155.621116 106.386884) (end 154.678884 106.386884) (width 0.15) (layer "In2.Cu") (net 102))
  (segment (start 158.5 101.48) (end 159.43 101.48) (width 0.15) (layer "In2.Cu") (net 102))
  (segment (start 153.4 104.04) (end 152.9 104.54) (width 0.15) (layer "In2.Cu") (net 102))
  (segment (start 152.9 104.608) (end 152.9 104.54) (width 0.15) (layer "In2.Cu") (net 102))
  (segment (start 159.99 102.04) (end 159.99 103.45) (width 0.15) (layer "In2.Cu") (net 102))
  (segment (start 159.43 101.48) (end 159.99 102.04) (width 0.15) (layer "In2.Cu") (net 102))
  (segment (start 159.99 103.45) (end 159.4 104.04) (width 0.15) (layer "In2.Cu") (net 102))
  (segment (start 155.621116 106.386884) (end 154.498116 106.386884) (width 0.15) (layer "B.Cu") (net 102))
  (segment (start 155.18 112.314) (end 155.18 113.57) (width 0.15) (layer "B.Cu") (net 102))
  (segment (start 155.621116 106.386884) (end 154.915 107.093) (width 0.15) (layer "B.Cu") (net 102))
  (segment (start 155.18 113.57) (end 155.28 113.67) (width 0.15) (layer "B.Cu") (net 102))
  (segment (start 154.915 112.049) (end 155.18 112.314) (width 0.15) (layer "B.Cu") (net 102))
  (segment (start 154.915 107.093) (end 154.915 112.049) (width 0.15) (layer "B.Cu") (net 102))
  (segment (start 154.498116 106.386884) (end 153.285 107.6) (width 0.15) (layer "B.Cu") (net 102))
  (segment (start 151.4275 105.3275) (end 156.6805 105.3275) (width 0.1) (layer "F.Cu") (net 103))
  (segment (start 147.71 109.045) (end 151.4275 105.3275) (width 0.1) (layer "F.Cu") (net 103))
  (segment (start 146.545 111.955) (end 147.71 110.79) (width 0.1) (layer "F.Cu") (net 103))
  (segment (start 157.23 104.778) (end 157.23 102.75) (width 0.1) (layer "F.Cu") (net 103))
  (segment (start 146.545 112.965) (end 146.545 111.955) (width 0.1) (layer "F.Cu") (net 103))
  (segment (start 147.71 110.79) (end 147.71 109.045) (width 0.1) (layer "F.Cu") (net 103))
  (segment (start 156.6805 105.3275) (end 157.23 104.778) (width 0.1) (layer "F.Cu") (net 103))
  (segment (start 145.895 117.195) (end 145.575 117.515) (width 0.1) (layer "F.Cu") (net 104))
  (segment (start 145.895 116.865) (end 145.895 117.195) (width 0.1) (layer "F.Cu") (net 104))
  (segment (start 145.575 117.515) (end 145.57 117.515) (width 0.1) (layer "F.Cu") (net 104))
  (segment (start 146.545 116.865) (end 147.195 117.515) (width 0.1) (layer "F.Cu") (net 104))
  (via (at 147.195 117.515) (size 0.55) (drill 0.15) (layers "F.Cu" "B.Cu") (net 104))
  (via (at 145.57 117.515) (size 0.55) (drill 0.15) (layers "F.Cu" "B.Cu") (net 104))
  (segment (start 145.57 117.515) (end 145.575 117.515) (width 0.125) (layer "In2.Cu") (net 104))
  (segment (start 146.065 117.025) (end 146.705 117.025) (width 0.125) (layer "In2.Cu") (net 104))
  (segment (start 145.575 117.515) (end 146.065 117.025) (width 0.125) (layer "In2.Cu") (net 104))
  (segment (start 146.705 117.025) (end 147.195 117.515) (width 0.125) (layer "In2.Cu") (net 104))
  (segment (start 145.33 119.02) (end 145.57 119.26) (width 0.15) (layer "B.Cu") (net 104))
  (segment (start 145.33 117.755) (end 145.33 119.02) (width 0.15) (layer "B.Cu") (net 104))
  (segment (start 145.57 117.515) (end 145.33 117.755) (width 0.15) (layer "B.Cu") (net 104))
  (segment (start 145.57 119.26) (end 145.735 119.26) (width 0.15) (layer "B.Cu") (net 104))
  (segment (start 138 130.75) (end 138 130.235) (width 0.1) (layer "F.Cu") (net 105))
  (segment (start 142.965 117.84) (end 143.29 118.165) (width 0.1) (layer "F.Cu") (net 105))
  (segment (start 143.29 118.165) (end 143.295 118.165) (width 0.1) (layer "F.Cu") (net 105))
  (segment (start 140.92 122.32) (end 140.92 121.34) (width 0.1) (layer "F.Cu") (net 105))
  (segment (start 152.6 132.5) (end 153.385 132.5) (width 0.1) (layer "F.Cu") (net 105))
  (segment (start 139.13 119.55) (end 139.13 119.02) (width 0.1) (layer "F.Cu") (net 105))
  (segment (start 153.385 132.5) (end 153.4 132.515) (width 0.1) (layer "F.Cu") (net 105))
  (segment (start 138 131.28) (end 138 130.75) (width 0.1) (layer "F.Cu") (net 105))
  (segment (start 140.31 117.84) (end 142.965 117.84) (width 0.1) (layer "F.Cu") (net 105))
  (segment (start 140.92 121.34) (end 139.13 119.55) (width 0.1) (layer "F.Cu") (net 105))
  (segment (start 139.13 119.02) (end 140.31 117.84) (width 0.1) (layer "F.Cu") (net 105))
  (segment (start 140.17 123.07) (end 140.92 122.32) (width 0.1) (layer "F.Cu") (net 105))
  (segment (start 138.64 123.07) (end 140.17 123.07) (width 0.1) (layer "F.Cu") (net 105))
  (via (at 138.64 123.07) (size 0.55) (drill 0.15) (layers "F.Cu" "B.Cu") (net 105))
  (via (at 138 130.75) (size 0.55) (drill 0.15) (layers "F.Cu" "B.Cu") (net 105))
  (via (at 152.6 132.5) (size 0.55) (drill 0.15) (layers "F.Cu" "B.Cu") (net 105))
  (segment (start 139.9 131.6) (end 139.9 130.2) (width 0.1) (layer "B.Cu") (net 105))
  (segment (start 152.6 132.5) (end 152.1 132) (width 0.1) (layer "B.Cu") (net 105))
  (segment (start 138 129.9) (end 138 130.75) (width 0.1) (layer "B.Cu") (net 105))
  (segment (start 139.9 130.2) (end 139.6 129.9) (width 0.1) (layer "B.Cu") (net 105))
  (segment (start 140.3 132) (end 139.9 131.6) (width 0.1) (layer "B.Cu") (net 105))
  (segment (start 138 123.71) (end 138 129.9) (width 0.1) (layer "B.Cu") (net 105))
  (segment (start 139.6 129.9) (end 138 129.9) (width 0.1) (layer "B.Cu") (net 105))
  (segment (start 152.1 132) (end 140.3 132) (width 0.1) (layer "B.Cu") (net 105))
  (segment (start 138.64 123.07) (end 138 123.71) (width 0.1) (layer "B.Cu") (net 105))
  (segment (start 140.15 119.28) (end 140.94 118.49) (width 0.1) (layer "F.Cu") (net 106))
  (segment (start 142.97 118.49) (end 143.295 118.815) (width 0.1) (layer "F.Cu") (net 106))
  (segment (start 140.94 118.49) (end 142.97 118.49) (width 0.1) (layer "F.Cu") (net 106))
  (segment (start 127.015 107.9) (end 127 107.885) (width 0.15) (layer "F.Cu") (net 106))
  (segment (start 128 107.9) (end 127.015 107.9) (width 0.15) (layer "F.Cu") (net 106))
  (segment (start 139.98 119.28) (end 140.15 119.28) (width 0.1) (layer "F.Cu") (net 106))
  (via (at 128 107.9) (size 0.625) (drill 0.15) (layers "F.Cu" "B.Cu") (net 106))
  (via (at 139.98 119.28) (size 0.55) (drill 0.15) (layers "F.Cu" "B.Cu") (net 106))
  (segment (start 138.108 119.28) (end 136.735 117.907) (width 0.15) (layer "B.Cu") (net 106))
  (segment (start 136.735 109.635) (end 135 107.9) (width 0.15) (layer "B.Cu") (net 106))
  (segment (start 136.735 117.907) (end 136.735 109.635) (width 0.15) (layer "B.Cu") (net 106))
  (segment (start 135 107.9) (end 128 107.9) (width 0.15) (layer "B.Cu") (net 106))
  (segment (start 139.98 119.28) (end 138.108 119.28) (width 0.15) (layer "B.Cu") (net 106))
  (segment (start 154.852 133.5) (end 158.95 133.5) (width 0.1) (layer "F.Cu") (net 125))
  (segment (start 153.4 133.485) (end 153.415 133.5) (width 0.1) (layer "F.Cu") (net 125))
  (segment (start 153.415 133.5) (end 154.852 133.5) (width 0.1) (layer "F.Cu") (net 125))
  (segment (start 122.5 112.9) (end 123 112.4) (width 0.125) (layer "F.Cu") (net 126))
  (via (at 123 112.4) (size 0.55) (drill 0.15) (layers "F.Cu" "B.Cu") (net 126))
  (segment (start 127.5 111.9) (end 127.5 111.385) (width 0.125) (layer "B.Cu") (net 126))
  (segment (start 128.5 111.385) (end 128.53 111.385) (width 0.125) (layer "B.Cu") (net 126))
  (segment (start 128.53 111.385) (end 129.5 110.415) (width 0.125) (layer "B.Cu") (net 126))
  (segment (start 127.1 112.3) (end 127.5 111.9) (width 0.125) (layer "B.Cu") (net 126))
  (segment (start 125 112.9) (end 125.6 112.3) (width 0.125) (layer "B.Cu") (net 126))
  (segment (start 123.5 112.9) (end 125 112.9) (width 0.125) (layer "B.Cu") (net 126))
  (segment (start 127.5 111.385) (end 128.5 111.385) (width 0.125) (layer "B.Cu") (net 126))
  (segment (start 123 112.4) (end 123.5 112.9) (width 0.125) (layer "B.Cu") (net 126))
  (segment (start 125.6 112.3) (end 127.1 112.3) (width 0.125) (layer "B.Cu") (net 126))
  (segment (start 146.545 119.87) (end 148.25 121.575) (width 0.125) (layer "F.Cu") (net 127))
  (segment (start 146.545 118.815) (end 146.545 119.87) (width 0.125) (layer "F.Cu") (net 127))
  (segment (start 148.25 121.575) (end 148.25 121.8) (width 0.125) (layer "F.Cu") (net 127))
  (via (at 148.25 121.8) (size 0.55) (drill 0.15) (layers "F.Cu" "B.Cu") (net 127))
  (segment (start 130.35 110.575) (end 129.54 111.385) (width 0.125) (layer "B.Cu") (net 127))
  (segment (start 128.25 108.675) (end 128.65 108.275) (width 0.125) (layer "B.Cu") (net 127))
  (segment (start 147.075 120.675) (end 145.6 120.675) (width 0.125) (layer "B.Cu") (net 127))
  (segment (start 143.425 118.725) (end 138.04 118.725) (width 0.125) (layer "B.Cu") (net 127))
  (segment (start 130.35 108.85) (end 130.35 110.575) (width 0.125) (layer "B.Cu") (net 127))
  (segment (start 127.3 108.675) (end 128.25 108.675) (width 0.125) (layer "B.Cu") (net 127))
  (segment (start 138.04 118.725) (end 136.989 117.674) (width 0.125) (layer "B.Cu") (net 127))
  (segment (start 127.6 105.75) (end 126.75 106.6) (width 0.125) (layer "B.Cu") (net 127))
  (segment (start 126.75 108.125) (end 127.3 108.675) (width 0.125) (layer "B.Cu") (net 127))
  (segment (start 144.8 119.875) (end 144.575 119.875) (width 0.125) (layer "B.Cu") (net 127))
  (segment (start 134.95 105.75) (end 127.6 105.75) (width 0.125) (layer "B.Cu") (net 127))
  (segment (start 148.25 121.8) (end 148.2 121.8) (width 0.125) (layer "B.Cu") (net 127))
  (segment (start 148.2 121.8) (end 147.075 120.675) (width 0.125) (layer "B.Cu") (net 127))
  (segment (start 129.54 111.385) (end 129.5 111.385) (width 0.125) (layer "B.Cu") (net 127))
  (segment (start 128.65 108.275) (end 129.775 108.275) (width 0.125) (layer "B.Cu") (net 127))
  (segment (start 144.575 119.875) (end 143.425 118.725) (width 0.125) (layer "B.Cu") (net 127))
  (segment (start 145.6 120.675) (end 144.8 119.875) (width 0.125) (layer "B.Cu") (net 127))
  (segment (start 129.775 108.275) (end 130.35 108.85) (width 0.125) (layer "B.Cu") (net 127))
  (segment (start 126.75 106.6) (end 126.75 108.125) (width 0.125) (layer "B.Cu") (net 127))
  (segment (start 136.989 107.789) (end 134.95 105.75) (width 0.125) (layer "B.Cu") (net 127))
  (segment (start 136.989 117.674) (end 136.989 107.789) (width 0.125) (layer "B.Cu") (net 127))
  (segment (start 143.295 112.965) (end 143.295 112.605) (width 0.1) (layer "F.Cu") (net 128))
  (segment (start 143.295 112.605) (end 142.1 111.41) (width 0.1) (layer "F.Cu") (net 128))
  (segment (start 130.525 134.08) (end 130.96 134.08) (width 0.15) (layer "F.Cu") (net 129))
  (segment (start 131.56 134.68) (end 131.56 135.99) (width 0.15) (layer "F.Cu") (net 129))
  (segment (start 130.96 134.08) (end 131.56 134.68) (width 0.15) (layer "F.Cu") (net 129))
  (segment (start 121.5 117.9) (end 122 118.4) (width 0.15) (layer "F.Cu") (net 130))
  (segment (start 122 118.4) (end 122 123.29) (width 0.15) (layer "F.Cu") (net 130))
  (segment (start 122 123.29) (end 122.435 123.725) (width 0.15) (layer "F.Cu") (net 130))
  (segment (start 111.61 124.2408) (end 111.61 122.85) (width 0.15) (layer "F.Cu") (net 131))
  (segment (start 160.305989 105.920989) (end 160.285 105.9) (width 0.2) (layer "F.Cu") (net 136))
  (segment (start 161.670989 105.920989) (end 160.305989 105.920989) (width 0.3) (layer "F.Cu") (net 136))
  (segment (start 161.65 105.45) (end 161.55 105.45) (width 0.25) (layer "F.Cu") (net 136))
  (segment (start 162.6 105.45) (end 161.65 105.45) (width 0.25) (layer "F.Cu") (net 136))
  (segment (start 161.7 105.95) (end 161.670989 105.920989) (width 0.25) (layer "F.Cu") (net 136))
  (segment (start 162.6 105.95) (end 161.7 105.95) (width 0.25) (layer "F.Cu") (net 136))
  (segment (start 161.55 105.45) (end 161.179011 105.920989) (width 0.25) (layer "F.Cu") (net 136))
  (segment (start 104.14 126) (end 105.54 124.6) (width 0.54) (layer "F.Cu") (net 140))
  (segment (start 105.54 124.6) (end 105.54 123.295) (width 0.54) (layer "F.Cu") (net 140))
  (segment (start 99 126) (end 104.14 126) (width 0.54) (layer "F.Cu") (net 140))
  (segment (start 148.98 114.455) (end 148.98 113.455) (width 0.15) (layer "B.Cu") (net 141))
  (segment (start 148.98 113.455) (end 148.95 113.425) (width 0.15) (layer "B.Cu") (net 141))
  (segment (start 113.35 113.905) (end 113.345 113.9) (width 0.25) (layer "F.Cu") (net 142))
  (segment (start 113.35 114.995) (end 113.35 113.905) (width 0.25) (layer "F.Cu") (net 142))
  (segment (start 153.932288 126.466289) (end 153.926564 126.517088) (width 0.1) (layer "F.Cu") (net 143))
  (segment (start 152.86125 126.31) (end 152.605 126.56625) (width 0.1) (layer "F.Cu") (net 143))
  (segment (start 155.146366 126.385303) (end 155.114697 126.353634) (width 0.1) (layer "F.Cu") (net 143))
  (segment (start 155.633633 126.385303) (end 155.609806 126.423224) (width 0.1) (layer "F.Cu") (net 143))
  (segment (start 155.434504 126.788653) (end 155.39 126.793667) (width 0.1) (layer "F.Cu") (net 143))
  (segment (start 153.332288 126.352288) (end 153.331227 126.342878) (width 0.1) (layer "F.Cu") (net 143))
  (segment (start 155.570193 126.680444) (end 155.546366 126.718365) (width 0.1) (layer "F.Cu") (net 143))
  (segment (start 155.703223 126.329807) (end 155.665302 126.353634) (width 0.1) (layer "F.Cu") (net 143))
  (segment (start 155.595014 126.465496) (end 155.59 126.51) (width 0.1) (layer "F.Cu") (net 143))
  (segment (start 155.476776 126.773861) (end 155.434504 126.788653) (width 0.1) (layer "F.Cu") (net 143))
  (segment (start 153.936475 126.333939) (end 153.933348 126.342878) (width 0.1) (layer "F.Cu") (net 143))
  (segment (start 153.316366 126.319225) (end 153.308348 126.314187) (width 0.1) (layer "F.Cu") (net 143))
  (segment (start 153.299409 126.31106) (end 153.29 126.31) (width 0.1) (layer "F.Cu") (net 143))
  (segment (start 150.18125 121.339814) (end 150.18125 123.705) (width 0.1) (layer "F.Cu") (net 143))
  (segment (start 153.704 126.694577) (end 153.560575 126.694577) (width 0.1) (layer "F.Cu") (net 143))
  (segment (start 162.6 128.95) (end 161.699999 128.95) (width 0.1) (layer "F.Cu") (net 143))
  (segment (start 153.846335 126.644771) (end 153.80305 126.671969) (width 0.1) (layer "F.Cu") (net 143))
  (segment (start 153.932288 126.352288) (end 153.932288 126.466289) (width 0.1) (layer "F.Cu") (net 143))
  (segment (start 155.39 126.793667) (end 155.345495 126.788653) (width 0.1) (layer "F.Cu") (net 143))
  (segment (start 153.509776 126.688853) (end 153.461525 126.671969) (width 0.1) (layer "F.Cu") (net 143))
  (segment (start 155.170193 126.423224) (end 155.146366 126.385303) (width 0.1) (layer "F.Cu") (net 143))
  (segment (start 148.495 118.815) (end 148.495 119.653564) (width 0.1) (layer "F.Cu") (net 143))
  (segment (start 155.59 126.51) (end 155.59 126.593667) (width 0.1) (layer "F.Cu") (net 143))
  (segment (start 155.19 126.51) (end 155.184985 126.465496) (width 0.1) (layer "F.Cu") (net 143))
  (segment (start 155.665302 126.353634) (end 155.633633 126.385303) (width 0.1) (layer "F.Cu") (net 143))
  (segment (start 155.233633 126.718365) (end 155.209806 126.680444) (width 0.1) (layer "F.Cu") (net 143))
  (segment (start 153.882482 126.608624) (end 153.846335 126.644771) (width 0.1) (layer "F.Cu") (net 143))
  (segment (start 155.209806 126.680444) (end 155.195014 126.638172) (width 0.1) (layer "F.Cu") (net 143))
  (segment (start 153.3281 126.333939) (end 153.323062 126.325921) (width 0.1) (layer "F.Cu") (net 143))
  (segment (start 155.303223 126.773861) (end 155.265302 126.750034) (width 0.1) (layer "F.Cu") (net 143))
  (segment (start 153.560575 126.694577) (end 153.509776 126.688853) (width 0.1) (layer "F.Cu") (net 143))
  (segment (start 155.345495 126.788653) (end 155.303223 126.773861) (width 0.1) (layer "F.Cu") (net 143))
  (segment (start 153.331227 126.342878) (end 153.3281 126.333939) (width 0.1) (layer "F.Cu") (net 143))
  (segment (start 153.41824 126.644771) (end 153.382093 126.608624) (width 0.1) (layer "F.Cu") (net 143))
  (segment (start 155.745495 126.315015) (end 155.703223 126.329807) (width 0.1) (layer "F.Cu") (net 143))
  (segment (start 153.933348 126.342878) (end 153.932288 126.352288) (width 0.1) (layer "F.Cu") (net 143))
  (segment (start 153.90968 126.565339) (end 153.882482 126.608624) (width 0.1) (layer "F.Cu") (net 143))
  (segment (start 155.609806 126.423224) (end 155.595014 126.465496) (width 0.1) (layer "F.Cu") (net 143))
  (segment (start 158.903578 126.31) (end 155.79 126.31) (width 0.1) (layer "F.Cu") (net 143))
  (segment (start 155.59 126.593667) (end 155.584985 126.638172) (width 0.1) (layer "F.Cu") (net 143))
  (segment (start 155.265302 126.750034) (end 155.233633 126.718365) (width 0.1) (layer "F.Cu") (net 143))
  (segment (start 155.034504 126.315015) (end 154.99 126.31) (width 0.1) (layer "F.Cu") (net 143))
  (segment (start 153.332288 126.466289) (end 153.332288 126.352288) (width 0.1) (layer "F.Cu") (net 143))
  (segment (start 153.926564 126.517088) (end 153.90968 126.565339) (width 0.1) (layer "F.Cu") (net 143))
  (segment (start 153.323062 126.325921) (end 153.316366 126.319225) (width 0.1) (layer "F.Cu") (net 143))
  (segment (start 153.29 126.31) (end 152.86125 126.31) (width 0.1) (layer "F.Cu") (net 143))
  (segment (start 155.114697 126.353634) (end 155.076776 126.329807) (width 0.1) (layer "F.Cu") (net 143))
  (segment (start 155.184985 126.465496) (end 155.170193 126.423224) (width 0.1) (layer "F.Cu") (net 143))
  (segment (start 153.965166 126.31106) (end 153.956227 126.314187) (width 0.1) (layer "F.Cu") (net 143))
  (segment (start 154.99 126.31) (end 153.974576 126.31) (width 0.1) (layer "F.Cu") (net 143))
  (segment (start 155.19 126.593667) (end 155.19 126.51) (width 0.1) (layer "F.Cu") (net 143))
  (segment (start 153.941513 126.325921) (end 153.936475 126.333939) (width 0.1) (layer "F.Cu") (net 143))
  (segment (start 155.195014 126.638172) (end 155.19 126.593667) (width 0.1) (layer "F.Cu") (net 143))
  (segment (start 155.584985 126.638172) (end 155.570193 126.680444) (width 0.1) (layer "F.Cu") (net 143))
  (segment (start 153.956227 126.314187) (end 153.948209 126.319225) (width 0.1) (layer "F.Cu") (net 143))
  (segment (start 155.514697 126.750034) (end 155.476776 126.773861) (width 0.1) (layer "F.Cu") (net 143))
  (segment (start 153.354895 126.565339) (end 153.338011 126.517088) (width 0.1) (layer "F.Cu") (net 143))
  (segment (start 155.79 126.31) (end 155.745495 126.315015) (width 0.1) (layer "F.Cu") (net 143))
  (segment (start 153.382093 126.608624) (end 153.354895 126.565339) (width 0.1) (layer "F.Cu") (net 143))
  (segment (start 153.338011 126.517088) (end 153.332288 126.466289) (width 0.1) (layer "F.Cu") (net 143))
  (segment (start 155.076776 126.329807) (end 155.034504 126.315015) (width 0.1) (layer "F.Cu") (net 143))
  (segment (start 153.461525 126.671969) (end 153.41824 126.644771) (width 0.1) (layer "F.Cu") (net 143))
  (segment (start 161.549999 128.8) (end 161.393578 128.8) (width 0.1) (layer "F.Cu") (net 143))
  (segment (start 153.308348 126.314187) (end 153.299409 126.31106) (width 0.1) (layer "F.Cu") (net 143))
  (segment (start 153.948209 126.319225) (end 153.941513 126.325921) (width 0.1) (layer "F.Cu") (net 143))
  (segment (start 161.699999 128.95) (end 161.549999 128.8) (width 0.1) (layer "F.Cu") (net 143))
  (segment (start 161.393578 128.8) (end 158.903578 126.31) (width 0.1) (layer "F.Cu") (net 143))
  (segment (start 148.495 119.653564) (end 150.18125 121.339814) (width 0.1) (layer "F.Cu") (net 143))
  (segment (start 153.754799 126.688853) (end 153.704 126.694577) (width 0.1) (layer "F.Cu") (net 143))
  (segment (start 153.974576 126.31) (end 153.965166 126.31106) (width 0.1) (layer "F.Cu") (net 143))
  (segment (start 155.546366 126.718365) (end 155.514697 126.750034) (width 0.1) (layer "F.Cu") (net 143))
  (segment (start 153.80305 126.671969) (end 153.754799 126.688853) (width 0.1) (layer "F.Cu") (net 143))
  (via (at 150.18125 123.705) (size 0.55) (drill 0.15) (layers "F.Cu" "B.Cu") (net 143))
  (via (at 152.605 126.56625) (size 0.55) (drill 0.15) (layers "F.Cu" "B.Cu") (net 143))
  (segment (start 151.532334 126.3975) (end 152.43625 126.3975) (width 0.15) (layer "In3.Cu") (net 143))
  (segment (start 152.43625 126.3975) (end 152.605 126.56625) (width 0.15) (layer "In3.Cu") (net 143))
  (segment (start 151.0475 122.442666) (end 151.0475 125.912666) (width 0.15) (layer "In3.Cu") (net 143))
  (segment (start 151.0475 125.912666) (end 151.532334 126.3975) (width 0.15) (layer "In3.Cu") (net 143))
  (segment (start 150.947334 122.3425) (end 151.0475 122.442666) (width 0.15) (layer "In3.Cu") (net 143))
  (segment (start 150.0125 122.472666) (end 150.142666 122.3425) (width 0.15) (layer "In3.Cu") (net 143))
  (segment (start 150.0125 123.53625) (end 150.18125 123.705) (width 0.15) (layer "In3.Cu") (net 143))
  (segment (start 150.0125 122.472666) (end 150.0125 123.53625) (width 0.15) (layer "In3.Cu") (net 143))
  (segment (start 150.142666 122.3425) (end 150.947334 122.3425) (width 0.15) (layer "In3.Cu") (net 143))
  (segment (start 153.738011 126.287488) (end 153.732288 126.338287) (width 0.1) (layer "F.Cu") (net 144))
  (segment (start 153.69 126.494577) (end 153.574576 126.494577) (width 0.1) (layer "F.Cu") (net 144))
  (segment (start 153.541513 126.478655) (end 153.536475 126.470637) (width 0.1) (layer "F.Cu") (net 144))
  (segment (start 153.699409 126.493516) (end 153.69 126.494577) (width 0.1) (layer "F.Cu") (net 144))
  (segment (start 161.476422 128.6) (end 158.986422 126.11) (width 0.1) (layer "F.Cu") (net 144))
  (segment (start 153.533348 126.461698) (end 153.532288 126.452289) (width 0.1) (layer "F.Cu") (net 144))
  (segment (start 153.548209 126.485351) (end 153.541513 126.478655) (width 0.1) (layer "F.Cu") (net 144))
  (segment (start 149.743749 121.185171) (end 149.743749 123.430001) (width 0.1) (layer "F.Cu") (net 144))
  (segment (start 148.140011 119.110011) (end 148.140011 119.581433) (width 0.1) (layer "F.Cu") (net 144))
  (segment (start 148.140011 119.581433) (end 149.743749 121.185171) (width 0.1) (layer "F.Cu") (net 144))
  (segment (start 153.909776 126.115723) (end 153.861525 126.132607) (width 0.1) (layer "F.Cu") (net 144))
  (segment (start 161.549999 128.6) (end 161.476422 128.6) (width 0.1) (layer "F.Cu") (net 144))
  (segment (start 153.716366 126.485351) (end 153.708348 126.490389) (width 0.1) (layer "F.Cu") (net 144))
  (segment (start 153.708348 126.490389) (end 153.699409 126.493516) (width 0.1) (layer "F.Cu") (net 144))
  (segment (start 153.532288 126.452289) (end 153.532288 126.338287) (width 0.1) (layer "F.Cu") (net 144))
  (segment (start 149.743749 123.430001) (end 149.46875 123.705) (width 0.1) (layer "F.Cu") (net 144))
  (segment (start 158.986422 126.11) (end 153.960575 126.11) (width 0.1) (layer "F.Cu") (net 144))
  (segment (start 153.731227 126.461698) (end 153.7281 126.470637) (width 0.1) (layer "F.Cu") (net 144))
  (segment (start 147.845 118.815) (end 148.140011 119.110011) (width 0.1) (layer "F.Cu") (net 144))
  (segment (start 161.699999 128.45) (end 161.549999 128.6) (width 0.1) (layer "F.Cu") (net 144))
  (segment (start 153.354799 126.115723) (end 153.304 126.11) (width 0.1) (layer "F.Cu") (net 144))
  (segment (start 153.574576 126.494577) (end 153.565166 126.493516) (width 0.1) (layer "F.Cu") (net 144))
  (segment (start 153.526564 126.287488) (end 153.50968 126.239237) (width 0.1) (layer "F.Cu") (net 144))
  (segment (start 153.556227 126.490389) (end 153.548209 126.485351) (width 0.1) (layer "F.Cu") (net 144))
  (segment (start 153.50968 126.239237) (end 153.482482 126.195952) (width 0.1) (layer "F.Cu") (net 144))
  (segment (start 153.446335 126.159805) (end 153.40305 126.132607) (width 0.1) (layer "F.Cu") (net 144))
  (segment (start 153.536475 126.470637) (end 153.533348 126.461698) (width 0.1) (layer "F.Cu") (net 144))
  (segment (start 153.482482 126.195952) (end 153.446335 126.159805) (width 0.1) (layer "F.Cu") (net 144))
  (segment (start 153.782093 126.195952) (end 153.754895 126.239237) (width 0.1) (layer "F.Cu") (net 144))
  (segment (start 153.723062 126.478655) (end 153.716366 126.485351) (width 0.1) (layer "F.Cu") (net 144))
  (segment (start 153.732288 126.338287) (end 153.732288 126.452289) (width 0.1) (layer "F.Cu") (net 144))
  (segment (start 153.532288 126.338287) (end 153.526564 126.287488) (width 0.1) (layer "F.Cu") (net 144))
  (segment (start 153.81824 126.159805) (end 153.782093 126.195952) (width 0.1) (layer "F.Cu") (net 144))
  (segment (start 153.861525 126.132607) (end 153.81824 126.159805) (width 0.1) (layer "F.Cu") (net 144))
  (segment (start 152.86125 126.11) (end 152.605 125.85375) (width 0.1) (layer "F.Cu") (net 144))
  (segment (start 153.754895 126.239237) (end 153.738011 126.287488) (width 0.1) (layer "F.Cu") (net 144))
  (segment (start 162.6 128.45) (end 161.699999 128.45) (width 0.1) (layer "F.Cu") (net 144))
  (segment (start 153.304 126.11) (end 152.86125 126.11) (width 0.1) (layer "F.Cu") (net 144))
  (segment (start 153.732288 126.452289) (end 153.731227 126.461698) (width 0.1) (layer "F.Cu") (net 144))
  (segment (start 153.40305 126.132607) (end 153.354799 126.115723) (width 0.1) (layer "F.Cu") (net 144))
  (segment (start 153.7281 126.470637) (end 153.723062 126.478655) (width 0.1) (layer "F.Cu") (net 144))
  (segment (start 153.565166 126.493516) (end 153.556227 126.490389) (width 0.1) (layer "F.Cu") (net 144))
  (segment (start 153.960575 126.11) (end 153.909776 126.115723) (width 0.1) (layer "F.Cu") (net 144))
  (via (at 152.605 125.85375) (size 0.55) (drill 0.15) (layers "F.Cu" "B.Cu") (net 144))
  (via (at 149.46875 123.705) (size 0.55) (drill 0.15) (layers "F.Cu" "B.Cu") (net 144))
  (segment (start 152.43625 126.0225) (end 152.605 125.85375) (width 0.15) (layer "In3.Cu") (net 144))
  (segment (start 149.987334 121.9675) (end 151.102666 121.9675) (width 0.15) (layer "In3.Cu") (net 144))
  (segment (start 151.687666 126.0225) (end 152.43625 126.0225) (width 0.15) (layer "In3.Cu") (net 144))
  (segment (start 151.4225 125.757334) (end 151.687666 126.0225) (width 0.15) (layer "In3.Cu") (net 144))
  (segment (start 151.102666 121.9675) (end 151.4225 122.287334) (width 0.15) (layer "In3.Cu") (net 144))
  (segment (start 151.4225 122.287334) (end 151.4225 125.757334) (width 0.15) (layer "In3.Cu") (net 144))
  (segment (start 149.6375 122.317334) (end 149.6375 123.53625) (width 0.15) (layer "In3.Cu") (net 144))
  (segment (start 149.6375 122.317334) (end 149.987334 121.9675) (width 0.15) (layer "In3.Cu") (net 144))
  (segment (start 149.6375 123.53625) (end 149.46875 123.705) (width 0.15) (layer "In3.Cu") (net 144))
  (segment (start 161.549999 127.8) (end 161.699999 127.95) (width 0.1) (layer "F.Cu") (net 145))
  (segment (start 153.670453 124.393862) (end 153.705467 124.421785) (width 0.1) (layer "F.Cu") (net 145))
  (segment (start 153.838603 123.942868) (end 153.670452 124.111018) (width 0.1) (layer "F.Cu") (net 145))
  (segment (start 153.885958 123.73539) (end 153.895923 123.779053) (width 0.1) (layer "F.Cu") (net 145))
  (segment (start 153.895924 123.823839) (end 153.885959 123.867502) (width 0.1) (layer "F.Cu") (net 145))
  (segment (start 153.443093 116.134515) (end 153.443093 116.496907) (width 0.1) (layer "F.Cu") (net 145))
  (segment (start 153.623097 124.318496) (end 153.642528 124.358846) (width 0.1) (layer "F.Cu") (net 145))
  (segment (start 153.623097 124.186384) (end 153.61313 124.230046) (width 0.1) (layer "F.Cu") (net 145))
  (segment (start 148.495 116.215) (end 149.4025 116.215) (width 0.1) (layer "F.Cu") (net 145))
  (segment (start 153.877929 124.441217) (end 153.918281 124.421786) (width 0.1) (layer "F.Cu") (net 145))
  (segment (start 153.425 123.246422) (end 153.838603 123.660025) (width 0.1) (layer "F.Cu") (net 145))
  (segment (start 154.328923 124.178355) (end 154.369275 124.197788) (width 0.1) (layer "F.Cu") (net 145))
  (segment (start 149.465 116.1525) (end 149.658922 116.1525) (width 0.1) (layer "F.Cu") (net 145))
  (segment (start 149.658922 116.1525) (end 149.956422 115.855) (width 0.1) (layer "F.Cu") (net 145))
  (segment (start 153.642529 124.146034) (end 153.623097 124.186384) (width 0.1) (layer "F.Cu") (net 145))
  (segment (start 153.838603 123.660025) (end 153.866527 123.69504) (width 0.1) (layer "F.Cu") (net 145))
  (segment (start 154.156461 124.197787) (end 154.196811 124.178355) (width 0.1) (layer "F.Cu") (net 145))
  (segment (start 153.642528 124.358846) (end 153.670453 124.393862) (width 0.1) (layer "F.Cu") (net 145))
  (segment (start 154.240475 124.16839) (end 154.285261 124.16839) (width 0.1) (layer "F.Cu") (net 145))
  (segment (start 153.885959 123.867502) (end 153.866526 123.907852) (width 0.1) (layer "F.Cu") (net 145))
  (segment (start 154.488578 124.31) (end 157.903578 124.31) (width 0.1) (layer "F.Cu") (net 145))
  (segment (start 153.895923 123.779053) (end 153.895924 123.823839) (width 0.1) (layer "F.Cu") (net 145))
  (segment (start 153.425 121.75125) (end 153.425 123.246422) (width 0.1) (layer "F.Cu") (net 145))
  (segment (start 161.393578 127.8) (end 161.549999 127.8) (width 0.1) (layer "F.Cu") (net 145))
  (segment (start 154.369275 124.197788) (end 154.404289 124.225711) (width 0.1) (layer "F.Cu") (net 145))
  (segment (start 154.196811 124.178355) (end 154.240475 124.16839) (width 0.1) (layer "F.Cu") (net 145))
  (segment (start 153.866526 123.907852) (end 153.838603 123.942868) (width 0.1) (layer "F.Cu") (net 145))
  (segment (start 153.705467 124.421785) (end 153.745819 124.441218) (width 0.1) (layer "F.Cu") (net 145))
  (segment (start 149.4025 116.215) (end 149.465 116.1525) (width 0.1) (layer "F.Cu") (net 145))
  (segment (start 149.956422 115.855) (end 153.163578 115.855) (width 0.1) (layer "F.Cu") (net 145))
  (segment (start 154.404289 124.225711) (end 154.488578 124.31) (width 0.1) (layer "F.Cu") (net 145))
  (segment (start 153.918281 124.421786) (end 153.953295 124.393861) (width 0.1) (layer "F.Cu") (net 145))
  (segment (start 161.699999 127.95) (end 162.6 127.95) (width 0.1) (layer "F.Cu") (net 145))
  (segment (start 154.285261 124.16839) (end 154.328923 124.178355) (width 0.1) (layer "F.Cu") (net 145))
  (segment (start 157.903578 124.31) (end 161.393578 127.8) (width 0.1) (layer "F.Cu") (net 145))
  (segment (start 153.745819 124.441218) (end 153.789482 124.451183) (width 0.1) (layer "F.Cu") (net 145))
  (segment (start 153.789482 124.451183) (end 153.834266 124.451182) (width 0.1) (layer "F.Cu") (net 145))
  (segment (start 153.670452 124.111018) (end 153.642529 124.146034) (width 0.1) (layer "F.Cu") (net 145))
  (segment (start 153.953295 124.393861) (end 154.121447 124.225712) (width 0.1) (layer "F.Cu") (net 145))
  (segment (start 154.121447 124.225712) (end 154.156461 124.197787) (width 0.1) (layer "F.Cu") (net 145))
  (segment (start 153.834266 124.451182) (end 153.877929 124.441217) (width 0.1) (layer "F.Cu") (net 145))
  (segment (start 153.61313 124.274832) (end 153.623097 124.318496) (width 0.1) (layer "F.Cu") (net 145))
  (segment (start 153.163578 115.855) (end 153.443093 116.134515) (width 0.1) (layer "F.Cu") (net 145))
  (segment (start 153.61313 124.230046) (end 153.61313 124.274832) (width 0.1) (layer "F.Cu") (net 145))
  (segment (start 153.866527 123.69504) (end 153.885958 123.73539) (width 0.1) (layer "F.Cu") (net 145))
  (segment (start 153.16875 121.495) (end 153.425 121.75125) (width 0.1) (layer "F.Cu") (net 145))
  (via (at 153.16875 121.495) (size 0.55) (drill 0.15) (layers "F.Cu" "B.Cu") (net 145))
  (via (at 153.443093 116.496907) (size 0.55) (drill 0.15) (layers "F.Cu" "B.Cu") (net 145))
  (segment (start 153.3375 120.807334) (end 153.3375 121.32625) (width 0.15) (layer "In3.Cu") (net 145))
  (segment (start 154.6775 119.467334) (end 153.3375 120.807334) (width 0.15) (layer "In3.Cu") (net 145))
  (segment (start 154.6775 117.492666) (end 153.681741 116.496907) (width 0.15) (layer "In3.Cu") (net 145))
  (segment (start 153.3375 121.32625) (end 153.16875 121.495) (width 0.15) (layer "In3.Cu") (net 145))
  (segment (start 154.6775 119.467334) (end 154.6775 117.492666) (width 0.15) (layer "In3.Cu") (net 145))
  (segment (start 153.681741 116.496907) (end 153.443093 116.496907) (width 0.15) (layer "In3.Cu") (net 145))
  (segment (start 148.17 115.89) (end 149.4025 115.89) (width 0.1) (layer "F.Cu") (net 146))
  (segment (start 161.699999 127.45) (end 162.6 127.45) (width 0.1) (layer "F.Cu") (net 146))
  (segment (start 149.465 115.9525) (end 149.576078 115.9525) (width 0.1) (layer "F.Cu") (net 146))
  (segment (start 153.88125 121.495) (end 153.625 121.75125) (width 0.1) (layer "F.Cu") (net 146))
  (segment (start 157.986422 124.11) (end 161.476422 127.6) (width 0.1) (layer "F.Cu") (net 146))
  (segment (start 161.476422 127.6) (end 161.549999 127.6) (width 0.1) (layer "F.Cu") (net 146))
  (segment (start 149.576078 115.9525) (end 149.873578 115.655) (width 0.1) (layer "F.Cu") (net 146))
  (segment (start 154.571422 124.11) (end 157.986422 124.11) (width 0.1) (layer "F.Cu") (net 146))
  (segment (start 147.845 116.215) (end 148.17 115.89) (width 0.1) (layer "F.Cu") (net 146))
  (segment (start 153.625 121.75125) (end 153.625 123.163578) (width 0.1) (layer "F.Cu") (net 146))
  (segment (start 161.549999 127.6) (end 161.699999 127.45) (width 0.1) (layer "F.Cu") (net 146))
  (segment (start 149.873578 115.655) (end 153.246422 115.655) (width 0.1) (layer "F.Cu") (net 146))
  (segment (start 149.4025 115.89) (end 149.465 115.9525) (width 0.1) (layer "F.Cu") (net 146))
  (segment (start 153.246422 115.655) (end 153.584515 115.993093) (width 0.1) (layer "F.Cu") (net 146))
  (segment (start 153.584515 115.993093) (end 153.946907 115.993093) (width 0.1) (layer "F.Cu") (net 146))
  (segment (start 153.625 123.163578) (end 154.571422 124.11) (width 0.1) (layer "F.Cu") (net 146))
  (via (at 153.88125 121.495) (size 0.55) (drill 0.15) (layers "F.Cu" "B.Cu") (net 146))
  (via (at 153.946907 115.993093) (size 0.55) (drill 0.15) (layers "F.Cu" "B.Cu") (net 146))
  (segment (start 153.7125 121.32625) (end 153.88125 121.495) (width 0.15) (layer "In3.Cu") (net 146))
  (segment (start 155.0525 119.622666) (end 153.7125 120.962666) (width 0.15) (layer "In3.Cu") (net 146))
  (segment (start 155.0525 117.337334) (end 153.946907 116.231741) (width 0.15) (layer "In3.Cu") (net 146))
  (segment (start 153.946907 116.231741) (end 153.946907 115.993093) (width 0.15) (layer "In3.Cu") (net 146))
  (segment (start 153.7125 120.962666) (end 153.7125 121.32625) (width 0.15) (layer "In3.Cu") (net 146))
  (segment (start 155.0525 119.622666) (end 155.0525 117.337334) (width 0.15) (layer "In3.Cu") (net 146))
  (segment (start 161.273617 126.413539) (end 161.352499 126.334656) (width 0.1) (layer "F.Cu") (net 147))
  (segment (start 160.354374 125.91856) (end 160.321382 125.94487) (width 0.1) (layer "F.Cu") (net 147))
  (segment (start 151.644267 119.053433) (end 151.644266 119.075825) (width 0.1) (layer "F.Cu") (net 147))
  (segment (start 159.885491 125.565308) (end 159.9038 125.527289) (width 0.1) (layer "F.Cu") (net 147))
  (segment (start 161.549999 126.8) (end 161.393578 126.8) (width 0.1) (layer "F.Cu") (net 147))
  (segment (start 161.219608 126.567888) (end 161.219608 126.52569) (width 0.1) (layer "F.Cu") (net 147))
  (segment (start 160.495797 126.326483) (end 160.469488 126.293493) (width 0.1) (layer "F.Cu") (net 147))
  (segment (start 159.319803 125.124098) (end 159.310413 125.082958) (width 0.1) (layer "F.Cu") (net 147))
  (segment (start 160.079702 125.061859) (end 159.788686 125.352872) (width 0.1) (layer "F.Cu") (net 147))
  (segment (start 151.258874 119.006447) (end 151.268591 119.026623) (width 0.1) (layer "F.Cu") (net 147))
  (segment (start 159.322981 124.629062) (end 159.280783 124.629062) (width 0.1) (layer "F.Cu") (net 147))
  (segment (start 151.536733 119.245064) (end 151.536734 119.267458) (width 0.1) (layer "F.Cu") (net 147))
  (segment (start 151.406466 119.058092) (end 151.423973 119.04413) (width 0.1) (layer "F.Cu") (net 147))
  (segment (start 159.634337 125.40688) (end 159.593199 125.397492) (width 0.1) (layer "F.Cu") (net 147))
  (segment (start 159.338112 124.961601) (end 159.364422 124.928609) (width 0.1) (layer "F.Cu") (net 147))
  (segment (start 160.88707 126.510558) (end 160.849051 126.528867) (width 0.1) (layer "F.Cu") (net 147))
  (segment (start 151.250856 118.682415) (end 151.27325 118.682416) (width 0.1) (layer "F.Cu") (net 147))
  (segment (start 160.120868 125.944871) (end 160.087876 125.918561) (width 0.1) (layer "F.Cu") (net 147))
  (segment (start 160.087876 125.918561) (end 159.930109 125.760795) (width 0.1) (layer "F.Cu") (net 147))
  (segment (start 159.717675 125.397491) (end 159.676535 125.406881) (width 0.1) (layer "F.Cu") (net 147))
  (segment (start 160.495798 126.059985) (end 160.786811 125.768968) (width 0.1) (layer "F.Cu") (net 147))
  (segment (start 151.615606 119.135339) (end 151.565395 119.185551) (width 0.1) (layer "F.Cu") (net 147))
  (segment (start 151.629568 119.117832) (end 151.615606 119.135339) (width 0.1) (layer "F.Cu") (net 147))
  (segment (start 151.639283 119.097656) (end 151.629568 119.117832) (width 0.1) (layer "F.Cu") (net 147))
  (segment (start 159.876101 125.648646) (end 159.876101 125.606448) (width 0.1) (layer "F.Cu") (net 147))
  (segment (start 151.533698 118.965257) (end 151.556092 118.965258) (width 0.1) (layer "F.Cu") (net 147))
  (segment (start 151.551433 119.309465) (end 151.565395 119.326973) (width 0.1) (layer "F.Cu") (net 147))
  (segment (start 151.342067 119.072791) (end 151.364459 119.07279) (width 0.1) (layer "F.Cu") (net 147))
  (segment (start 159.168632 124.575054) (end 158.845 124.251422) (width 0.1) (layer "F.Cu") (net 147))
  (segment (start 151.541716 119.289289) (end 151.551433 119.309465) (width 0.1) (layer "F.Cu") (net 147))
  (segment (start 151.059225 118.789949) (end 151.081617 118.789948) (width 0.1) (layer "F.Cu") (net 147))
  (segment (start 160.920062 126.484248) (end 160.88707 126.510558) (width 0.1) (layer "F.Cu") (net 147))
  (segment (start 158.845 124.251422) (end 158.845 122.741422) (width 0.1) (layer "F.Cu") (net 147))
  (segment (start 159.676535 125.406881) (end 159.634337 125.40688) (width 0.1) (layer "F.Cu") (net 147))
  (segment (start 151.511867 118.97024) (end 151.533698 118.965257) (width 0.1) (layer "F.Cu") (net 147))
  (segment (start 159.310413 125.04076) (end 159.319803 124.99962) (width 0.1) (layer "F.Cu") (net 147))
  (segment (start 160.200025 125.972568) (end 160.158887 125.96318) (width 0.1) (layer "F.Cu") (net 147))
  (segment (start 160.451179 126.130996) (end 160.469488 126.092977) (width 0.1) (layer "F.Cu") (net 147))
  (segment (start 151.629568 119.011426) (end 151.639283 119.0316) (width 0.1) (layer "F.Cu") (net 147))
  (segment (start 151.356441 118.748758) (end 151.361425 118.770591) (width 0.1) (layer "F.Cu") (net 147))
  (segment (start 151.346726 118.728584) (end 151.356441 118.748758) (width 0.1) (layer "F.Cu") (net 147))
  (segment (start 159.280783 124.629062) (end 159.239643 124.619673) (width 0.1) (layer "F.Cu") (net 147))
  (segment (start 160.807911 126.538257) (end 160.765713 126.538256) (width 0.1) (layer "F.Cu") (net 147))
  (segment (start 159.93011 125.494297) (end 160.221123 125.20328) (width 0.1) (layer "F.Cu") (net 147))
  (segment (start 151.30006 119.058092) (end 151.320234 119.067807) (width 0.1) (layer "F.Cu") (net 147))
  (segment (start 151.268591 118.920217) (end 151.258874 118.940391) (width 0.1) (layer "F.Cu") (net 147))
  (segment (start 151.282553 119.044131) (end 151.30006 119.058092) (width 0.1) (layer "F.Cu") (net 147))
  (segment (start 151.551433 119.203059) (end 151.541716 119.223233) (width 0.1) (layer "F.Cu") (net 147))
  (segment (start 151.315257 118.697115) (end 151.332765 118.711077) (width 0.1) (layer "F.Cu") (net 147))
  (segment (start 159.9038 125.527289) (end 159.93011 125.494297) (width 0.1) (layer "F.Cu") (net 147))
  (segment (start 160.765713 126.538256) (end 160.724575 126.528868) (width 0.1) (layer "F.Cu") (net 147))
  (segment (start 151.191343 118.711077) (end 151.208851 118.697115) (width 0.1) (layer "F.Cu") (net 147))
  (segment (start 151.253891 118.962222) (end 151.253892 118.984616) (width 0.1) (layer "F.Cu") (net 147))
  (segment (start 151.361424 118.792983) (end 151.356441 118.814814) (width 0.1) (layer "F.Cu") (net 147))
  (segment (start 159.40214 124.601364) (end 159.364121 124.619673) (width 0.1) (layer "F.Cu") (net 147))
  (segment (start 160.321382 125.94487) (end 160.283363 125.963179) (width 0.1) (layer "F.Cu") (net 147))
  (segment (start 158.845 122.741422) (end 158.413578 122.31) (width 0.1) (layer "F.Cu") (net 147))
  (segment (start 151.364459 119.07279) (end 151.38629 119.067807) (width 0.1) (layer "F.Cu") (net 147))
  (segment (start 159.319803 124.99962) (end 159.338112 124.961601) (width 0.1) (layer "F.Cu") (net 147))
  (segment (start 160.451179 126.255474) (end 160.441789 126.214334) (width 0.1) (layer "F.Cu") (net 147))
  (segment (start 151.141131 118.761288) (end 151.191343 118.711077) (width 0.1) (layer "F.Cu") (net 147))
  (segment (start 159.876101 125.606448) (end 159.885491 125.565308) (width 0.1) (layer "F.Cu") (net 147))
  (segment (start 160.158887 125.96318) (end 160.120868 125.944871) (width 0.1) (layer "F.Cu") (net 147))
  (segment (start 161.247307 126.647047) (end 161.228998 126.609028) (width 0.1) (layer "F.Cu") (net 147))
  (segment (start 151.639283 119.0316) (end 151.644267 119.053433) (width 0.1) (layer "F.Cu") (net 147))
  (segment (start 159.435131 124.575054) (end 159.40214 124.601364) (width 0.1) (layer "F.Cu") (net 147))
  (segment (start 151.565395 119.326973) (end 151.715 119.476578) (width 0.1) (layer "F.Cu") (net 147))
  (segment (start 159.522188 125.352873) (end 159.364421 125.195107) (width 0.1) (layer "F.Cu") (net 147))
  (segment (start 161.393578 126.8) (end 161.273617 126.680038) (width 0.1) (layer "F.Cu") (net 147))
  (segment (start 160.283363 125.963179) (end 160.242223 125.972569) (width 0.1) (layer "F.Cu") (net 147))
  (segment (start 159.593199 125.397492) (end 159.55518 125.379183) (width 0.1) (layer "F.Cu") (net 147))
  (segment (start 151.577923 118.97024) (end 151.598099 118.979957) (width 0.1) (layer "F.Cu") (net 147))
  (segment (start 159.9038 125.727805) (end 159.885491 125.689786) (width 0.1) (layer "F.Cu") (net 147))
  (segment (start 151.332764 118.852497) (end 151.282553 118.902709) (width 0.1) (layer "F.Cu") (net 147))
  (segment (start 158.413578 122.31) (end 155.986258 122.31) (width 0.1) (layer "F.Cu") (net 147))
  (segment (start 160.786811 125.768968) (end 160.64539 125.627547) (width 0.1) (layer "F.Cu") (net 147))
  (segment (start 159.364422 124.928609) (end 159.655435 124.637592) (width 0.1) (layer "F.Cu") (net 147))
  (segment (start 151.081617 118.789948) (end 151.103448 118.784965) (width 0.1) (layer "F.Cu") (net 147))
  (segment (start 151.536734 119.267458) (end 151.541716 119.289289) (width 0.1) (layer "F.Cu") (net 147))
  (segment (start 148.495 118.165) (end 149.4075 118.165) (width 0.1) (layer "F.Cu") (net 147))
  (segment (start 159.755694 125.379182) (end 159.717675 125.397491) (width 0.1) (layer "F.Cu") (net 147))
  (segment (start 151.229025 118.687398) (end 151.250856 118.682415) (width 0.1) (layer "F.Cu") (net 147))
  (segment (start 149.4075 118.165) (end 149.47 118.2275) (width 0.1) (layer "F.Cu") (net 147))
  (segment (start 151.491693 118.979957) (end 151.511867 118.97024) (width 0.1) (layer "F.Cu") (net 147))
  (segment (start 151.565395 119.185551) (end 151.551433 119.203059) (width 0.1) (layer "F.Cu") (net 147))
  (segment (start 151.268591 119.026623) (end 151.282553 119.044131) (width 0.1) (layer "F.Cu") (net 147))
  (segment (start 150.996907 121.014515) (end 150.996907 121.376907) (width 0.1) (layer "F.Cu") (net 147))
  (segment (start 151.361425 118.770591) (end 151.361424 118.792983) (width 0.1) (layer "F.Cu") (net 147))
  (segment (start 151.423973 119.04413) (end 151.474185 118.993919) (width 0.1) (layer "F.Cu") (net 147))
  (segment (start 155.986258 122.31) (end 155.730008 122.56625) (width 0.1) (layer "F.Cu") (net 147))
  (segment (start 160.441789 126.172136) (end 160.451179 126.130996) (width 0.1) (layer "F.Cu") (net 147))
  (segment (start 161.228998 126.609028) (end 161.219608 126.567888) (width 0.1) (layer "F.Cu") (net 147))
  (segment (start 150.465922 118.2275) (end 150.999711 118.761289) (width 0.1) (layer "F.Cu") (net 147))
  (segment (start 151.346726 118.83499) (end 151.332764 118.852497) (width 0.1) (layer "F.Cu") (net 147))
  (segment (start 160.686556 126.510559) (end 160.653564 126.484249) (width 0.1) (layer "F.Cu") (net 147))
  (segment (start 151.253892 118.984616) (end 151.258874 119.006447) (width 0.1) (layer "F.Cu") (net 147))
  (segment (start 151.208851 118.697115) (end 151.229025 118.687398) (width 0.1) (layer "F.Cu") (net 147))
  (segment (start 150.999711 118.761289) (end 151.017218 118.77525) (width 0.1) (layer "F.Cu") (net 147))
  (segment (start 161.247307 126.446531) (end 161.273617 126.413539) (width 0.1) (layer "F.Cu") (net 147))
  (segment (start 159.239643 124.619673) (end 159.201624 124.601364) (width 0.1) (layer "F.Cu") (net 147))
  (segment (start 161.211078 126.193234) (end 160.920062 126.484248) (width 0.1) (layer "F.Cu") (net 147))
  (segment (start 151.556092 118.965258) (end 151.577923 118.97024) (width 0.1) (layer "F.Cu") (net 147))
  (segment (start 159.338112 125.162117) (end 159.319803 125.124098) (width 0.1) (layer "F.Cu") (net 147))
  (segment (start 151.38629 119.067807) (end 151.406466 119.058092) (width 0.1) (layer "F.Cu") (net 147))
  (segment (start 151.356441 118.814814) (end 151.346726 118.83499) (width 0.1) (layer "F.Cu") (net 147))
  (segment (start 161.699999 126.95) (end 161.549999 126.8) (width 0.1) (layer "F.Cu") (net 147))
  (segment (start 160.469488 126.092977) (end 160.495798 126.059985) (width 0.1) (layer "F.Cu") (net 147))
  (segment (start 151.541716 119.223233) (end 151.536733 119.245064) (width 0.1) (layer "F.Cu") (net 147))
  (segment (start 159.930109 125.760795) (end 159.9038 125.727805) (width 0.1) (layer "F.Cu") (net 147))
  (segment (start 159.364421 125.195107) (end 159.338112 125.162117) (width 0.1) (layer "F.Cu") (net 147))
  (segment (start 159.364121 124.619673) (end 159.322981 124.629062) (width 0.1) (layer "F.Cu") (net 147))
  (segment (start 162.6 126.95) (end 161.699999 126.95) (width 0.1) (layer "F.Cu") (net 147))
  (segment (start 160.221123 125.20328) (end 160.079702 125.061859) (width 0.1) (layer "F.Cu") (net 147))
  (segment (start 151.615607 118.993919) (end 151.629568 119.011426) (width 0.1) (layer "F.Cu") (net 147))
  (segment (start 151.715 120.296422) (end 150.996907 121.014515) (width 0.1) (layer "F.Cu") (net 147))
  (segment (start 160.441789 126.214334) (end 160.441789 126.172136) (width 0.1) (layer "F.Cu") (net 147))
  (segment (start 159.788686 125.352872) (end 159.755694 125.379182) (width 0.1) (layer "F.Cu") (net 147))
  (segment (start 151.103448 118.784965) (end 151.123624 118.77525) (width 0.1) (layer "F.Cu") (net 147))
  (segment (start 159.55518 125.379183) (end 159.522188 125.352873) (width 0.1) (layer "F.Cu") (net 147))
  (segment (start 160.724575 126.528868) (end 160.686556 126.510559) (width 0.1) (layer "F.Cu") (net 147))
  (segment (start 159.201624 124.601364) (end 159.168632 124.575054) (width 0.1) (layer "F.Cu") (net 147))
  (segment (start 151.27325 118.682416) (end 151.295081 118.687398) (width 0.1) (layer "F.Cu") (net 147))
  (segment (start 151.715 119.476578) (end 151.715 120.296422) (width 0.1) (layer "F.Cu") (net 147))
  (segment (start 160.849051 126.528867) (end 160.807911 126.538257) (width 0.1) (layer "F.Cu") (net 147))
  (segment (start 160.242223 125.972569) (end 160.200025 125.972568) (width 0.1) (layer "F.Cu") (net 147))
  (segment (start 151.282553 118.902709) (end 151.268591 118.920217) (width 0.1) (layer "F.Cu") (net 147))
  (segment (start 149.47 118.2275) (end 150.465922 118.2275) (width 0.1) (layer "F.Cu") (net 147))
  (segment (start 160.653564 126.484249) (end 160.495797 126.326483) (width 0.1) (layer "F.Cu") (net 147))
  (segment (start 161.219608 126.52569) (end 161.228998 126.48455) (width 0.1) (layer "F.Cu") (net 147))
  (segment (start 160.64539 125.627547) (end 160.354374 125.91856) (width 0.1) (layer "F.Cu") (net 147))
  (segment (start 161.273617 126.680038) (end 161.247307 126.647047) (width 0.1) (layer "F.Cu") (net 147))
  (segment (start 151.123624 118.77525) (end 151.141131 118.761288) (width 0.1) (layer "F.Cu") (net 147))
  (segment (start 151.037392 118.784965) (end 151.059225 118.789949) (width 0.1) (layer "F.Cu") (net 147))
  (segment (start 159.885491 125.689786) (end 159.876101 125.648646) (width 0.1) (layer "F.Cu") (net 147))
  (segment (start 160.469488 126.293493) (end 160.451179 126.255474) (width 0.1) (layer "F.Cu") (net 147))
  (segment (start 151.258874 118.940391) (end 151.253891 118.962222) (width 0.1) (layer "F.Cu") (net 147))
  (segment (start 151.332765 118.711077) (end 151.346726 118.728584) (width 0.1) (layer "F.Cu") (net 147))
  (segment (start 161.352499 126.334656) (end 161.211078 126.193234) (width 0.1) (layer "F.Cu") (net 147))
  (segment (start 151.320234 119.067807) (end 151.342067 119.072791) (width 0.1) (layer "F.Cu") (net 147))
  (segment (start 151.598099 118.979957) (end 151.615607 118.993919) (width 0.1) (layer "F.Cu") (net 147))
  (segment (start 159.655435 124.637592) (end 159.514014 124.496171) (width 0.1) (layer "F.Cu") (net 147))
  (segment (start 151.017218 118.77525) (end 151.037392 118.784965) (width 0.1) (layer "F.Cu") (net 147))
  (segment (start 151.295081 118.687398) (end 151.315257 118.697115) (width 0.1) (layer "F.Cu") (net 147))
  (segment (start 151.644266 119.075825) (end 151.639283 119.097656) (width 0.1) (layer "F.Cu") (net 147))
  (segment (start 159.310413 125.082958) (end 159.310413 125.04076) (width 0.1) (layer "F.Cu") (net 147))
  (segment (start 159.514014 124.496171) (end 159.435131 124.575054) (width 0.1) (layer "F.Cu") (net 147))
  (segment (start 161.228998 126.48455) (end 161.247307 126.446531) (width 0.1) (layer "F.Cu") (net 147))
  (segment (start 151.474185 118.993919) (end 151.491693 118.979957) (width 0.1) (layer "F.Cu") (net 147))
  (via (at 150.996907 121.376907) (size 0.55) (drill 0.15) (layers "F.Cu" "B.Cu") (net 147))
  (via (at 155.730008 122.56625) (size 0.55) (drill 0.15) (layers "F.Cu" "B.Cu") (net 147))
  (segment (start 153.232334 123.1085) (end 154.401666 123.1085) (width 0.125) (layer "In3.Cu") (net 147))
  (segment (start 151.371927 121.248093) (end 153.232334 123.1085) (width 0.125) (layer "In3.Cu") (net 147))
  (segment (start 150.996907 121.376907) (end 151.125721 121.248093) (width 0.125) (layer "In3.Cu") (net 147))
  (segment (start 155.112666 122.3975) (end 155.561258 122.3975) (width 0.125) (layer "In3.Cu") (net 147))
  (segment (start 151.125721 121.248093) (end 151.371927 121.248093) (width 0.125) (layer "In3.Cu") (net 147))
  (segment (start 154.401666 123.1085) (end 155.112666 122.3975) (width 0.125) (layer "In3.Cu") (net 147))
  (segment (start 155.561258 122.3975) (end 155.730008 122.56625) (width 0.125) (layer "In3.Cu") (net 147))
  (segment (start 159.045 122.658578) (end 158.496422 122.11) (width 0.1) (layer "F.Cu") (net 148))
  (segment (start 159.576253 124.301958) (end 159.535113 124.292568) (width 0.1) (layer "F.Cu") (net 148))
  (segment (start 159.831338 124.73785) (end 159.849647 124.699831) (width 0.1) (layer "F.Cu") (net 148))
  (segment (start 160.100801 124.858256) (end 160.058603 124.858256) (width 0.1) (layer "F.Cu") (net 148))
  (segment (start 147.845 118.165) (end 148.17 118.49) (width 0.1) (layer "F.Cu") (net 148))
  (segment (start 161.273317 125.999022) (end 161.232177 125.989632) (width 0.1) (layer "F.Cu") (net 148))
  (segment (start 148.17 118.49) (end 149.4075 118.49) (width 0.1) (layer "F.Cu") (net 148))
  (segment (start 160.981023 125.70673) (end 160.962714 125.668711) (width 0.1) (layer "F.Cu") (net 148))
  (segment (start 159.831338 124.537335) (end 159.805028 124.504343) (width 0.1) (layer "F.Cu") (net 148))
  (segment (start 151.515 120.213578) (end 150.855485 120.873093) (width 0.1) (layer "F.Cu") (net 148))
  (segment (start 149.47 118.4275) (end 150.383078 118.4275) (width 0.1) (layer "F.Cu") (net 148))
  (segment (start 160.212951 124.912265) (end 160.17996 124.885955) (width 0.1) (layer "F.Cu") (net 148))
  (segment (start 160.962714 125.869226) (end 160.981023 125.831207) (width 0.1) (layer "F.Cu") (net 148))
  (segment (start 159.859037 124.658691) (end 159.859037 124.616494) (width 0.1) (layer "F.Cu") (net 148))
  (segment (start 155.986258 122.11) (end 155.730008 121.85375) (width 0.1) (layer "F.Cu") (net 148))
  (segment (start 160.962714 125.668711) (end 160.936404 125.635719) (width 0.1) (layer "F.Cu") (net 148))
  (segment (start 160.583151 125.433334) (end 160.545132 125.451643) (width 0.1) (layer "F.Cu") (net 148))
  (segment (start 149.4075 118.49) (end 149.47 118.4275) (width 0.1) (layer "F.Cu") (net 148))
  (segment (start 160.990413 125.790067) (end 160.990413 125.74787) (width 0.1) (layer "F.Cu") (net 148))
  (segment (start 159.451775 124.301958) (end 159.413756 124.320267) (width 0.1) (layer "F.Cu") (net 148))
  (segment (start 162.6 126.45) (end 161.699999 126.45) (width 0.1) (layer "F.Cu") (net 148))
  (segment (start 161.344327 126.043641) (end 161.311336 126.017331) (width 0.1) (layer "F.Cu") (net 148))
  (segment (start 160.51214 125.477953) (end 160.221125 125.768968) (width 0.1) (layer "F.Cu") (net 148))
  (segment (start 160.424725 125.182182) (end 160.415335 125.141042) (width 0.1) (layer "F.Cu") (net 148))
  (segment (start 160.645392 126.193235) (end 160.936404 125.902218) (width 0.1) (layer "F.Cu") (net 148))
  (segment (start 160.079704 125.627547) (end 160.370716 125.33653) (width 0.1) (layer "F.Cu") (net 148))
  (segment (start 161.546712 126.396896) (end 161.556102 126.355756) (width 0.1) (layer "F.Cu") (net 148))
  (segment (start 159.301881 124.425459) (end 159.045 124.168578) (width 0.1) (layer "F.Cu") (net 148))
  (segment (start 161.546712 126.272418) (end 161.528403 126.234399) (width 0.1) (layer "F.Cu") (net 148))
  (segment (start 159.045 124.168578) (end 159.045 122.658578) (width 0.1) (layer "F.Cu") (net 148))
  (segment (start 160.624291 125.423944) (end 160.583151 125.433334) (width 0.1) (layer "F.Cu") (net 148))
  (segment (start 159.849647 124.699831) (end 159.859037 124.658691) (width 0.1) (layer "F.Cu") (net 148))
  (segment (start 160.370716 125.070031) (end 160.212951 124.912265) (width 0.1) (layer "F.Cu") (net 148))
  (segment (start 160.936404 125.902218) (end 160.962714 125.869226) (width 0.1) (layer "F.Cu") (net 148))
  (segment (start 160.981023 125.831207) (end 160.990413 125.790067) (width 0.1) (layer "F.Cu") (net 148))
  (segment (start 160.778639 125.477953) (end 160.745648 125.451643) (width 0.1) (layer "F.Cu") (net 148))
  (segment (start 159.614272 124.320267) (end 159.576253 124.301958) (width 0.1) (layer "F.Cu") (net 148))
  (segment (start 160.017463 124.867646) (end 159.979444 124.885955) (width 0.1) (layer "F.Cu") (net 148))
  (segment (start 159.492915 124.292568) (end 159.451775 124.301958) (width 0.1) (layer "F.Cu") (net 148))
  (segment (start 160.141941 124.867646) (end 160.100801 124.858256) (width 0.1) (layer "F.Cu") (net 148))
  (segment (start 161.502093 126.201407) (end 161.344327 126.043641) (width 0.1) (layer "F.Cu") (net 148))
  (segment (start 150.855485 120.873093) (end 150.493093 120.873093) (width 0.1) (layer "F.Cu") (net 148))
  (segment (start 161.148839 125.999022) (end 161.11082 126.017331) (width 0.1) (layer "F.Cu") (net 148))
  (segment (start 161.476422 126.6) (end 161.42321 126.546789) (width 0.1) (layer "F.Cu") (net 148))
  (segment (start 159.514016 125.061859) (end 159.805028 124.770842) (width 0.1) (layer "F.Cu") (net 148))
  (segment (start 159.805028 124.504343) (end 159.647263 124.346577) (width 0.1) (layer "F.Cu") (net 148))
  (segment (start 150.383078 118.4275) (end 151.515 119.559422) (width 0.1) (layer "F.Cu") (net 148))
  (segment (start 160.397026 125.103023) (end 160.370716 125.070031) (width 0.1) (layer "F.Cu") (net 148))
  (segment (start 151.515 119.559422) (end 151.515 120.213578) (width 0.1) (layer "F.Cu") (net 148))
  (segment (start 159.946452 124.912265) (end 159.655437 125.20328) (width 0.1) (layer "F.Cu") (net 148))
  (segment (start 161.528403 126.234399) (end 161.502093 126.201407) (width 0.1) (layer "F.Cu") (net 148))
  (segment (start 161.189979 125.989632) (end 161.148839 125.999022) (width 0.1) (layer "F.Cu") (net 148))
  (segment (start 160.707629 125.433334) (end 160.666489 125.423944) (width 0.1) (layer "F.Cu") (net 148))
  (segment (start 159.805028 124.770842) (end 159.831338 124.73785) (width 0.1) (layer "F.Cu") (net 148))
  (segment (start 159.535113 124.292568) (end 159.492915 124.292568) (width 0.1) (layer "F.Cu") (net 148))
  (segment (start 159.647263 124.346577) (end 159.614272 124.320267) (width 0.1) (layer "F.Cu") (net 148))
  (segment (start 160.545132 125.451643) (end 160.51214 125.477953) (width 0.1) (layer "F.Cu") (net 148))
  (segment (start 160.415335 125.141042) (end 160.397026 125.103023) (width 0.1) (layer "F.Cu") (net 148))
  (segment (start 158.496422 122.11) (end 155.986258 122.11) (width 0.1) (layer "F.Cu") (net 148))
  (segment (start 160.415335 125.265519) (end 160.424725 125.224379) (width 0.1) (layer "F.Cu") (net 148))
  (segment (start 161.502093 126.467906) (end 161.528403 126.434915) (width 0.1) (layer "F.Cu") (net 148))
  (segment (start 161.11082 126.017331) (end 161.077828 126.043641) (width 0.1) (layer "F.Cu") (net 148))
  (segment (start 161.232177 125.989632) (end 161.189979 125.989632) (width 0.1) (layer "F.Cu") (net 148))
  (segment (start 160.058603 124.858256) (end 160.017463 124.867646) (width 0.1) (layer "F.Cu") (net 148))
  (segment (start 160.397026 125.303538) (end 160.415335 125.265519) (width 0.1) (layer "F.Cu") (net 148))
  (segment (start 160.424725 125.224379) (end 160.424725 125.182182) (width 0.1) (layer "F.Cu") (net 148))
  (segment (start 161.42321 126.546789) (end 161.502093 126.467906) (width 0.1) (layer "F.Cu") (net 148))
  (segment (start 161.077828 126.043641) (end 160.786813 126.334656) (width 0.1) (layer "F.Cu") (net 148))
  (segment (start 160.17996 124.885955) (end 160.141941 124.867646) (width 0.1) (layer "F.Cu") (net 148))
  (segment (start 160.990413 125.74787) (end 160.981023 125.70673) (width 0.1) (layer "F.Cu") (net 148))
  (segment (start 159.413756 124.320267) (end 159.380764 124.346577) (width 0.1) (layer "F.Cu") (net 148))
  (segment (start 160.666489 125.423944) (end 160.624291 125.423944) (width 0.1) (layer "F.Cu") (net 148))
  (segment (start 161.549999 126.6) (end 161.476422 126.6) (width 0.1) (layer "F.Cu") (net 148))
  (segment (start 161.699999 126.45) (end 161.549999 126.6) (width 0.1) (layer "F.Cu") (net 148))
  (segment (start 161.556102 126.313558) (end 161.546712 126.272418) (width 0.1) (layer "F.Cu") (net 148))
  (segment (start 161.556102 126.355756) (end 161.556102 126.313558) (width 0.1) (layer "F.Cu") (net 148))
  (segment (start 159.849647 124.575354) (end 159.831338 124.537335) (width 0.1) (layer "F.Cu") (net 148))
  (segment (start 161.528403 126.434915) (end 161.546712 126.396896) (width 0.1) (layer "F.Cu") (net 148))
  (segment (start 159.380764 124.346577) (end 159.301881 124.425459) (width 0.1) (layer "F.Cu") (net 148))
  (segment (start 159.979444 124.885955) (end 159.946452 124.912265) (width 0.1) (layer "F.Cu") (net 148))
  (segment (start 160.221125 125.768968) (end 160.079704 125.627547) (width 0.1) (layer "F.Cu") (net 148))
  (segment (start 160.745648 125.451643) (end 160.707629 125.433334) (width 0.1) (layer "F.Cu") (net 148))
  (segment (start 159.655437 125.20328) (end 159.514016 125.061859) (width 0.1) (layer "F.Cu") (net 148))
  (segment (start 159.859037 124.616494) (end 159.849647 124.575354) (width 0.1) (layer "F.Cu") (net 148))
  (segment (start 161.311336 126.017331) (end 161.273317 125.999022) (width 0.1) (layer "F.Cu") (net 148))
  (segment (start 160.936404 125.635719) (end 160.778639 125.477953) (width 0.1) (layer "F.Cu") (net 148))
  (segment (start 160.370716 125.33653) (end 160.397026 125.303538) (width 0.1) (layer "F.Cu") (net 148))
  (segment (start 160.786813 126.334656) (end 160.645392 126.193235) (width 0.1) (layer "F.Cu") (net 148))
  (via (at 150.493093 120.873093) (size 0.55) (drill 0.15) (layers "F.Cu" "B.Cu") (net 148))
  (via (at 155.730008 121.85375) (size 0.55) (drill 0.15) (layers "F.Cu" "B.Cu") (net 148))
  (segment (start 154.246334 122.7335) (end 154.957334 122.0225) (width 0.125) (layer "In3.Cu") (net 148))
  (segment (start 155.561258 122.0225) (end 155.730008 121.85375) (width 0.125) (layer "In3.Cu") (net 148))
  (segment (start 154.957334 122.0225) (end 155.561258 122.0225) (width 0.125) (layer "In3.Cu") (net 148))
  (segment (start 151.527259 120.873093) (end 153.387666 122.7335) (width 0.125) (layer "In3.Cu") (net 148))
  (segment (start 150.493093 120.873093) (end 151.527259 120.873093) (width 0.125) (layer "In3.Cu") (net 148))
  (segment (start 153.387666 122.7335) (end 154.246334 122.7335) (width 0.125) (layer "In3.Cu") (net 148))
  (segment (start 154.68 118.935686) (end 154.657747 118.938194) (width 0.1) (layer "F.Cu") (net 149))
  (segment (start 155.516425 120.426621) (end 155.512665 120.46) (width 0.1) (layer "F.Cu") (net 149))
  (segment (start 154.589903 118.992298) (end 154.582507 119.013434) (width 0.1) (layer "F.Cu") (net 149))
  (segment (start 153.88 120.31) (end 153.658578 120.31) (width 0.1) (layer "F.Cu") (net 149))
  (segment (start 150.04875 116.8025) (end 150.305 117.05875) (width 0.1) (layer "F.Cu") (net 149))
  (segment (start 154.262665 120.934314) (end 154.199766 120.927226) (width 0.1) (layer "F.Cu") (net 149))
  (segment (start 155.512665 120.827043) (end 155.508904 120.860421) (width 0.1) (layer "F.Cu") (net 149))
  (segment (start 154.360233 120.927226) (end 154.297334 120.934314) (width 0.1) (layer "F.Cu") (net 149))
  (segment (start 154.041668 120.827887) (end 154.007992 120.774292) (width 0.1) (layer "F.Cu") (net 149))
  (segment (start 154.787087 120.090234) (end 154.78 120.027335) (width 0.1) (layer "F.Cu") (net 149))
  (segment (start 155.427747 120.962188) (end 155.396043 120.973282) (width 0.1) (layer "F.Cu") (net 149))
  (segment (start 154.58 119.035686) (end 154.58 120.651648) (width 0.1) (layer "F.Cu") (net 149))
  (segment (start 154.723388 118.94559) (end 154.702252 118.938194) (width 0.1) (layer "F.Cu") (net 149))
  (segment (start 154.78 120.027335) (end 154.78 119.035686) (width 0.1) (layer "F.Cu") (net 149))
  (segment (start 155.208904 120.426621) (end 155.19781 120.394917) (width 0.1) (layer "F.Cu") (net 149))
  (segment (start 155.24539 120.920566) (end 155.227519 120.892125) (width 0.1) (layer "F.Cu") (net 149))
  (segment (start 155.179939 120.366476) (end 155.156188 120.342725) (width 0.1) (layer "F.Cu") (net 149))
  (segment (start 155.49781 120.892125) (end 155.479939 120.920566) (width 0.1) (layer "F.Cu") (net 149))
  (segment (start 154.770096 118.992298) (end 154.758183 118.973338) (width 0.1) (layer "F.Cu") (net 149))
  (segment (start 155.569141 120.342725) (end 155.54539 120.366476) (width 0.1) (layer "F.Cu") (net 149))
  (segment (start 159.425 121.111422) (end 158.623578 120.31) (width 0.1) (layer "F.Cu") (net 149))
  (segment (start 154.742348 118.957503) (end 154.723388 118.94559) (width 0.1) (layer "F.Cu") (net 149))
  (segment (start 161.549999 125.8) (end 161.413578 125.8) (width 0.1) (layer "F.Cu") (net 149))
  (segment (start 153.923388 120.319903) (end 153.902252 120.312507) (width 0.1) (layer "F.Cu") (net 149))
  (segment (start 154.78 119.035686) (end 154.777492 119.013434) (width 0.1) (layer "F.Cu") (net 149))
  (segment (start 153.987087 120.714547) (end 153.98 120.651648) (width 0.1) (layer "F.Cu") (net 149))
  (segment (start 155.527519 120.394917) (end 155.516425 120.426621) (width 0.1) (layer "F.Cu") (net 149))
  (segment (start 154.657747 118.938194) (end 154.636611 118.94559) (width 0.1) (layer "F.Cu") (net 149))
  (segment (start 153.977492 120.387747) (end 153.970096 120.366611) (width 0.1) (layer "F.Cu") (net 149))
  (segment (start 154.552007 120.774292) (end 154.518331 120.827887) (width 0.1) (layer "F.Cu") (net 149))
  (segment (start 154.572912 120.714547) (end 154.552007 120.774292) (width 0.1) (layer "F.Cu") (net 149))
  (segment (start 155.19781 120.394917) (end 155.179939 120.366476) (width 0.1) (layer "F.Cu") (net 149))
  (segment (start 153.98 120.41) (end 153.977492 120.387747) (width 0.1) (layer "F.Cu") (net 149))
  (segment (start 154.199766 120.927226) (end 154.140021 120.906321) (width 0.1) (layer "F.Cu") (net 149))
  (segment (start 154.297334 120.934314) (end 154.262665 120.934314) (width 0.1) (layer "F.Cu") (net 149))
  (segment (start 155.54539 120.366476) (end 155.527519 120.394917) (width 0.1) (layer "F.Cu") (net 149))
  (segment (start 153.445 119.66125) (end 153.18875 119.405) (width 0.1) (layer "F.Cu") (net 149))
  (segment (start 154.777492 119.013434) (end 154.770096 118.992298) (width 0.1) (layer "F.Cu") (net 149))
  (segment (start 155.456188 120.944317) (end 155.427747 120.962188) (width 0.1) (layer "F.Cu") (net 149))
  (segment (start 155.127747 120.324854) (end 155.096043 120.31376) (width 0.1) (layer "F.Cu") (net 149))
  (segment (start 158.623578 120.31) (end 155.662665 120.31) (width 0.1) (layer "F.Cu") (net 149))
  (segment (start 154.702252 118.938194) (end 154.68 118.935686) (width 0.1) (layer "F.Cu") (net 149))
  (segment (start 153.970096 120.366611) (end 153.958183 120.347651) (width 0.1) (layer "F.Cu") (net 149))
  (segment (start 155.096043 120.31376) (end 154.999766 120.302913) (width 0.1) (layer "F.Cu") (net 149))
  (segment (start 155.269141 120.944317) (end 155.24539 120.920566) (width 0.1) (layer "F.Cu") (net 149))
  (segment (start 159.425 123.811422) (end 159.425 121.111422) (width 0.1) (layer "F.Cu") (net 149))
  (segment (start 154.807992 120.149979) (end 154.787087 120.090234) (width 0.1) (layer "F.Cu") (net 149))
  (segment (start 154.518331 120.827887) (end 154.473573 120.872645) (width 0.1) (layer "F.Cu") (net 149))
  (segment (start 149.085 116.8025) (end 150.04875 116.8025) (width 0.1) (layer "F.Cu") (net 149))
  (segment (start 154.58 120.651648) (end 154.572912 120.714547) (width 0.1) (layer "F.Cu") (net 149))
  (segment (start 155.479939 120.920566) (end 155.456188 120.944317) (width 0.1) (layer "F.Cu") (net 149))
  (segment (start 162.6 125.95) (end 161.699999 125.95) (width 0.1) (layer "F.Cu") (net 149))
  (segment (start 154.601816 118.973338) (end 154.589903 118.992298) (width 0.1) (layer "F.Cu") (net 149))
  (segment (start 154.886426 120.248332) (end 154.841668 120.203574) (width 0.1) (layer "F.Cu") (net 149))
  (segment (start 154.582507 119.013434) (end 154.58 119.035686) (width 0.1) (layer "F.Cu") (net 149))
  (segment (start 154.140021 120.906321) (end 154.086426 120.872645) (width 0.1) (layer "F.Cu") (net 149))
  (segment (start 154.999766 120.302913) (end 154.940021 120.282008) (width 0.1) (layer "F.Cu") (net 149))
  (segment (start 153.98 120.651648) (end 153.98 120.41) (width 0.1) (layer "F.Cu") (net 149))
  (segment (start 155.212665 120.827043) (end 155.212665 120.46) (width 0.1) (layer "F.Cu") (net 149))
  (segment (start 154.841668 120.203574) (end 154.807992 120.149979) (width 0.1) (layer "F.Cu") (net 149))
  (segment (start 153.445 120.096422) (end 153.445 119.66125) (width 0.1) (layer "F.Cu") (net 149))
  (segment (start 161.413578 125.8) (end 159.425 123.811422) (width 0.1) (layer "F.Cu") (net 149))
  (segment (start 155.362665 120.977043) (end 155.329286 120.973282) (width 0.1) (layer "F.Cu") (net 149))
  (segment (start 153.958183 120.347651) (end 153.942348 120.331816) (width 0.1) (layer "F.Cu") (net 149))
  (segment (start 148.495 116.865) (end 149.0225 116.865) (width 0.1) (layer "F.Cu") (net 149))
  (segment (start 155.227519 120.892125) (end 155.216425 120.860421) (width 0.1) (layer "F.Cu") (net 149))
  (segment (start 155.216425 120.860421) (end 155.212665 120.827043) (width 0.1) (layer "F.Cu") (net 149))
  (segment (start 153.902252 120.312507) (end 153.88 120.31) (width 0.1) (layer "F.Cu") (net 149))
  (segment (start 153.942348 120.331816) (end 153.923388 120.319903) (width 0.1) (layer "F.Cu") (net 149))
  (segment (start 155.512665 120.46) (end 155.512665 120.827043) (width 0.1) (layer "F.Cu") (net 149))
  (segment (start 155.508904 120.860421) (end 155.49781 120.892125) (width 0.1) (layer "F.Cu") (net 149))
  (segment (start 155.396043 120.973282) (end 155.362665 120.977043) (width 0.1) (layer "F.Cu") (net 149))
  (segment (start 154.473573 120.872645) (end 154.419978 120.906321) (width 0.1) (layer "F.Cu") (net 149))
  (segment (start 154.419978 120.906321) (end 154.360233 120.927226) (width 0.1) (layer "F.Cu") (net 149))
  (segment (start 149.0225 116.865) (end 149.085 116.8025) (width 0.1) (layer "F.Cu") (net 149))
  (segment (start 155.629286 120.31376) (end 155.597582 120.324854) (width 0.1) (layer "F.Cu") (net 149))
  (segment (start 155.662665 120.31) (end 155.629286 120.31376) (width 0.1) (layer "F.Cu") (net 149))
  (segment (start 154.086426 120.872645) (end 154.041668 120.827887) (width 0.1) (layer "F.Cu") (net 149))
  (segment (start 154.007992 120.774292) (end 153.987087 120.714547) (width 0.1) (layer "F.Cu") (net 149))
  (segment (start 161.699999 125.95) (end 161.549999 125.8) (width 0.1) (layer "F.Cu") (net 149))
  (segment (start 155.212665 120.46) (end 155.208904 120.426621) (width 0.1) (layer "F.Cu") (net 149))
  (segment (start 155.597582 120.324854) (end 155.569141 120.342725) (width 0.1) (layer "F.Cu") (net 149))
  (segment (start 155.156188 120.342725) (end 155.127747 120.324854) (width 0.1) (layer "F.Cu") (net 149))
  (segment (start 155.329286 120.973282) (end 155.297582 120.962188) (width 0.1) (layer "F.Cu") (net 149))
  (segment (start 155.297582 120.962188) (end 155.269141 120.944317) (width 0.1) (layer "F.Cu") (net 149))
  (segment (start 154.758183 118.973338) (end 154.742348 118.957503) (width 0.1) (layer "F.Cu") (net 149))
  (segment (start 154.636611 118.94559) (end 154.617651 118.957503) (width 0.1) (layer "F.Cu") (net 149))
  (segment (start 153.658578 120.31) (end 153.445 120.096422) (width 0.1) (layer "F.Cu") (net 149))
  (segment (start 154.940021 120.282008) (end 154.886426 120.248332) (width 0.1) (layer "F.Cu") (net 149))
  (segment (start 154.617651 118.957503) (end 154.601816 118.973338) (width 0.1) (layer "F.Cu") (net 149))
  (via (at 150.305 117.05875) (size 0.55) (drill 0.15) (layers "F.Cu" "B.Cu") (net 149))
  (via (at 153.18875 119.405) (size 0.55) (drill 0.15) (layers "F.Cu" "B.Cu") (net 149))
  (segment (start 152.634834 116.89) (end 153.3575 117.612666) (width 0.15) (layer "In3.Cu") (net 149))
  (segment (start 150.47375 116.89) (end 152.634834 116.89) (width 0.15) (layer "In3.Cu") (net 149))
  (segment (start 150.305 117.05875) (end 150.47375 116.89) (width 0.15) (layer "In3.Cu") (net 149))
  (segment (start 153.3575 119.23625) (end 153.18875 119.405) (width 0.15) (layer "In3.Cu") (net 149))
  (segment (start 153.3575 117.612666) (end 153.3575 119.23625) (width 0.15) (layer "In3.Cu") (net 149))
  (segment (start 154.952007 118.895708) (end 154.918331 118.842113) (width 0.1) (layer "F.Cu") (net 150))
  (segment (start 159.625 121.028578) (end 158.706422 120.11) (width 0.1) (layer "F.Cu") (net 150))
  (segment (start 154.387087 118.955453) (end 154.38 119.018352) (width 0.1) (layer "F.Cu") (net 150))
  (segment (start 154.118331 120.216426) (end 154.073573 120.171668) (width 0.1) (layer "F.Cu") (net 150))
  (segment (start 154.18 120.634314) (end 154.18 120.392665) (width 0.1) (layer "F.Cu") (net 150))
  (segment (start 154.38 120.634314) (end 154.377492 120.656566) (width 0.1) (layer "F.Cu") (net 150))
  (segment (start 147.845 116.865) (end 148.17 116.54) (width 0.1) (layer "F.Cu") (net 150))
  (segment (start 149.085 116.6025) (end 150.04875 116.6025) (width 0.1) (layer "F.Cu") (net 150))
  (segment (start 161.496422 125.6) (end 159.625 123.728578) (width 0.1) (layer "F.Cu") (net 150))
  (segment (start 154.662665 118.735686) (end 154.599766 118.742774) (width 0.1) (layer "F.Cu") (net 150))
  (segment (start 154.236611 120.72441) (end 154.217651 120.712497) (width 0.1) (layer "F.Cu") (net 150))
  (segment (start 154.697334 118.735686) (end 154.662665 118.735686) (width 0.1) (layer "F.Cu") (net 150))
  (segment (start 154.189903 120.677702) (end 154.182507 120.656566) (width 0.1) (layer "F.Cu") (net 150))
  (segment (start 155.036611 120.100097) (end 155.017651 120.088184) (width 0.1) (layer "F.Cu") (net 150))
  (segment (start 154.873573 118.797355) (end 154.819978 118.763679) (width 0.1) (layer "F.Cu") (net 150))
  (segment (start 154.172912 120.329766) (end 154.152007 120.270021) (width 0.1) (layer "F.Cu") (net 150))
  (segment (start 155.017651 120.088184) (end 155.001816 120.072349) (width 0.1) (layer "F.Cu") (net 150))
  (segment (start 154.441668 118.842113) (end 154.407992 118.895708) (width 0.1) (layer "F.Cu") (net 150))
  (segment (start 154.982507 120.032253) (end 154.98 120.01) (width 0.1) (layer "F.Cu") (net 150))
  (segment (start 162.6 125.45) (end 161.699999 125.45) (width 0.1) (layer "F.Cu") (net 150))
  (segment (start 148.17 116.54) (end 149.0225 116.54) (width 0.1) (layer "F.Cu") (net 150))
  (segment (start 150.04875 116.6025) (end 150.305 116.34625) (width 0.1) (layer "F.Cu") (net 150))
  (segment (start 154.989903 120.053389) (end 154.982507 120.032253) (width 0.1) (layer "F.Cu") (net 150))
  (segment (start 159.625 123.728578) (end 159.625 121.028578) (width 0.1) (layer "F.Cu") (net 150))
  (segment (start 154.342348 120.712497) (end 154.323388 120.72441) (width 0.1) (layer "F.Cu") (net 150))
  (segment (start 154.599766 118.742774) (end 154.540021 118.763679) (width 0.1) (layer "F.Cu") (net 150))
  (segment (start 161.699999 125.45) (end 161.549999 125.6) (width 0.1) (layer "F.Cu") (net 150))
  (segment (start 154.98 120.01) (end 154.98 119.018352) (width 0.1) (layer "F.Cu") (net 150))
  (segment (start 154.370096 120.677702) (end 154.358183 120.696662) (width 0.1) (layer "F.Cu") (net 150))
  (segment (start 154.217651 120.712497) (end 154.201816 120.696662) (width 0.1) (layer "F.Cu") (net 150))
  (segment (start 153.741422 120.11) (end 153.645 120.013578) (width 0.1) (layer "F.Cu") (net 150))
  (segment (start 154.486426 118.797355) (end 154.441668 118.842113) (width 0.1) (layer "F.Cu") (net 150))
  (segment (start 154.323388 120.72441) (end 154.302252 120.731806) (width 0.1) (layer "F.Cu") (net 150))
  (segment (start 154.760233 118.742774) (end 154.697334 118.735686) (width 0.1) (layer "F.Cu") (net 150))
  (segment (start 154.18 120.392665) (end 154.172912 120.329766) (width 0.1) (layer "F.Cu") (net 150))
  (segment (start 154.358183 120.696662) (end 154.342348 120.712497) (width 0.1) (layer "F.Cu") (net 150))
  (segment (start 153.645 120.013578) (end 153.645 119.66125) (width 0.1) (layer "F.Cu") (net 150))
  (segment (start 154.28 120.734314) (end 154.257747 120.731806) (width 0.1) (layer "F.Cu") (net 150))
  (segment (start 154.819978 118.763679) (end 154.760233 118.742774) (width 0.1) (layer "F.Cu") (net 150))
  (segment (start 155.057747 120.107493) (end 155.036611 120.100097) (width 0.1) (layer "F.Cu") (net 150))
  (segment (start 154.073573 120.171668) (end 154.019978 120.137992) (width 0.1) (layer "F.Cu") (net 150))
  (segment (start 154.152007 120.270021) (end 154.118331 120.216426) (width 0.1) (layer "F.Cu") (net 150))
  (segment (start 154.972912 118.955453) (end 154.952007 118.895708) (width 0.1) (layer "F.Cu") (net 150))
  (segment (start 155.08 120.11) (end 155.057747 120.107493) (width 0.1) (layer "F.Cu") (net 150))
  (segment (start 153.897334 120.11) (end 153.741422 120.11) (width 0.1) (layer "F.Cu") (net 150))
  (segment (start 154.377492 120.656566) (end 154.370096 120.677702) (width 0.1) (layer "F.Cu") (net 150))
  (segment (start 154.019978 120.137992) (end 153.960233 120.117087) (width 0.1) (layer "F.Cu") (net 150))
  (segment (start 154.407992 118.895708) (end 154.387087 118.955453) (width 0.1) (layer "F.Cu") (net 150))
  (segment (start 155.001816 120.072349) (end 154.989903 120.053389) (width 0.1) (layer "F.Cu") (net 150))
  (segment (start 154.302252 120.731806) (end 154.28 120.734314) (width 0.1) (layer "F.Cu") (net 150))
  (segment (start 161.549999 125.6) (end 161.496422 125.6) (width 0.1) (layer "F.Cu") (net 150))
  (segment (start 153.960233 120.117087) (end 153.897334 120.11) (width 0.1) (layer "F.Cu") (net 150))
  (segment (start 158.706422 120.11) (end 155.08 120.11) (width 0.1) (layer "F.Cu") (net 150))
  (segment (start 154.540021 118.763679) (end 154.486426 118.797355) (width 0.1) (layer "F.Cu") (net 150))
  (segment (start 153.645 119.66125) (end 153.90125 119.405) (width 0.1) (layer "F.Cu") (net 150))
  (segment (start 149.0225 116.54) (end 149.085 116.6025) (width 0.1) (layer "F.Cu") (net 150))
  (segment (start 154.38 119.018352) (end 154.38 120.634314) (width 0.1) (layer "F.Cu") (net 150))
  (segment (start 154.257747 120.731806) (end 154.236611 120.72441) (width 0.1) (layer "F.Cu") (net 150))
  (segment (start 154.98 119.018352) (end 154.972912 118.955453) (width 0.1) (layer "F.Cu") (net 150))
  (segment (start 154.201816 120.696662) (end 154.189903 120.677702) (width 0.1) (layer "F.Cu") (net 150))
  (segment (start 154.918331 118.842113) (end 154.873573 118.797355) (width 0.1) (layer "F.Cu") (net 150))
  (segment (start 154.182507 120.656566) (end 154.18 120.634314) (width 0.1) (layer "F.Cu") (net 150))
  (via (at 150.305 116.34625) (size 0.55) (drill 0.15) (layers "F.Cu" "B.Cu") (net 150))
  (via (at 153.90125 119.405) (size 0.55) (drill 0.15) (layers "F.Cu" "B.Cu") (net 150))
  (segment (start 152.790166 116.515) (end 153.7325 117.457334) (width 0.15) (layer "In3.Cu") (net 150))
  (segment (start 153.7325 117.457334) (end 153.7325 119.23625) (width 0.15) (layer "In3.Cu") (net 150))
  (segment (start 153.7325 119.23625) (end 153.90125 119.405) (width 0.15) (layer "In3.Cu") (net 150))
  (segment (start 150.305 116.34625) (end 150.47375 116.515) (width 0.15) (layer "In3.Cu") (net 150))
  (segment (start 150.47375 116.515) (end 152.790166 116.515) (width 0.15) (layer "In3.Cu") (net 150))
  (segment (start 162.6 124.45) (end 161.699999 124.45) (width 0.1) (layer "F.Cu") (net 151))
  (segment (start 159.982992 121.095021) (end 160.016668 121.041426) (width 0.1) (layer "F.Cu") (net 151))
  (segment (start 161.033183 122.497348) (end 161.045096 122.478388) (width 0.1) (layer "F.Cu") (net 151))
  (segment (start 161.045096 121.678388) (end 161.052492 121.657252) (width 0.1) (layer "F.Cu") (net 151))
  (segment (start 161.033183 120.772651) (end 161.017348 120.756816) (width 0.1) (layer "F.Cu") (net 151))
  (segment (start 148.495 117.515) (end 149.0425 117.515) (width 0.1) (layer "F.Cu") (net 151))
  (segment (start 160.115021 121.507007) (end 160.061426 121.473331) (width 0.1) (layer "F.Cu") (net 151))
  (segment (start 161.055 121.635) (end 161.052492 121.612747) (width 0.1) (layer "F.Cu") (net 151))
  (segment (start 159.955 121.217665) (end 159.962087 121.154766) (width 0.1) (layer "F.Cu") (net 151))
  (segment (start 160.061426 121.473331) (end 160.016668 121.428573) (width 0.1) (layer "F.Cu") (net 151))
  (segment (start 160.977252 121.732492) (end 160.998388 121.725096) (width 0.1) (layer "F.Cu") (net 151))
  (segment (start 153.227274 118.366476) (end 153.203523 118.342725) (width 0.1) (layer "F.Cu") (net 151))
  (segment (start 160.237665 122.535) (end 160.955 122.535) (width 0.1) (layer "F.Cu") (net 151))
  (segment (start 161.052492 121.657252) (end 161.055 121.635) (width 0.1) (layer "F.Cu") (net 151))
  (segment (start 153.41 118.832068) (end 153.376621 118.828307) (width 0.1) (layer "F.Cu") (net 151))
  (segment (start 149.0425 117.515) (end 149.105 117.4525) (width 0.1) (layer "F.Cu") (net 151))
  (segment (start 159.955 122.017665) (end 159.962087 121.954766) (width 0.1) (layer "F.Cu") (net 151))
  (segment (start 161.699999 124.45) (end 161.549999 124.3) (width 0.1) (layer "F.Cu") (net 151))
  (segment (start 160.016668 121.041426) (end 160.061426 120.996668) (width 0.1) (layer "F.Cu") (net 151))
  (segment (start 153.545145 118.74715) (end 153.527274 118.775591) (width 0.1) (layer "F.Cu") (net 151))
  (segment (start 160.115021 120.962992) (end 160.174766 120.942087) (width 0.1) (layer "F.Cu") (net 151))
  (segment (start 161.052492 122.457252) (end 161.055 122.435) (width 0.1) (layer "F.Cu") (net 151))
  (segment (start 161.045096 120.878388) (end 161.052492 120.857252) (width 0.1) (layer "F.Cu") (net 151))
  (segment (start 161.033183 121.572651) (end 161.017348 121.556816) (width 0.1) (layer "F.Cu") (net 151))
  (segment (start 159.962087 121.154766) (end 159.982992 121.095021) (width 0.1) (layer "F.Cu") (net 151))
  (segment (start 160.174766 120.727912) (end 160.115021 120.707007) (width 0.1) (layer "F.Cu") (net 151))
  (segment (start 160.016668 122.641426) (end 160.061426 122.596668) (width 0.1) (layer "F.Cu") (net 151))
  (segment (start 160.955 120.935) (end 160.977252 120.932492) (width 0.1) (layer "F.Cu") (net 151))
  (segment (start 160.061426 121.796668) (end 160.115021 121.762992) (width 0.1) (layer "F.Cu") (net 151))
  (segment (start 153.26 118.46) (end 153.256239 118.426621) (width 0.1) (layer "F.Cu") (net 151))
  (segment (start 160.998388 122.344903) (end 160.977252 122.337507) (width 0.1) (layer "F.Cu") (net 151))
  (segment (start 161.193578 124.3) (end 159.955 123.061422) (width 0.1) (layer "F.Cu") (net 151))
  (segment (start 161.052492 122.412747) (end 161.045096 122.391611) (width 0.1) (layer "F.Cu") (net 151))
  (segment (start 161.045096 121.591611) (end 161.033183 121.572651) (width 0.1) (layer "F.Cu") (net 151))
  (segment (start 153.26376 118.715446) (end 153.26 118.682068) (width 0.1) (layer "F.Cu") (net 151))
  (segment (start 160.237665 120.735) (end 160.174766 120.727912) (width 0.1) (layer "F.Cu") (net 151))
  (segment (start 161.045096 122.391611) (end 161.033183 122.372651) (width 0.1) (layer "F.Cu") (net 151))
  (segment (start 159.982992 121.374978) (end 159.962087 121.315233) (width 0.1) (layer "F.Cu") (net 151))
  (segment (start 161.017348 120.913183) (end 161.033183 120.897348) (width 0.1) (layer "F.Cu") (net 151))
  (segment (start 161.549999 124.3) (end 161.193578 124.3) (width 0.1) (layer "F.Cu") (net 151))
  (segment (start 153.503523 118.799342) (end 153.475082 118.817213) (width 0.1) (layer "F.Cu") (net 151))
  (segment (start 160.115021 120.707007) (end 160.061426 120.673331) (width 0.1) (layer "F.Cu") (net 151))
  (segment (start 159.982992 122.174978) (end 159.962087 122.115233) (width 0.1) (layer "F.Cu") (net 151))
  (segment (start 160.061426 122.273331) (end 160.016668 122.228573) (width 0.1) (layer "F.Cu") (net 151))
  (segment (start 161.045096 122.478388) (end 161.052492 122.457252) (width 0.1) (layer "F.Cu") (net 151))
  (segment (start 160.174766 122.542087) (end 160.237665 122.535) (width 0.1) (layer "F.Cu") (net 151))
  (segment (start 160.237665 120.935) (end 160.955 120.935) (width 0.1) (layer "F.Cu") (net 151))
  (segment (start 160.998388 121.544903) (end 160.977252 121.537507) (width 0.1) (layer "F.Cu") (net 151))
  (segment (start 159.955 121.252334) (end 159.955 121.217665) (width 0.1) (layer "F.Cu") (net 151))
  (segment (start 153.245145 118.394917) (end 153.227274 118.366476) (width 0.1) (layer "F.Cu") (net 151))
  (segment (start 149.411078 117.4525) (end 149.833578 117.875) (width 0.1) (layer "F.Cu") (net 151))
  (segment (start 153.616476 118.342725) (end 153.592725 118.366476) (width 0.1) (layer "F.Cu") (net 151))
  (segment (start 161.045096 120.791611) (end 161.033183 120.772651) (width 0.1) (layer "F.Cu") (net 151))
  (segment (start 153.26 118.682068) (end 153.26 118.46) (width 0.1) (layer "F.Cu") (net 151))
  (segment (start 159.955 120.452334) (end 159.955 119.801422) (width 0.1) (layer "F.Cu") (net 151))
  (segment (start 150.76875 117.875) (end 151.025 118.13125) (width 0.1) (layer "F.Cu") (net 151))
  (segment (start 160.977252 122.532492) (end 160.998388 122.525096) (width 0.1) (layer "F.Cu") (net 151))
  (segment (start 159.982992 122.695021) (end 160.016668 122.641426) (width 0.1) (layer "F.Cu") (net 151))
  (segment (start 149.105 117.4525) (end 149.411078 117.4525) (width 0.1) (layer "F.Cu") (net 151))
  (segment (start 159.962087 122.754766) (end 159.982992 122.695021) (width 0.1) (layer "F.Cu") (net 151))
  (segment (start 159.955 122.817665) (end 159.962087 122.754766) (width 0.1) (layer "F.Cu") (net 151))
  (segment (start 159.962087 121.315233) (end 159.955 121.252334) (width 0.1) (layer "F.Cu") (net 151))
  (segment (start 161.017348 121.713183) (end 161.033183 121.697348) (width 0.1) (layer "F.Cu") (net 151))
  (segment (start 160.016668 121.428573) (end 159.982992 121.374978) (width 0.1) (layer "F.Cu") (net 151))
  (segment (start 160.977252 120.737507) (end 160.955 120.735) (width 0.1) (layer "F.Cu") (net 151))
  (segment (start 153.376621 118.828307) (end 153.344917 118.817213) (width 0.1) (layer "F.Cu") (net 151))
  (segment (start 160.955 121.535) (end 160.237665 121.535) (width 0.1) (layer "F.Cu") (net 151))
  (segment (start 153.203523 118.342725) (end 153.175082 118.324854) (width 0.1) (layer "F.Cu") (net 151))
  (segment (start 159.962087 120.515233) (end 159.955 120.452334) (width 0.1) (layer "F.Cu") (net 151))
  (segment (start 153.71 118.31) (end 153.676621 118.31376) (width 0.1) (layer "F.Cu") (net 151))
  (segment (start 160.237665 122.335) (end 160.174766 122.327912) (width 0.1) (layer "F.Cu") (net 151))
  (segment (start 159.955 122.052334) (end 159.955 122.017665) (width 0.1) (layer "F.Cu") (net 151))
  (segment (start 160.955 122.335) (end 160.237665 122.335) (width 0.1) (layer "F.Cu") (net 151))
  (segment (start 160.061426 120.673331) (end 160.016668 120.628573) (width 0.1) (layer "F.Cu") (net 151))
  (segment (start 153.56 118.682068) (end 153.556239 118.715446) (width 0.1) (layer "F.Cu") (net 151))
  (segment (start 161.033183 121.697348) (end 161.045096 121.678388) (width 0.1) (layer "F.Cu") (net 151))
  (segment (start 153.443378 118.828307) (end 153.41 118.832068) (width 0.1) (layer "F.Cu") (net 151))
  (segment (start 160.237665 121.735) (end 160.955 121.735) (width 0.1) (layer "F.Cu") (net 151))
  (segment (start 159.955 119.801422) (end 158.463578 118.31) (width 0.1) (layer "F.Cu") (net 151))
  (segment (start 160.115021 122.562992) (end 160.174766 122.542087) (width 0.1) (layer "F.Cu") (net 151))
  (segment (start 153.475082 118.817213) (end 153.443378 118.828307) (width 0.1) (layer "F.Cu") (net 151))
  (segment (start 161.052492 121.612747) (end 161.045096 121.591611) (width 0.1) (layer "F.Cu") (net 151))
  (segment (start 160.061426 120.996668) (end 160.115021 120.962992) (width 0.1) (layer "F.Cu") (net 151))
  (segment (start 160.115021 121.762992) (end 160.174766 121.742087) (width 0.1) (layer "F.Cu") (net 151))
  (segment (start 161.055 122.435) (end 161.052492 122.412747) (width 0.1) (layer "F.Cu") (net 151))
  (segment (start 160.016668 120.628573) (end 159.982992 120.574978) (width 0.1) (layer "F.Cu") (net 151))
  (segment (start 160.998388 120.744903) (end 160.977252 120.737507) (width 0.1) (layer "F.Cu") (net 151))
  (segment (start 153.56 118.46) (end 153.56 118.682068) (width 0.1) (layer "F.Cu") (net 151))
  (segment (start 161.017348 122.356816) (end 160.998388 122.344903) (width 0.1) (layer "F.Cu") (net 151))
  (segment (start 153.292725 118.775591) (end 153.274854 118.74715) (width 0.1) (layer "F.Cu") (net 151))
  (segment (start 152.82125 118.31) (end 152.565 118.56625) (width 0.1) (layer "F.Cu") (net 151))
  (segment (start 153.574854 118.394917) (end 153.56376 118.426621) (width 0.1) (layer "F.Cu") (net 151))
  (segment (start 153.316476 118.799342) (end 153.292725 118.775591) (width 0.1) (layer "F.Cu") (net 151))
  (segment (start 153.644917 118.324854) (end 153.616476 118.342725) (width 0.1) (layer "F.Cu") (net 151))
  (segment (start 160.977252 121.537507) (end 160.955 121.535) (width 0.1) (layer "F.Cu") (net 151))
  (segment (start 160.174766 121.527912) (end 160.115021 121.507007) (width 0.1) (layer "F.Cu") (net 151))
  (segment (start 160.955 121.735) (end 160.977252 121.732492) (width 0.1) (layer "F.Cu") (net 151))
  (segment (start 161.055 120.835) (end 161.052492 120.812747) (width 0.1) (layer "F.Cu") (net 151))
  (segment (start 161.052492 120.857252) (end 161.055 120.835) (width 0.1) (layer "F.Cu") (net 151))
  (segment (start 153.56376 118.426621) (end 153.56 118.46) (width 0.1) (layer "F.Cu") (net 151))
  (segment (start 160.174766 121.742087) (end 160.237665 121.735) (width 0.1) (layer "F.Cu") (net 151))
  (segment (start 160.016668 121.841426) (end 160.061426 121.796668) (width 0.1) (layer "F.Cu") (net 151))
  (segment (start 160.977252 122.337507) (end 160.955 122.335) (width 0.1) (layer "F.Cu") (net 151))
  (segment (start 160.115021 122.307007) (end 160.061426 122.273331) (width 0.1) (layer "F.Cu") (net 151))
  (segment (start 160.174766 122.327912) (end 160.115021 122.307007) (width 0.1) (layer "F.Cu") (net 151))
  (segment (start 161.017348 120.756816) (end 160.998388 120.744903) (width 0.1) (layer "F.Cu") (net 151))
  (segment (start 159.982992 120.574978) (end 159.962087 120.515233) (width 0.1) (layer "F.Cu") (net 151))
  (segment (start 161.033183 122.372651) (end 161.017348 122.356816) (width 0.1) (layer "F.Cu") (net 151))
  (segment (start 153.676621 118.31376) (end 153.644917 118.324854) (width 0.1) (layer "F.Cu") (net 151))
  (segment (start 160.977252 120.932492) (end 160.998388 120.925096) (width 0.1) (layer "F.Cu") (net 151))
  (segment (start 153.592725 118.366476) (end 153.574854 118.394917) (width 0.1) (layer "F.Cu") (net 151))
  (segment (start 160.955 120.735) (end 160.237665 120.735) (width 0.1) (layer "F.Cu") (net 151))
  (segment (start 160.016668 122.228573) (end 159.982992 122.174978) (width 0.1) (layer "F.Cu") (net 151))
  (segment (start 153.11 118.31) (end 152.82125 118.31) (width 0.1) (layer "F.Cu") (net 151))
  (segment (start 159.955 123.061422) (end 159.955 122.817665) (width 0.1) (layer "F.Cu") (net 151))
  (segment (start 159.982992 121.895021) (end 160.016668 121.841426) (width 0.1) (layer "F.Cu") (net 151))
  (segment (start 161.017348 121.556816) (end 160.998388 121.544903) (width 0.1) (layer "F.Cu") (net 151))
  (segment (start 160.061426 122.596668) (end 160.115021 122.562992) (width 0.1) (layer "F.Cu") (net 151))
  (segment (start 160.237665 121.535) (end 160.174766 121.527912) (width 0.1) (layer "F.Cu") (net 151))
  (segment (start 160.998388 120.925096) (end 161.017348 120.913183) (width 0.1) (layer "F.Cu") (net 151))
  (segment (start 153.344917 118.817213) (end 153.316476 118.799342) (width 0.1) (layer "F.Cu") (net 151))
  (segment (start 153.175082 118.324854) (end 153.143378 118.31376) (width 0.1) (layer "F.Cu") (net 151))
  (segment (start 149.833578 117.875) (end 150.76875 117.875) (width 0.1) (layer "F.Cu") (net 151))
  (segment (start 153.143378 118.31376) (end 153.11 118.31) (width 0.1) (layer "F.Cu") (net 151))
  (segment (start 159.962087 121.954766) (end 159.982992 121.895021) (width 0.1) (layer "F.Cu") (net 151))
  (segment (start 160.998388 122.525096) (end 161.017348 122.513183) (width 0.1) (layer "F.Cu") (net 151))
  (segment (start 159.962087 122.115233) (end 159.955 122.052334) (width 0.1) (layer "F.Cu") (net 151))
  (segment (start 160.174766 120.942087) (end 160.237665 120.935) (width 0.1) (layer "F.Cu") (net 151))
  (segment (start 153.556239 118.715446) (end 153.545145 118.74715) (width 0.1) (layer "F.Cu") (net 151))
  (segment (start 160.998388 121.725096) (end 161.017348 121.713183) (width 0.1) (layer "F.Cu") (net 151))
  (segment (start 161.052492 120.812747) (end 161.045096 120.791611) (width 0.1) (layer "F.Cu") (net 151))
  (segment (start 161.017348 122.513183) (end 161.033183 122.497348) (width 0.1) (layer "F.Cu") (net 151))
  (segment (start 153.527274 118.775591) (end 153.503523 118.799342) (width 0.1) (layer "F.Cu") (net 151))
  (segment (start 161.033183 120.897348) (end 161.045096 120.878388) (width 0.1) (layer "F.Cu") (net 151))
  (segment (start 153.256239 118.426621) (end 153.245145 118.394917) (width 0.1) (layer "F.Cu") (net 151))
  (segment (start 160.955 122.535) (end 160.977252 122.532492) (width 0.1) (layer "F.Cu") (net 151))
  (segment (start 158.463578 118.31) (end 153.71 118.31) (width 0.1) (layer "F.Cu") (net 151))
  (segment (start 153.274854 118.74715) (end 153.26376 118.715446) (width 0.1) (layer "F.Cu") (net 151))
  (via (at 152.565 118.56625) (size 0.55) (drill 0.15) (layers "F.Cu" "B.Cu") (net 151))
  (via (at 151.025 118.13125) (size 0.55) (drill 0.15) (layers "F.Cu" "B.Cu") (net 151))
  (segment (start 151.19375 117.9625) (end 151.025 118.13125) (width 0.15) (layer "In3.Cu") (net 151))
  (segment (start 151.637334 117.9625) (end 151.19375 117.9625) (width 0.15) (layer "In3.Cu") (net 151))
  (segment (start 152.072334 118.3975) (end 151.637334 117.9625) (width 0.15) (layer "In3.Cu") (net 151))
  (segment (start 152.565 118.56625) (end 152.39625 118.3975) (width 0.15) (layer "In3.Cu") (net 151))
  (segment (start 152.39625 118.3975) (end 152.072334 118.3975) (width 0.15) (layer "In3.Cu") (net 151))
  (segment (start 160.211611 121.325096) (end 160.192651 121.313183) (width 0.1) (layer "F.Cu") (net 152))
  (segment (start 160.211611 120.525096) (end 160.192651 120.513183) (width 0.1) (layer "F.Cu") (net 152))
  (segment (start 161.247912 121.715233) (end 161.255 121.652334) (width 0.1) (layer "F.Cu") (net 152))
  (segment (start 160.157507 122.057252) (end 160.155 122.035) (width 0.1) (layer "F.Cu") (net 152))
  (segment (start 160.155 120.435) (end 160.155 119.718578) (width 0.1) (layer "F.Cu") (net 152))
  (segment (start 160.972334 122.135) (end 160.255 122.135) (width 0.1) (layer "F.Cu") (net 152))
  (segment (start 160.232747 120.532492) (end 160.211611 120.525096) (width 0.1) (layer "F.Cu") (net 152))
  (segment (start 161.148573 122.196668) (end 161.094978 122.162992) (width 0.1) (layer "F.Cu") (net 152))
  (segment (start 160.164903 121.191611) (end 160.176816 121.172651) (width 0.1) (layer "F.Cu") (net 152))
  (segment (start 160.176816 122.772651) (end 160.192651 122.756816) (width 0.1) (layer "F.Cu") (net 152))
  (segment (start 161.148573 121.396668) (end 161.094978 121.362992) (width 0.1) (layer "F.Cu") (net 152))
  (segment (start 160.972334 122.735) (end 161.035233 122.727912) (width 0.1) (layer "F.Cu") (net 152))
  (segment (start 160.211611 122.125096) (end 160.192651 122.113183) (width 0.1) (layer "F.Cu") (net 152))
  (segment (start 149.0425 117.19) (end 149.105 117.2525) (width 0.1) (layer "F.Cu") (net 152))
  (segment (start 160.164903 121.278388) (end 160.157507 121.257252) (width 0.1) (layer "F.Cu") (net 152))
  (segment (start 161.255 122.452334) (end 161.255 122.417665) (width 0.1) (layer "F.Cu") (net 152))
  (segment (start 161.227007 120.974978) (end 161.247912 120.915233) (width 0.1) (layer "F.Cu") (net 152))
  (segment (start 161.247912 122.515233) (end 161.255 122.452334) (width 0.1) (layer "F.Cu") (net 152))
  (segment (start 149.105 117.2525) (end 149.493922 117.2525) (width 0.1) (layer "F.Cu") (net 152))
  (segment (start 160.211611 122.744903) (end 160.232747 122.737507) (width 0.1) (layer "F.Cu") (net 152))
  (segment (start 161.094978 121.907007) (end 161.148573 121.873331) (width 0.1) (layer "F.Cu") (net 152))
  (segment (start 150.76875 117.675) (end 151.025 117.41875) (width 0.1) (layer "F.Cu") (net 152))
  (segment (start 161.549999 124.1) (end 161.276422 124.1) (width 0.1) (layer "F.Cu") (net 152))
  (segment (start 161.193331 122.628573) (end 161.227007 122.574978) (width 0.1) (layer "F.Cu") (net 152))
  (segment (start 160.176816 120.497348) (end 160.164903 120.478388) (width 0.1) (layer "F.Cu") (net 152))
  (segment (start 161.276422 124.1) (end 160.155 122.978578) (width 0.1) (layer "F.Cu") (net 152))
  (segment (start 160.211611 121.144903) (end 160.232747 121.137507) (width 0.1) (layer "F.Cu") (net 152))
  (segment (start 161.148573 120.596668) (end 161.094978 120.562992) (width 0.1) (layer "F.Cu") (net 152))
  (segment (start 160.232747 122.132492) (end 160.211611 122.125096) (width 0.1) (layer "F.Cu") (net 152))
  (segment (start 160.157507 120.457252) (end 160.155 120.435) (width 0.1) (layer "F.Cu") (net 152))
  (segment (start 161.193331 120.641426) (end 161.148573 120.596668) (width 0.1) (layer "F.Cu") (net 152))
  (segment (start 160.192651 121.956816) (end 160.211611 121.944903) (width 0.1) (layer "F.Cu") (net 152))
  (segment (start 160.176816 121.297348) (end 160.164903 121.278388) (width 0.1) (layer "F.Cu") (net 152))
  (segment (start 160.972334 121.335) (end 160.255 121.335) (width 0.1) (layer "F.Cu") (net 152))
  (segment (start 161.094978 122.707007) (end 161.148573 122.673331) (width 0.1) (layer "F.Cu") (net 152))
  (segment (start 148.17 117.19) (end 149.0425 117.19) (width 0.1) (layer "F.Cu") (net 152))
  (segment (start 161.227007 121.774978) (end 161.247912 121.715233) (width 0.1) (layer "F.Cu") (net 152))
  (segment (start 160.232747 121.332492) (end 160.211611 121.325096) (width 0.1) (layer "F.Cu") (net 152))
  (segment (start 162.6 123.95) (end 161.699999 123.95) (width 0.1) (layer "F.Cu") (net 152))
  (segment (start 160.164903 122.078388) (end 160.157507 122.057252) (width 0.1) (layer "F.Cu") (net 152))
  (segment (start 160.972334 121.135) (end 161.035233 121.127912) (width 0.1) (layer "F.Cu") (net 152))
  (segment (start 160.232747 121.937507) (end 160.255 121.935) (width 0.1) (layer "F.Cu") (net 152))
  (segment (start 160.255 122.735) (end 160.972334 122.735) (width 0.1) (layer "F.Cu") (net 152))
  (segment (start 160.176816 122.097348) (end 160.164903 122.078388) (width 0.1) (layer "F.Cu") (net 152))
  (segment (start 152.82125 118.11) (end 152.565 117.85375) (width 0.1) (layer "F.Cu") (net 152))
  (segment (start 160.176816 121.172651) (end 160.192651 121.156816) (width 0.1) (layer "F.Cu") (net 152))
  (segment (start 161.255 122.417665) (end 161.247912 122.354766) (width 0.1) (layer "F.Cu") (net 152))
  (segment (start 158.546422 118.11) (end 152.82125 118.11) (width 0.1) (layer "F.Cu") (net 152))
  (segment (start 161.227007 120.695021) (end 161.193331 120.641426) (width 0.1) (layer "F.Cu") (net 152))
  (segment (start 161.227007 121.495021) (end 161.193331 121.441426) (width 0.1) (layer "F.Cu") (net 152))
  (segment (start 147.845 117.515) (end 148.17 117.19) (width 0.1) (layer "F.Cu") (net 152))
  (segment (start 160.255 122.135) (end 160.232747 122.132492) (width 0.1) (layer "F.Cu") (net 152))
  (segment (start 161.035233 122.727912) (end 161.094978 122.707007) (width 0.1) (layer "F.Cu") (net 152))
  (segment (start 161.035233 122.142087) (end 160.972334 122.135) (width 0.1) (layer "F.Cu") (net 152))
  (segment (start 161.094978 121.362992) (end 161.035233 121.342087) (width 0.1) (layer "F.Cu") (net 152))
  (segment (start 161.247912 120.754766) (end 161.227007 120.695021) (width 0.1) (layer "F.Cu") (net 152))
  (segment (start 149.493922 117.2525) (end 149.916422 117.675) (width 0.1) (layer "F.Cu") (net 152))
  (segment (start 161.255 121.617665) (end 161.247912 121.554766) (width 0.1) (layer "F.Cu") (net 152))
  (segment (start 161.094978 120.562992) (end 161.035233 120.542087) (width 0.1) (layer "F.Cu") (net 152))
  (segment (start 161.699999 123.95) (end 161.549999 124.1) (width 0.1) (layer "F.Cu") (net 152))
  (segment (start 160.255 120.535) (end 160.232747 120.532492) (width 0.1) (layer "F.Cu") (net 152))
  (segment (start 161.094978 121.107007) (end 161.148573 121.073331) (width 0.1) (layer "F.Cu") (net 152))
  (segment (start 161.227007 122.295021) (end 161.193331 122.241426) (width 0.1) (layer "F.Cu") (net 152))
  (segment (start 160.155 122.835) (end 160.157507 122.812747) (width 0.1) (layer "F.Cu") (net 152))
  (segment (start 161.193331 121.441426) (end 161.148573 121.396668) (width 0.1) (layer "F.Cu") (net 152))
  (segment (start 160.972334 121.935) (end 161.035233 121.927912) (width 0.1) (layer "F.Cu") (net 152))
  (segment (start 160.972334 120.535) (end 160.255 120.535) (width 0.1) (layer "F.Cu") (net 152))
  (segment (start 160.164903 121.991611) (end 160.176816 121.972651) (width 0.1) (layer "F.Cu") (net 152))
  (segment (start 160.192651 122.113183) (end 160.176816 122.097348) (width 0.1) (layer "F.Cu") (net 152))
  (segment (start 160.155 121.235) (end 160.157507 121.212747) (width 0.1) (layer "F.Cu") (net 152))
  (segment (start 160.176816 121.972651) (end 160.192651 121.956816) (width 0.1) (layer "F.Cu") (net 152))
  (segment (start 161.247912 122.354766) (end 161.227007 122.295021) (width 0.1) (layer "F.Cu") (net 152))
  (segment (start 160.192651 121.156816) (end 160.211611 121.144903) (width 0.1) (layer "F.Cu") (net 152))
  (segment (start 160.232747 122.737507) (end 160.255 122.735) (width 0.1) (layer "F.Cu") (net 152))
  (segment (start 160.192651 120.513183) (end 160.176816 120.497348) (width 0.1) (layer "F.Cu") (net 152))
  (segment (start 161.247912 120.915233) (end 161.255 120.852334) (width 0.1) (layer "F.Cu") (net 152))
  (segment (start 161.094978 122.162992) (end 161.035233 122.142087) (width 0.1) (layer "F.Cu") (net 152))
  (segment (start 160.157507 121.257252) (end 160.155 121.235) (width 0.1) (layer "F.Cu") (net 152))
  (segment (start 160.255 121.935) (end 160.972334 121.935) (width 0.1) (layer "F.Cu") (net 152))
  (segment (start 161.148573 121.873331) (end 161.193331 121.828573) (width 0.1) (layer "F.Cu") (net 152))
  (segment (start 160.155 119.718578) (end 158.546422 118.11) (width 0.1) (layer "F.Cu") (net 152))
  (segment (start 160.192651 122.756816) (end 160.211611 122.744903) (width 0.1) (layer "F.Cu") (net 152))
  (segment (start 161.255 120.817665) (end 161.247912 120.754766) (width 0.1) (layer "F.Cu") (net 152))
  (segment (start 161.255 120.852334) (end 161.255 120.817665) (width 0.1) (layer "F.Cu") (net 152))
  (segment (start 160.155 122.035) (end 160.157507 122.012747) (width 0.1) (layer "F.Cu") (net 152))
  (segment (start 161.193331 122.241426) (end 161.148573 122.196668) (width 0.1) (layer "F.Cu") (net 152))
  (segment (start 161.035233 121.342087) (end 160.972334 121.335) (width 0.1) (layer "F.Cu") (net 152))
  (segment (start 160.255 121.335) (end 160.232747 121.332492) (width 0.1) (layer "F.Cu") (net 152))
  (segment (start 161.035233 120.542087) (end 160.972334 120.535) (width 0.1) (layer "F.Cu") (net 152))
  (segment (start 161.035233 121.127912) (end 161.094978 121.107007) (width 0.1) (layer "F.Cu") (net 152))
  (segment (start 161.193331 121.828573) (end 161.227007 121.774978) (width 0.1) (layer "F.Cu") (net 152))
  (segment (start 161.255 121.652334) (end 161.255 121.617665) (width 0.1) (layer "F.Cu") (net 152))
  (segment (start 160.157507 122.012747) (end 160.164903 121.991611) (width 0.1) (layer "F.Cu") (net 152))
  (segment (start 160.155 122.978578) (end 160.155 122.835) (width 0.1) (layer "F.Cu") (net 152))
  (segment (start 161.227007 122.574978) (end 161.247912 122.515233) (width 0.1) (layer "F.Cu") (net 152))
  (segment (start 161.247912 121.554766) (end 161.227007 121.495021) (width 0.1) (layer "F.Cu") (net 152))
  (segment (start 160.255 121.135) (end 160.972334 121.135) (width 0.1) (layer "F.Cu") (net 152))
  (segment (start 161.035233 121.927912) (end 161.094978 121.907007) (width 0.1) (layer "F.Cu") (net 152))
  (segment (start 149.916422 117.675) (end 150.76875 117.675) (width 0.1) (layer "F.Cu") (net 152))
  (segment (start 160.164903 120.478388) (end 160.157507 120.457252) (width 0.1) (layer "F.Cu") (net 152))
  (segment (start 161.148573 122.673331) (end 161.193331 122.628573) (width 0.1) (layer "F.Cu") (net 152))
  (segment (start 160.157507 121.212747) (end 160.164903 121.191611) (width 0.1) (layer "F.Cu") (net 152))
  (segment (start 160.157507 122.812747) (end 160.164903 122.791611) (width 0.1) (layer "F.Cu") (net 152))
  (segment (start 161.193331 121.028573) (end 161.227007 120.974978) (width 0.1) (layer "F.Cu") (net 152))
  (segment (start 161.148573 121.073331) (end 161.193331 121.028573) (width 0.1) (layer "F.Cu") (net 152))
  (segment (start 160.211611 121.944903) (end 160.232747 121.937507) (width 0.1) (layer "F.Cu") (net 152))
  (segment (start 160.192651 121.313183) (end 160.176816 121.297348) (width 0.1) (layer "F.Cu") (net 152))
  (segment (start 160.232747 121.137507) (end 160.255 121.135) (width 0.1) (layer "F.Cu") (net 152))
  (segment (start 160.164903 122.791611) (end 160.176816 122.772651) (width 0.1) (layer "F.Cu") (net 152))
  (via (at 152.565 117.85375) (size 0.55) (drill 0.15) (layers "F.Cu" "B.Cu") (net 152))
  (via (at 151.025 117.41875) (size 0.55) (drill 0.15) (layers "F.Cu" "B.Cu") (net 152))
  (segment (start 152.39625 118.0225) (end 152.227666 118.0225) (width 0.15) (layer "In3.Cu") (net 152))
  (segment (start 152.227666 118.0225) (end 151.792666 117.5875) (width 0.15) (layer "In3.Cu") (net 152))
  (segment (start 151.792666 117.5875) (end 151.19375 117.5875) (width 0.15) (layer "In3.Cu") (net 152))
  (segment (start 152.565 117.85375) (end 152.39625 118.0225) (width 0.15) (layer "In3.Cu") (net 152))
  (segment (start 151.19375 117.5875) (end 151.025 117.41875) (width 0.15) (layer "In3.Cu") (net 152))
  (segment (start 150.185 115.445) (end 150.235 115.445) (width 0.1) (layer "F.Cu") (net 153))
  (segment (start 150.138238 115.428637) (end 150.152458 115.437572) (width 0.1) (layer "F.Cu") (net 153))
  (segment (start 152.093637 115.323238) (end 152.102572 115.337458) (width 0.1) (layer "F.Cu") (net 153))
  (segment (start 151.651689 115.29688) (end 151.667541 115.302427) (width 0.1) (layer "F.Cu") (net 153))
  (segment (start 151.708119 115.35331) (end 151.71188 115.386689) (width 0.1) (layer "F.Cu") (net 153))
  (segment (start 149.826422 115.295) (end 150.035 115.295) (width 0.1) (layer "F.Cu") (net 153))
  (segment (start 151.481761 115.428637) (end 151.493637 115.416761) (width 0.1) (layer "F.Cu") (net 153))
  (segment (start 151.56831 115.29688) (end 151.585 115.295) (width 0.1) (layer "F.Cu") (net 153))
  (segment (start 150.851689 115.29688) (end 150.867541 115.302427) (width 0.1) (layer "F.Cu") (net 153))
  (segment (start 151.538238 115.311362) (end 151.552458 115.302427) (width 0.1) (layer "F.Cu") (net 153))
  (segment (start 150.385 115.295) (end 150.435 115.295) (width 0.1) (layer "F.Cu") (net 153))
  (segment (start 150.517427 115.402541) (end 150.526362 115.416761) (width 0.1) (layer "F.Cu") (net 153))
  (segment (start 151.117427 115.337458) (end 151.126362 115.323238) (width 0.1) (layer "F.Cu") (net 153))
  (segment (start 150.667541 115.437572) (end 150.681761 115.428637) (width 0.1) (layer "F.Cu") (net 153))
  (segment (start 151.752458 115.437572) (end 151.76831 115.443119) (width 0.1) (layer "F.Cu") (net 153))
  (segment (start 151.517427 115.337458) (end 151.526362 115.323238) (width 0.1) (layer "F.Cu") (net 153))
  (segment (start 151.352458 115.437572) (end 151.36831 115.443119) (width 0.1) (layer "F.Cu") (net 153))
  (segment (start 151.317427 115.402541) (end 151.326362 115.416761) (width 0.1) (layer "F.Cu") (net 153))
  (segment (start 152.36831 115.29688) (end 152.385 115.295) (width 0.1) (layer "F.Cu") (net 153))
  (segment (start 152.067541 115.302427) (end 152.081761 115.311362) (width 0.1) (layer "F.Cu") (net 153))
  (segment (start 152.108119 115.35331) (end 152.11188 115.386689) (width 0.1) (layer "F.Cu") (net 153))
  (segment (start 150.738238 115.311362) (end 150.752458 115.302427) (width 0.1) (layer "F.Cu") (net 153))
  (segment (start 150.251689 115.443119) (end 150.267541 115.437572) (width 0.1) (layer "F.Cu") (net 153))
  (segment (start 151.726362 115.416761) (end 151.738238 115.428637) (width 0.1) (layer "F.Cu") (net 153))
  (segment (start 150.693637 115.416761) (end 150.702572 115.402541) (width 0.1) (layer "F.Cu") (net 153))
  (segment (start 151.451689 115.443119) (end 151.467541 115.437572) (width 0.1) (layer "F.Cu") (net 153))
  (segment (start 151.552458 115.302427) (end 151.56831 115.29688) (width 0.1) (layer "F.Cu") (net 153))
  (segment (start 151.493637 115.416761) (end 151.502572 115.402541) (width 0.1) (layer "F.Cu") (net 153))
  (segment (start 150.91188 115.386689) (end 150.917427 115.402541) (width 0.1) (layer "F.Cu") (net 153))
  (segment (start 152.352458 115.302427) (end 152.36831 115.29688) (width 0.1) (layer "F.Cu") (net 153))
  (segment (start 151.938238 115.311362) (end 151.952458 115.302427) (width 0.1) (layer "F.Cu") (net 153))
  (segment (start 151.785 115.445) (end 151.835 115.445) (width 0.1) (layer "F.Cu") (net 153))
  (segment (start 150.338238 115.311362) (end 150.352458 115.302427) (width 0.1) (layer "F.Cu") (net 153))
  (segment (start 151.851689 115.443119) (end 151.867541 115.437572) (width 0.1) (layer "F.Cu") (net 153))
  (segment (start 152.152458 115.437572) (end 152.16831 115.443119) (width 0.1) (layer "F.Cu") (net 153))
  (segment (start 150.481761 115.311362) (end 150.493637 115.323238) (width 0.1) (layer "F.Cu") (net 153))
  (segment (start 150.717427 115.337458) (end 150.726362 115.323238) (width 0.1) (layer "F.Cu") (net 153))
  (segment (start 150.702572 115.402541) (end 150.708119 115.386689) (width 0.1) (layer "F.Cu") (net 153))
  (segment (start 151.667541 115.302427) (end 151.681761 115.311362) (width 0.1) (layer "F.Cu") (net 153))
  (segment (start 152.385 115.295) (end 152.726422 115.295) (width 0.1) (layer "F.Cu") (net 153))
  (segment (start 152.081761 115.311362) (end 152.093637 115.323238) (width 0.1) (layer "F.Cu") (net 153))
  (segment (start 151.267541 115.302427) (end 151.281761 115.311362) (width 0.1) (layer "F.Cu") (net 153))
  (segment (start 150.538238 115.428637) (end 150.552458 115.437572) (width 0.1) (layer "F.Cu") (net 153))
  (segment (start 151.902572 115.402541) (end 151.908119 115.386689) (width 0.1) (layer "F.Cu") (net 153))
  (segment (start 151.051689 115.443119) (end 151.067541 115.437572) (width 0.1) (layer "F.Cu") (net 153))
  (segment (start 150.11188 115.386689) (end 150.117427 115.402541) (width 0.1) (layer "F.Cu") (net 153))
  (segment (start 150.302572 115.402541) (end 150.308119 115.386689) (width 0.1) (layer "F.Cu") (net 153))
  (segment (start 151.293637 115.323238) (end 151.302572 115.337458) (width 0.1) (layer "F.Cu") (net 153))
  (segment (start 148.965 115.5025) (end 149.618922 115.5025) (width 0.1) (layer "F.Cu") (net 153))
  (segment (start 151.081761 115.428637) (end 151.093637 115.416761) (width 0.1) (layer "F.Cu") (net 153))
  (segment (start 152.281761 115.428637) (end 152.293637 115.416761) (width 0.1) (layer "F.Cu") (net 153))
  (segment (start 152.317427 115.337458) (end 152.326362 115.323238) (width 0.1) (layer "F.Cu") (net 153))
  (segment (start 150.752458 115.302427) (end 150.76831 115.29688) (width 0.1) (layer "F.Cu") (net 153))
  (segment (start 150.035 115.295) (end 150.051689 115.29688) (width 0.1) (layer "F.Cu") (net 153))
  (segment (start 150.152458 115.437572) (end 150.16831 115.443119) (width 0.1) (layer "F.Cu") (net 153))
  (segment (start 150.867541 115.302427) (end 150.881761 115.311362) (width 0.1) (layer "F.Cu") (net 153))
  (segment (start 151.526362 115.323238) (end 151.538238 115.311362) (width 0.1) (layer "F.Cu") (net 153))
  (segment (start 151.102572 115.402541) (end 151.108119 115.386689) (width 0.1) (layer "F.Cu") (net 153))
  (segment (start 150.267541 115.437572) (end 150.281761 115.428637) (width 0.1) (layer "F.Cu") (net 153))
  (segment (start 149.618922 115.5025) (end 149.826422 115.295) (width 0.1) (layer "F.Cu") (net 153))
  (segment (start 151.035 115.445) (end 151.051689 115.443119) (width 0.1) (layer "F.Cu") (net 153))
  (segment (start 148.9025 115.565) (end 148.965 115.5025) (width 0.1) (layer "F.Cu") (net 153))
  (segment (start 150.56831 115.443119) (end 150.585 115.445) (width 0.1) (layer "F.Cu") (net 153))
  (segment (start 151.16831 115.29688) (end 151.185 115.295) (width 0.1) (layer "F.Cu") (net 153))
  (segment (start 152.185 115.445) (end 152.235 115.445) (width 0.1) (layer "F.Cu") (net 153))
  (segment (start 151.51188 115.35331) (end 151.517427 115.337458) (width 0.1) (layer "F.Cu") (net 153))
  (segment (start 152.302572 115.402541) (end 152.308119 115.386689) (width 0.1) (layer "F.Cu") (net 153))
  (segment (start 150.081761 115.311362) (end 150.093637 115.323238) (width 0.1) (layer "F.Cu") (net 153))
  (segment (start 150.108119 115.35331) (end 150.11188 115.386689) (width 0.1) (layer "F.Cu") (net 153))
  (segment (start 150.126362 115.416761) (end 150.138238 115.428637) (width 0.1) (layer "F.Cu") (net 153))
  (segment (start 151.385 115.445) (end 151.435 115.445) (width 0.1) (layer "F.Cu") (net 153))
  (segment (start 151.985 115.295) (end 152.035 115.295) (width 0.1) (layer "F.Cu") (net 153))
  (segment (start 150.093637 115.323238) (end 150.102572 115.337458) (width 0.1) (layer "F.Cu") (net 153))
  (segment (start 150.067541 115.302427) (end 150.081761 115.311362) (width 0.1) (layer "F.Cu") (net 153))
  (segment (start 151.717427 115.402541) (end 151.726362 115.416761) (width 0.1) (layer "F.Cu") (net 153))
  (segment (start 152.138238 115.428637) (end 152.152458 115.437572) (width 0.1) (layer "F.Cu") (net 153))
  (segment (start 150.293637 115.416761) (end 150.302572 115.402541) (width 0.1) (layer "F.Cu") (net 153))
  (segment (start 150.952458 115.437572) (end 150.96831 115.443119) (width 0.1) (layer "F.Cu") (net 153))
  (segment (start 151.76831 115.443119) (end 151.785 115.445) (width 0.1) (layer "F.Cu") (net 153))
  (segment (start 166.2375 119.8) (end 166.5 120.0625) (width 0.1) (layer "F.Cu") (net 153))
  (segment (start 152.308119 115.386689) (end 152.31188 115.35331) (width 0.1) (layer "F.Cu") (net 153))
  (segment (start 152.035 115.295) (end 152.051689 115.29688) (width 0.1) (layer "F.Cu") (net 153))
  (segment (start 151.738238 115.428637) (end 151.752458 115.437572) (width 0.1) (layer "F.Cu") (net 153))
  (segment (start 151.91188 115.35331) (end 151.917427 115.337458) (width 0.1) (layer "F.Cu") (net 153))
  (segment (start 150.31188 115.35331) (end 150.317427 115.337458) (width 0.1) (layer "F.Cu") (net 153))
  (segment (start 150.708119 115.386689) (end 150.71188 115.35331) (width 0.1) (layer "F.Cu") (net 153))
  (segment (start 150.281761 115.428637) (end 150.293637 115.416761) (width 0.1) (layer "F.Cu") (net 153))
  (segment (start 153.016128 115.166907) (end 153.216907 115.166907) (width 0.1) (layer "F.Cu") (net 153))
  (segment (start 152.117427 115.402541) (end 152.126362 115.416761) (width 0.1) (layer "F.Cu") (net 153))
  (segment (start 151.926362 115.323238) (end 151.938238 115.311362) (width 0.1) (layer "F.Cu") (net 153))
  (segment (start 150.502572 115.337458) (end 150.508119 115.35331) (width 0.1) (layer "F.Cu") (net 153))
  (segment (start 150.552458 115.437572) (end 150.56831 115.443119) (width 0.1) (layer "F.Cu") (net 153))
  (segment (start 150.526362 115.416761) (end 150.538238 115.428637) (width 0.1) (layer "F.Cu") (net 153))
  (segment (start 150.785 115.295) (end 150.835 115.295) (width 0.1) (layer "F.Cu") (net 153))
  (segment (start 150.326362 115.323238) (end 150.338238 115.311362) (width 0.1) (layer "F.Cu") (net 153))
  (segment (start 151.952458 115.302427) (end 151.96831 115.29688) (width 0.1) (layer "F.Cu") (net 153))
  (segment (start 151.835 115.445) (end 151.851689 115.443119) (width 0.1) (layer "F.Cu") (net 153))
  (segment (start 151.067541 115.437572) (end 151.081761 115.428637) (width 0.1) (layer "F.Cu") (net 153))
  (segment (start 151.11188 115.35331) (end 151.117427 115.337458) (width 0.1) (layer "F.Cu") (net 153))
  (segment (start 151.093637 115.416761) (end 151.102572 115.402541) (width 0.1) (layer "F.Cu") (net 153))
  (segment (start 152.293637 115.416761) (end 152.302572 115.402541) (width 0.1) (layer "F.Cu") (net 153))
  (segment (start 150.908119 115.35331) (end 150.91188 115.386689) (width 0.1) (layer "F.Cu") (net 153))
  (segment (start 151.36831 115.443119) (end 151.385 115.445) (width 0.1) (layer "F.Cu") (net 153))
  (segment (start 151.338238 115.428637) (end 151.352458 115.437572) (width 0.1) (layer "F.Cu") (net 153))
  (segment (start 150.317427 115.337458) (end 150.326362 115.323238) (width 0.1) (layer "F.Cu") (net 153))
  (segment (start 151.108119 115.386689) (end 151.11188 115.35331) (width 0.1) (layer "F.Cu") (net 153))
  (segment (start 151.71188 115.386689) (end 151.717427 115.402541) (width 0.1) (layer "F.Cu") (net 153))
  (segment (start 150.508119 115.35331) (end 150.51188 115.386689) (width 0.1) (layer "F.Cu") (net 153))
  (segment (start 150.451689 115.29688) (end 150.467541 115.302427) (width 0.1) (layer "F.Cu") (net 153))
  (segment (start 151.96831 115.29688) (end 151.985 115.295) (width 0.1) (layer "F.Cu") (net 153))
  (segment (start 151.31188 115.386689) (end 151.317427 115.402541) (width 0.1) (layer "F.Cu") (net 153))
  (segment (start 162.6 119.95) (end 163.500001 119.95) (width 0.1) (layer "F.Cu") (net 153))
  (segment (start 152.126362 115.416761) (end 152.138238 115.428637) (width 0.1) (layer "F.Cu") (net 153))
  (segment (start 151.893637 115.416761) (end 151.902572 115.402541) (width 0.1) (layer "F.Cu") (net 153))
  (segment (start 151.908119 115.386689) (end 151.91188 115.35331) (width 0.1) (layer "F.Cu") (net 153))
  (segment (start 150.835 115.295) (end 150.851689 115.29688) (width 0.1) (layer "F.Cu") (net 153))
  (segment (start 150.102572 115.337458) (end 150.108119 115.35331) (width 0.1) (layer "F.Cu") (net 153))
  (segment (start 150.352458 115.302427) (end 150.36831 115.29688) (width 0.1) (layer "F.Cu") (net 153))
  (segment (start 151.693637 115.323238) (end 151.702572 115.337458) (width 0.1) (layer "F.Cu") (net 153))
  (segment (start 151.251689 115.29688) (end 151.267541 115.302427) (width 0.1) (layer "F.Cu") (net 153))
  (segment (start 163.500001 119.95) (end 163.650001 119.8) (width 0.1) (layer "F.Cu") (net 153))
  (segment (start 151.235 115.295) (end 151.251689 115.29688) (width 0.1) (layer "F.Cu") (net 153))
  (segment (start 151.467541 115.437572) (end 151.481761 115.428637) (width 0.1) (layer "F.Cu") (net 153))
  (segment (start 151.152458 115.302427) (end 151.16831 115.29688) (width 0.1) (layer "F.Cu") (net 153))
  (segment (start 150.051689 115.29688) (end 150.067541 115.302427) (width 0.1) (layer "F.Cu") (net 153))
  (segment (start 150.76831 115.29688) (end 150.785 115.295) (width 0.1) (layer "F.Cu") (net 153))
  (segment (start 151.326362 115.416761) (end 151.338238 115.428637) (width 0.1) (layer "F.Cu") (net 153))
  (segment (start 150.235 115.445) (end 150.251689 115.443119) (width 0.1) (layer "F.Cu") (net 153))
  (segment (start 151.867541 115.437572) (end 151.881761 115.428637) (width 0.1) (layer "F.Cu") (net 153))
  (segment (start 150.881761 115.311362) (end 150.893637 115.323238) (width 0.1) (layer "F.Cu") (net 153))
  (segment (start 150.938238 115.428637) (end 150.952458 115.437572) (width 0.1) (layer "F.Cu") (net 153))
  (segment (start 148.495 115.565) (end 148.9025 115.565) (width 0.1) (layer "F.Cu") (net 153))
  (segment (start 151.702572 115.337458) (end 151.708119 115.35331) (width 0.1) (layer "F.Cu") (net 153))
  (segment (start 150.51188 115.386689) (end 150.517427 115.402541) (width 0.1) (layer "F.Cu") (net 153))
  (segment (start 150.726362 115.323238) (end 150.738238 115.311362) (width 0.1) (layer "F.Cu") (net 153))
  (segment (start 151.917427 115.337458) (end 151.926362 115.323238) (width 0.1) (layer "F.Cu") (net 153))
  (segment (start 152.31188 115.35331) (end 152.317427 115.337458) (width 0.1) (layer "F.Cu") (net 153))
  (segment (start 152.267541 115.437572) (end 152.281761 115.428637) (width 0.1) (layer "F.Cu") (net 153))
  (segment (start 152.11188 115.386689) (end 152.117427 115.402541) (width 0.1) (layer "F.Cu") (net 153))
  (segment (start 150.96831 115.443119) (end 150.985 115.445) (width 0.1) (layer "F.Cu") (net 153))
  (segment (start 151.681761 115.311362) (end 151.693637 115.323238) (width 0.1) (layer "F.Cu") (net 153))
  (segment (start 150.635 115.445) (end 150.651689 115.443119) (width 0.1) (layer "F.Cu") (net 153))
  (segment (start 151.502572 115.402541) (end 151.508119 115.386689) (width 0.1) (layer "F.Cu") (net 153))
  (segment (start 151.126362 115.323238) (end 151.138238 115.311362) (width 0.1) (layer "F.Cu") (net 153))
  (segment (start 150.681761 115.428637) (end 150.693637 115.416761) (width 0.1) (layer "F.Cu") (net 153))
  (segment (start 150.926362 115.416761) (end 150.938238 115.428637) (width 0.1) (layer "F.Cu") (net 153))
  (segment (start 150.585 115.445) (end 150.635 115.445) (width 0.1) (layer "F.Cu") (net 153))
  (segment (start 151.435 115.445) (end 151.451689 115.443119) (width 0.1) (layer "F.Cu") (net 153))
  (segment (start 152.326362 115.323238) (end 152.338238 115.311362) (width 0.1) (layer "F.Cu") (net 153))
  (segment (start 152.726422 115.295) (end 152.854515 115.166907) (width 0.1) (layer "F.Cu") (net 153))
  (segment (start 152.854515 115.166907) (end 153.016128 115.166907) (width 0.1) (layer "F.Cu") (net 153))
  (segment (start 150.435 115.295) (end 150.451689 115.29688) (width 0.1) (layer "F.Cu") (net 153))
  (segment (start 150.308119 115.386689) (end 150.31188 115.35331) (width 0.1) (layer "F.Cu") (net 153))
  (segment (start 150.902572 115.337458) (end 150.908119 115.35331) (width 0.1) (layer "F.Cu") (net 153))
  (segment (start 151.308119 115.35331) (end 151.31188 115.386689) (width 0.1) (layer "F.Cu") (net 153))
  (segment (start 151.635 115.295) (end 151.651689 115.29688) (width 0.1) (layer "F.Cu") (net 153))
  (segment (start 150.117427 115.402541) (end 150.126362 115.416761) (width 0.1) (layer "F.Cu") (net 153))
  (segment (start 150.985 115.445) (end 151.035 115.445) (width 0.1) (layer "F.Cu") (net 153))
  (segment (start 152.338238 115.311362) (end 152.352458 115.302427) (width 0.1) (layer "F.Cu") (net 153))
  (segment (start 150.16831 115.443119) (end 150.185 115.445) (width 0.1) (layer "F.Cu") (net 153))
  (segment (start 163.650001 119.8) (end 166.2375 119.8) (width 0.1) (layer "F.Cu") (net 153))
  (segment (start 152.251689 115.443119) (end 152.267541 115.437572) (width 0.1) (layer "F.Cu") (net 153))
  (segment (start 150.71188 115.35331) (end 150.717427 115.337458) (width 0.1) (layer "F.Cu") (net 153))
  (segment (start 150.893637 115.323238) (end 150.902572 115.337458) (width 0.1) (layer "F.Cu") (net 153))
  (segment (start 152.235 115.445) (end 152.251689 115.443119) (width 0.1) (layer "F.Cu") (net 153))
  (segment (start 151.508119 115.386689) (end 151.51188 115.35331) (width 0.1) (layer "F.Cu") (net 153))
  (segment (start 151.881761 115.428637) (end 151.893637 115.416761) (width 0.1) (layer "F.Cu") (net 153))
  (segment (start 150.493637 115.323238) (end 150.502572 115.337458) (width 0.1) (layer "F.Cu") (net 153))
  (segment (start 150.917427 115.402541) (end 150.926362 115.416761) (width 0.1) (layer "F.Cu") (net 153))
  (segment (start 150.36831 115.29688) (end 150.385 115.295) (width 0.1) (layer "F.Cu") (net 153))
  (segment (start 151.585 115.295) (end 151.635 115.295) (width 0.1) (layer "F.Cu") (net 153))
  (segment (start 150.651689 115.443119) (end 150.667541 115.437572) (width 0.1) (layer "F.Cu") (net 153))
  (segment (start 151.138238 115.311362) (end 151.152458 115.302427) (width 0.1) (layer "F.Cu") (net 153))
  (segment (start 152.051689 115.29688) (end 152.067541 115.302427) (width 0.1) (layer "F.Cu") (net 153))
  (segment (start 152.102572 115.337458) (end 152.108119 115.35331) (width 0.1) (layer "F.Cu") (net 153))
  (segment (start 151.281761 115.311362) (end 151.293637 115.323238) (width 0.1) (layer "F.Cu") (net 153))
  (segment (start 150.467541 115.302427) (end 150.481761 115.311362) (width 0.1) (layer "F.Cu") (net 153))
  (segment (start 151.185 115.295) (end 151.235 115.295) (width 0.1) (layer "F.Cu") (net 153))
  (segment (start 151.302572 115.337458) (end 151.308119 115.35331) (width 0.1) (layer "F.Cu") (net 153))
  (segment (start 152.16831 115.443119) (end 152.185 115.445) (width 0.1) (layer "F.Cu") (net 153))
  (via (at 155.730008 116.56625) (size 0.55) (drill 0.15) (layers "F.Cu" "B.Cu") (net 153))
  (via (at 153.216907 115.166907) (size 0.55) (drill 0.15) (layers "F.Cu" "B.Cu") (net 153))
  (via (at 166.5 120.0625) (size 0.55) (drill 0.15) (layers "F.Cu" "B.Cu") (net 153))
  (segment (start 153.216907 115.166907) (end 154.330665 115.166907) (width 0.15) (layer "In3.Cu") (net 153))
  (segment (start 154.330665 115.166907) (end 155.730008 116.56625) (width 0.15) (layer "In3.Cu") (net 153))
  (segment (start 160.843116 119.014659) (end 160.853081 118.970995) (width 0.1) (layer "B.Cu") (net 153))
  (segment (start 160.424416 119.662049) (end 160.424416 119.577653) (width 0.1) (layer "B.Cu") (net 153))
  (segment (start 159.575888 118.729125) (end 159.594668 118.646845) (width 0.1) (layer "B.Cu") (net 153))
  (segment (start 159.994588 118.034019) (end 159.975156 117.993669) (width 0.1) (layer "B.Cu") (net 153))
  (segment (start 161.361446 119.65571) (end 161.09812 119.919037) (width 0.1) (layer "B.Cu") (net 153))
  (segment (start 159.975156 118.206481) (end 159.994588 118.166131) (width 0.1) (layer "B.Cu") (net 153))
  (segment (start 159.716592 119.070508) (end 159.683905 119.037821) (width 0.1) (layer "B.Cu") (net 153))
  (segment (start 160.547933 118.779259) (end 160.512918 118.807182) (width 0.1) (layer "B.Cu") (net 153))
  (segment (start 160.588285 118.759828) (end 160.547933 118.779259) (width 0.1) (layer "B.Cu") (net 153))
  (segment (start 160.424416 119.577653) (end 160.443196 119.495373) (width 0.1) (layer "B.Cu") (net 153))
  (segment (start 160.56512 119.919036) (end 160.532433 119.886349) (width 0.1) (layer "B.Cu") (net 153))
  (segment (start 160.707142 120.008274) (end 160.631104 119.971656) (width 0.1) (layer "B.Cu") (net 153))
  (segment (start 159.575888 118.813521) (end 159.575888 118.729125) (width 0.1) (layer "B.Cu") (net 153))
  (segment (start 160.843116 118.882547) (end 160.823684 118.842197) (width 0.1) (layer "B.Cu") (net 153))
  (segment (start 160.004553 118.077681) (end 159.994588 118.034019) (width 0.1) (layer "B.Cu") (net 153))
  (segment (start 160.10757 119.159747) (end 160.02529 119.178526) (width 0.1) (layer "B.Cu") (net 153))
  (segment (start 160.631947 118.749861) (end 160.588285 118.759828) (width 0.1) (layer "B.Cu") (net 153))
  (segment (start 160.795761 119.090024) (end 160.823684 119.055009) (width 0.1) (layer "B.Cu") (net 153))
  (segment (start 159.994588 118.166131) (end 160.004553 118.122467) (width 0.1) (layer "B.Cu") (net 153))
  (segment (start 159.940894 119.178526) (end 159.858614 119.159746) (width 0.1) (layer "B.Cu") (net 153))
  (segment (start 159.947234 117.958655) (end 158.298578 116.31) (width 0.1) (layer "B.Cu") (net 153))
  (segment (start 159.947233 118.241496) (end 159.975156 118.206481) (width 0.1) (layer "B.Cu") (net 153))
  (segment (start 161.480475 119.598389) (end 161.436813 119.608356) (width 0.1) (layer "B.Cu") (net 153))
  (segment (start 161.568923 119.608355) (end 161.525261 119.59839) (width 0.1) (layer "B.Cu") (net 153))
  (segment (start 166.2375 119.8) (end 161.788578 119.8) (width 0.1) (layer "B.Cu") (net 153))
  (segment (start 160.02529 119.178526) (end 159.940894 119.178526) (width 0.1) (layer "B.Cu") (net 153))
  (segment (start 161.64429 119.655711) (end 161.609275 119.627788) (width 0.1) (layer "B.Cu") (net 153))
  (segment (start 161.525261 119.59839) (end 161.480475 119.598389) (width 0.1) (layer "B.Cu") (net 153))
  (segment (start 159.683905 119.037821) (end 159.631286 118.971839) (width 0.1) (layer "B.Cu") (net 153))
  (segment (start 159.683905 118.504823) (end 159.947233 118.241496) (width 0.1) (layer "B.Cu") (net 153))
  (segment (start 159.631286 118.971839) (end 159.594668 118.895801) (width 0.1) (layer "B.Cu") (net 153))
  (segment (start 160.676733 118.749862) (end 160.631947 118.749861) (width 0.1) (layer "B.Cu") (net 153))
  (segment (start 160.532433 119.353351) (end 160.795761 119.090024) (width 0.1) (layer "B.Cu") (net 153))
  (segment (start 159.594668 118.895801) (end 159.575888 118.813521) (width 0.1) (layer "B.Cu") (net 153))
  (segment (start 160.443196 119.495373) (end 160.479814 119.419335) (width 0.1) (layer "B.Cu") (net 153))
  (segment (start 160.004553 118.122467) (end 160.004553 118.077681) (width 0.1) (layer "B.Cu") (net 153))
  (segment (start 161.032136 119.971657) (end 160.956098 120.008275) (width 0.1) (layer "B.Cu") (net 153))
  (segment (start 160.853081 118.926209) (end 160.843116 118.882547) (width 0.1) (layer "B.Cu") (net 153))
  (segment (start 160.249592 119.070509) (end 160.183608 119.123129) (width 0.1) (layer "B.Cu") (net 153))
  (segment (start 159.858614 119.159746) (end 159.782576 119.123128) (width 0.1) (layer "B.Cu") (net 153))
  (segment (start 160.823684 119.055009) (end 160.843116 119.014659) (width 0.1) (layer "B.Cu") (net 153))
  (segment (start 159.975156 117.993669) (end 159.947234 117.958655) (width 0.1) (layer "B.Cu") (net 153))
  (segment (start 160.789422 120.027054) (end 160.707142 120.008274) (width 0.1) (layer "B.Cu") (net 153))
  (segment (start 160.956098 120.008275) (end 160.873818 120.027054) (width 0.1) (layer "B.Cu") (net 153))
  (segment (start 160.720395 118.759827) (end 160.676733 118.749862) (width 0.1) (layer "B.Cu") (net 153))
  (segment (start 160.479814 119.820367) (end 160.443196 119.744329) (width 0.1) (layer "B.Cu") (net 153))
  (segment (start 158.298578 116.31) (end 155.986258 116.31) (width 0.1) (layer "B.Cu") (net 153))
  (segment (start 160.795762 118.807183) (end 160.760747 118.77926) (width 0.1) (layer "B.Cu") (net 153))
  (segment (start 161.09812 119.919037) (end 161.032136 119.971657) (width 0.1) (layer "B.Cu") (net 153))
  (segment (start 161.396461 119.627787) (end 161.361446 119.65571) (width 0.1) (layer "B.Cu") (net 153))
  (segment (start 166.5 120.0625) (end 166.2375 119.8) (width 0.1) (layer "B.Cu") (net 153))
  (segment (start 161.788578 119.8) (end 161.64429 119.655711) (width 0.1) (layer "B.Cu") (net 153))
  (segment (start 159.594668 118.646845) (end 159.631286 118.570807) (width 0.1) (layer "B.Cu") (net 153))
  (segment (start 160.512918 118.807182) (end 160.249592 119.070509) (width 0.1) (layer "B.Cu") (net 153))
  (segment (start 160.873818 120.027054) (end 160.789422 120.027054) (width 0.1) (layer "B.Cu") (net 153))
  (segment (start 160.443196 119.744329) (end 160.424416 119.662049) (width 0.1) (layer "B.Cu") (net 153))
  (segment (start 161.436813 119.608356) (end 161.396461 119.627787) (width 0.1) (layer "B.Cu") (net 153))
  (segment (start 160.631104 119.971656) (end 160.56512 119.919036) (width 0.1) (layer "B.Cu") (net 153))
  (segment (start 160.853081 118.970995) (end 160.853081 118.926209) (width 0.1) (layer "B.Cu") (net 153))
  (segment (start 159.631286 118.570807) (end 159.683905 118.504823) (width 0.1) (layer "B.Cu") (net 153))
  (segment (start 160.760747 118.77926) (end 160.720395 118.759827) (width 0.1) (layer "B.Cu") (net 153))
  (segment (start 160.479814 119.419335) (end 160.532433 119.353351) (width 0.1) (layer "B.Cu") (net 153))
  (segment (start 160.823684 118.842197) (end 160.795762 118.807183) (width 0.1) (layer "B.Cu") (net 153))
  (segment (start 155.986258 116.31) (end 155.730008 116.56625) (width 0.1) (layer "B.Cu") (net 153))
  (segment (start 160.183608 119.123129) (end 160.10757 119.159747) (width 0.1) (layer "B.Cu") (net 153))
  (segment (start 161.609275 119.627788) (end 161.568923 119.608355) (width 0.1) (layer "B.Cu") (net 153))
  (segment (start 160.532433 119.886349) (end 160.479814 119.820367) (width 0.1) (layer "B.Cu") (net 153))
  (segment (start 159.782576 119.123128) (end 159.716592 119.070508) (width 0.1) (layer "B.Cu") (net 153))
  (segment (start 162.6 119.45) (end 163.500001 119.45) (width 0.1) (layer "F.Cu") (net 154))
  (segment (start 149.536078 115.3025) (end 149.743578 115.095) (width 0.1) (layer "F.Cu") (net 154))
  (segment (start 166.2375 119.6) (end 166.5 119.3375) (width 0.1) (layer "F.Cu") (net 154))
  (segment (start 149.743578 115.095) (end 152.643578 115.095) (width 0.1) (layer "F.Cu") (net 154))
  (segment (start 148.9025 115.24) (end 148.965 115.3025) (width 0.1) (layer "F.Cu") (net 154))
  (segment (start 163.500001 119.45) (end 163.650001 119.6) (width 0.1) (layer "F.Cu") (net 154))
  (segment (start 148.17 115.24) (end 148.9025 115.24) (width 0.1) (layer "F.Cu") (net 154))
  (segment (start 152.643578 115.095) (end 152.713093 115.025485) (width 0.1) (layer "F.Cu") (net 154))
  (segment (start 147.845 115.565) (end 148.17 115.24) (width 0.1) (layer "F.Cu") (net 154))
  (segment (start 163.650001 119.6) (end 166.2375 119.6) (width 0.1) (layer "F.Cu") (net 154))
  (segment (start 148.965 115.3025) (end 149.536078 115.3025) (width 0.1) (layer "F.Cu") (net 154))
  (segment (start 152.713093 115.025485) (end 152.713093 114.663093) (width 0.1) (layer "F.Cu") (net 154))
  (via (at 152.713093 114.663093) (size 0.55) (drill 0.15) (layers "F.Cu" "B.Cu") (net 154))
  (via (at 155.730008 115.85375) (size 0.55) (drill 0.15) (layers "F.Cu" "B.Cu") (net 154))
  (via (at 166.5 119.3375) (size 0.55) (drill 0.15) (layers "F.Cu" "B.Cu") (net 154))
  (segment (start 152.713093 114.663093) (end 154.539351 114.663093) (width 0.15) (layer "In3.Cu") (net 154))
  (segment (start 154.539351 114.663093) (end 155.730008 115.85375) (width 0.15) (layer "In3.Cu") (net 154))
  (segment (start 159.813748 118.664917) (end 159.841671 118.629901) (width 0.1) (layer "B.Cu") (net 154))
  (segment (start 160.529863 118.56018) (end 160.453825 118.596798) (width 0.1) (layer "B.Cu") (net 154))
  (segment (start 160.632877 119.642243) (end 160.632877 119.597457) (width 0.1) (layer "B.Cu") (net 154))
  (segment (start 160.662276 119.513445) (end 160.690199 119.478429) (width 0.1) (layer "B.Cu") (net 154))
  (segment (start 159.960699 118.970065) (end 159.917037 118.9601) (width 0.1) (layer "B.Cu") (net 154))
  (segment (start 160.642844 119.553795) (end 160.662276 119.513445) (width 0.1) (layer "B.Cu") (net 154))
  (segment (start 160.104998 118.366575) (end 160.157618 118.300591) (width 0.1) (layer "B.Cu") (net 154))
  (segment (start 160.690199 119.478429) (end 160.953526 119.215103) (width 0.1) (layer "B.Cu") (net 154))
  (segment (start 160.973042 119.761273) (end 160.938027 119.789196) (width 0.1) (layer "B.Cu") (net 154))
  (segment (start 161.871422 119.6) (end 161.769367 119.497945) (width 0.1) (layer "B.Cu") (net 154))
  (segment (start 161.061543 118.990801) (end 161.061543 118.906405) (width 0.1) (layer "B.Cu") (net 154))
  (segment (start 160.6902 119.761273) (end 160.662275 119.726257) (width 0.1) (layer "B.Cu") (net 154))
  (segment (start 161.061543 118.906405) (end 161.042763 118.824125) (width 0.1) (layer "B.Cu") (net 154))
  (segment (start 160.632877 119.597457) (end 160.642844 119.553795) (width 0.1) (layer "B.Cu") (net 154))
  (segment (start 160.089499 118.940668) (end 160.049149 118.9601) (width 0.1) (layer "B.Cu") (net 154))
  (segment (start 160.005485 118.970065) (end 159.960699 118.970065) (width 0.1) (layer "B.Cu") (net 154))
  (segment (start 161.769367 119.497945) (end 161.703383 119.445325) (width 0.1) (layer "B.Cu") (net 154))
  (segment (start 160.049149 118.9601) (end 160.005485 118.970065) (width 0.1) (layer "B.Cu") (net 154))
  (segment (start 160.104997 117.833575) (end 158.381422 116.11) (width 0.1) (layer "B.Cu") (net 154))
  (segment (start 159.794316 118.705267) (end 159.813748 118.664917) (width 0.1) (layer "B.Cu") (net 154))
  (segment (start 160.662275 119.726257) (end 160.642844 119.685907) (width 0.1) (layer "B.Cu") (net 154))
  (segment (start 159.841672 118.912745) (end 159.813747 118.877729) (width 0.1) (layer "B.Cu") (net 154))
  (segment (start 159.841671 118.629901) (end 160.104998 118.366575) (width 0.1) (layer "B.Cu") (net 154))
  (segment (start 159.876687 118.940668) (end 159.841672 118.912745) (width 0.1) (layer "B.Cu") (net 154))
  (segment (start 161.006146 119.149119) (end 161.042764 119.073081) (width 0.1) (layer "B.Cu") (net 154))
  (segment (start 161.545065 119.389927) (end 161.460671 119.389928) (width 0.1) (layer "B.Cu") (net 154))
  (segment (start 161.378391 119.408708) (end 161.302353 119.445326) (width 0.1) (layer "B.Cu") (net 154))
  (segment (start 160.725215 119.789196) (end 160.6902 119.761273) (width 0.1) (layer "B.Cu") (net 154))
  (segment (start 160.124514 118.912745) (end 160.089499 118.940668) (width 0.1) (layer "B.Cu") (net 154))
  (segment (start 160.194236 118.224553) (end 160.213015 118.142273) (width 0.1) (layer "B.Cu") (net 154))
  (segment (start 155.986258 116.11) (end 155.730008 115.85375) (width 0.1) (layer "B.Cu") (net 154))
  (segment (start 161.703383 119.445325) (end 161.627345 119.408707) (width 0.1) (layer "B.Cu") (net 154))
  (segment (start 160.953526 119.215103) (end 161.006146 119.149119) (width 0.1) (layer "B.Cu") (net 154))
  (segment (start 161.236369 119.497946) (end 160.973042 119.761273) (width 0.1) (layer "B.Cu") (net 154))
  (segment (start 159.784349 118.748929) (end 159.794316 118.705267) (width 0.1) (layer "B.Cu") (net 154))
  (segment (start 160.778817 118.560179) (end 160.696537 118.541399) (width 0.1) (layer "B.Cu") (net 154))
  (segment (start 159.917037 118.9601) (end 159.876687 118.940668) (width 0.1) (layer "B.Cu") (net 154))
  (segment (start 160.213015 118.057877) (end 160.194235 117.975597) (width 0.1) (layer "B.Cu") (net 154))
  (segment (start 158.381422 116.11) (end 155.986258 116.11) (width 0.1) (layer "B.Cu") (net 154))
  (segment (start 160.194235 117.975597) (end 160.157617 117.899559) (width 0.1) (layer "B.Cu") (net 154))
  (segment (start 160.696537 118.541399) (end 160.612143 118.5414) (width 0.1) (layer "B.Cu") (net 154))
  (segment (start 160.387841 118.649418) (end 160.124514 118.912745) (width 0.1) (layer "B.Cu") (net 154))
  (segment (start 161.302353 119.445326) (end 161.236369 119.497946) (width 0.1) (layer "B.Cu") (net 154))
  (segment (start 160.809227 119.818593) (end 160.765565 119.808628) (width 0.1) (layer "B.Cu") (net 154))
  (segment (start 161.042764 119.073081) (end 161.061543 118.990801) (width 0.1) (layer "B.Cu") (net 154))
  (segment (start 160.453825 118.596798) (end 160.387841 118.649418) (width 0.1) (layer "B.Cu") (net 154))
  (segment (start 160.953525 118.682103) (end 160.920839 118.649417) (width 0.1) (layer "B.Cu") (net 154))
  (segment (start 160.854855 118.596797) (end 160.778817 118.560179) (width 0.1) (layer "B.Cu") (net 154))
  (segment (start 166.5 119.3375) (end 166.2375 119.6) (width 0.1) (layer "B.Cu") (net 154))
  (segment (start 160.157618 118.300591) (end 160.194236 118.224553) (width 0.1) (layer "B.Cu") (net 154))
  (segment (start 160.920839 118.649417) (end 160.854855 118.596797) (width 0.1) (layer "B.Cu") (net 154))
  (segment (start 161.042763 118.824125) (end 161.006145 118.748087) (width 0.1) (layer "B.Cu") (net 154))
  (segment (start 160.765565 119.808628) (end 160.725215 119.789196) (width 0.1) (layer "B.Cu") (net 154))
  (segment (start 159.813747 118.877729) (end 159.794316 118.837379) (width 0.1) (layer "B.Cu") (net 154))
  (segment (start 159.794316 118.837379) (end 159.784349 118.793715) (width 0.1) (layer "B.Cu") (net 154))
  (segment (start 160.938027 119.789196) (end 160.897677 119.808628) (width 0.1) (layer "B.Cu") (net 154))
  (segment (start 160.612143 118.5414) (end 160.529863 118.56018) (width 0.1) (layer "B.Cu") (net 154))
  (segment (start 161.460671 119.389928) (end 161.378391 119.408708) (width 0.1) (layer "B.Cu") (net 154))
  (segment (start 160.213015 118.142273) (end 160.213015 118.057877) (width 0.1) (layer "B.Cu") (net 154))
  (segment (start 160.157617 117.899559) (end 160.104997 117.833575) (width 0.1) (layer "B.Cu") (net 154))
  (segment (start 161.006145 118.748087) (end 160.953525 118.682103) (width 0.1) (layer "B.Cu") (net 154))
  (segment (start 160.854013 119.818593) (end 160.809227 119.818593) (width 0.1) (layer "B.Cu") (net 154))
  (segment (start 166.2375 119.6) (end 161.871422 119.6) (width 0.1) (layer "B.Cu") (net 154))
  (segment (start 160.897677 119.808628) (end 160.854013 119.818593) (width 0.1) (layer "B.Cu") (net 154))
  (segment (start 160.642844 119.685907) (end 160.632877 119.642243) (width 0.1) (layer "B.Cu") (net 154))
  (segment (start 159.784349 118.793715) (end 159.784349 118.748929) (width 0.1) (layer "B.Cu") (net 154))
  (segment (start 161.627345 119.408707) (end 161.545065 119.389927) (width 0.1) (layer "B.Cu") (net 154))
  (segment (start 148.341422 112.4) (end 148.77 112.4) (width 0.1) (layer "F.Cu") (net 155))
  (segment (start 148.792252 112.402507) (end 148.813388 112.409903) (width 0.1) (layer "F.Cu") (net 155))
  (segment (start 149.17 112.4) (end 151.00875 112.4) (width 0.1) (layer "F.Cu") (net 155))
  (segment (start 148.891816 112.614544) (end 148.907651 112.630379) (width 0.1) (layer "F.Cu") (net 155))
  (segment (start 148.872507 112.574448) (end 148.879903 112.595584) (width 0.1) (layer "F.Cu") (net 155))
  (segment (start 148.907651 112.630379) (end 148.926611 112.642292) (width 0.1) (layer "F.Cu") (net 155))
  (segment (start 149.067492 112.574448) (end 149.07 112.552196) (width 0.1) (layer "F.Cu") (net 155))
  (segment (start 148.813388 112.409903) (end 148.832348 112.421816) (width 0.1) (layer "F.Cu") (net 155))
  (segment (start 149.048183 112.614544) (end 149.060096 112.595584) (width 0.1) (layer "F.Cu") (net 155))
  (segment (start 148.926611 112.642292) (end 148.947747 112.649688) (width 0.1) (layer "F.Cu") (net 155))
  (segment (start 163.650001 118.8) (end 165.2155 118.8) (width 0.1) (layer "F.Cu") (net 155))
  (segment (start 149.060096 112.595584) (end 149.067492 112.574448) (width 0.1) (layer "F.Cu") (net 155))
  (segment (start 149.079903 112.456611) (end 149.091816 112.437651) (width 0.1) (layer "F.Cu") (net 155))
  (segment (start 165.2155 118.8) (end 165.478 119.0625) (width 0.1) (layer "F.Cu") (net 155))
  (segment (start 149.091816 112.437651) (end 149.107651 112.421816) (width 0.1) (layer "F.Cu") (net 155))
  (segment (start 149.013388 112.642292) (end 149.032348 112.630379) (width 0.1) (layer "F.Cu") (net 155))
  (segment (start 149.147747 112.402507) (end 149.17 112.4) (width 0.1) (layer "F.Cu") (net 155))
  (segment (start 148.495 112.965) (end 148.27 112.74) (width 0.1) (layer "F.Cu") (net 155))
  (segment (start 148.87 112.5) (end 148.87 112.552196) (width 0.1) (layer "F.Cu") (net 155))
  (segment (start 148.832348 112.421816) (end 148.848183 112.437651) (width 0.1) (layer "F.Cu") (net 155))
  (segment (start 148.87 112.552196) (end 148.872507 112.574448) (width 0.1) (layer "F.Cu") (net 155))
  (segment (start 149.07 112.5) (end 149.072507 112.477747) (width 0.1) (layer "F.Cu") (net 155))
  (segment (start 163.500001 118.95) (end 163.650001 118.8) (width 0.1) (layer "F.Cu") (net 155))
  (segment (start 162.6 118.95) (end 163.500001 118.95) (width 0.1) (layer "F.Cu") (net 155))
  (segment (start 148.879903 112.595584) (end 148.891816 112.614544) (width 0.1) (layer "F.Cu") (net 155))
  (segment (start 149.072507 112.477747) (end 149.079903 112.456611) (width 0.1) (layer "F.Cu") (net 155))
  (segment (start 148.77 112.4) (end 148.792252 112.402507) (width 0.1) (layer "F.Cu") (net 155))
  (segment (start 149.032348 112.630379) (end 149.048183 112.614544) (width 0.1) (layer "F.Cu") (net 155))
  (segment (start 149.107651 112.421816) (end 149.126611 112.409903) (width 0.1) (layer "F.Cu") (net 155))
  (segment (start 148.860096 112.456611) (end 148.867492 112.477747) (width 0.1) (layer "F.Cu") (net 155))
  (segment (start 148.27 112.74) (end 148.27 112.471422) (width 0.1) (layer "F.Cu") (net 155))
  (segment (start 148.27 112.471422) (end 148.341422 112.4) (width 0.1) (layer "F.Cu") (net 155))
  (segment (start 148.97 112.652196) (end 148.992252 112.649688) (width 0.1) (layer "F.Cu") (net 155))
  (segment (start 149.07 112.552196) (end 149.07 112.5) (width 0.1) (layer "F.Cu") (net 155))
  (segment (start 148.867492 112.477747) (end 148.87 112.5) (width 0.1) (layer "F.Cu") (net 155))
  (segment (start 149.126611 112.409903) (end 149.147747 112.402507) (width 0.1) (layer "F.Cu") (net 155))
  (segment (start 148.848183 112.437651) (end 148.860096 112.456611) (width 0.1) (layer "F.Cu") (net 155))
  (segment (start 151.00875 112.4) (end 151.265 112.65625) (width 0.1) (layer "F.Cu") (net 155))
  (segment (start 148.947747 112.649688) (end 148.97 112.652196) (width 0.1) (layer "F.Cu") (net 155))
  (segment (start 148.992252 112.649688) (end 149.013388 112.642292) (width 0.1) (layer "F.Cu") (net 155))
  (via (at 151.265 112.65625) (size 0.55) (drill 0.15) (layers "F.Cu" "B.Cu") (net 155))
  (via (at 165.478 119.0625) (size 0.55) (drill 0.15) (layers "F.Cu" "B.Cu") (net 155))
  (via (at 153.135 112.66125) (size 0.55) (drill 0.15) (layers "F.Cu" "B.Cu") (net 155))
  (segment (start 152.96125 112.4875) (end 151.43375 112.4875) (width 0.15) (layer "In3.Cu") (net 155))
  (segment (start 151.43375 112.4875) (end 151.265 112.65625) (width 0.15) (layer "In3.Cu") (net 155))
  (segment (start 153.135 112.66125) (end 152.96125 112.4875) (width 0.15) (layer "In3.Cu") (net 155))
  (segment (start 158.937032 115.345386) (end 158.955509 115.33892) (width 0.1) (layer "B.Cu") (net 155))
  (segment (start 159.002809 115.279609) (end 159.005 115.260156) (width 0.1) (layer "B.Cu") (net 155))
  (segment (start 158.800969 115.947578) (end 158.740708 115.940788) (width 0.1) (layer "B.Cu") (net 155))
  (segment (start 162.364268 119.143606) (end 162.356 119.070224) (width 0.1) (layer "B.Cu") (net 155))
  (segment (start 159.005 116.035) (end 159.002809 116.015546) (width 0.1) (layer "B.Cu") (net 155))
  (segment (start 163.156 119.070224) (end 163.147731 119.143606) (width 0.1) (layer "B.Cu") (net 155))
  (segment (start 158.917578 115.347578) (end 158.937032 115.345386) (width 0.1) (layer "B.Cu") (net 155))
  (segment (start 154.968578 114.31) (end 153.795 113.136422) (width 0.1) (layer "B.Cu") (net 155))
  (segment (start 163.523274 118.256477) (end 163.499523 118.232726) (width 0.1) (layer "B.Cu") (net 155))
  (segment (start 158.937032 115.949769) (end 158.917578 115.947578) (width 0.1) (layer "B.Cu") (net 155))
  (segment (start 165.2155 118.8) (end 163.885775 118.8) (width 0.1) (layer "B.Cu") (net 155))
  (segment (start 158.740708 115.354367) (end 158.800969 115.347578) (width 0.1) (layer "B.Cu") (net 155))
  (segment (start 158.536945 115.55813) (end 158.556974 115.50089) (width 0.1) (layer "B.Cu") (net 155))
  (segment (start 163.556 118.470225) (end 163.556 118.35) (width 0.1) (layer "B.Cu") (net 155))
  (segment (start 162.271082 118.814854) (end 162.239378 118.80376) (width 0.1) (layer "B.Cu") (net 155))
  (segment (start 163.031836 119.328053) (end 162.969308 119.367341) (width 0.1) (layer "B.Cu") (net 155))
  (segment (start 162.480163 119.328053) (end 162.427946 119.275836) (width 0.1) (layer "B.Cu") (net 155))
  (segment (start 158.556974 115.794265) (end 158.536945 115.737025) (width 0.1) (layer "B.Cu") (net 155))
  (segment (start 162.826224 119.4) (end 162.685775 119.4) (width 0.1) (layer "B.Cu") (net 155))
  (segment (start 158.530155 115.618391) (end 158.536945 115.55813) (width 0.1) (layer "B.Cu") (net 155))
  (segment (start 158.530155 115.676764) (end 158.530155 115.618391) (width 0.1) (layer "B.Cu") (net 155))
  (segment (start 162.542691 119.367341) (end 162.480163 119.328053) (width 0.1) (layer "B.Cu") (net 155))
  (segment (start 158.740708 115.940788) (end 158.683468 115.920759) (width 0.1) (layer "B.Cu") (net 155))
  (segment (start 163.588658 118.613309) (end 163.564268 118.543607) (width 0.1) (layer "B.Cu") (net 155))
  (segment (start 153.795 113.136422) (end 153.795 112.676422) (width 0.1) (layer "B.Cu") (net 155))
  (segment (start 163.212476 118.232726) (end 163.188725 118.256477) (width 0.1) (layer "B.Cu") (net 155))
  (segment (start 158.985928 115.314662) (end 158.996343 115.298086) (width 0.1) (layer "B.Cu") (net 155))
  (segment (start 163.084053 119.275836) (end 163.031836 119.328053) (width 0.1) (layer "B.Cu") (net 155))
  (segment (start 163.123341 119.213308) (end 163.084053 119.275836) (width 0.1) (layer "B.Cu") (net 155))
  (segment (start 163.188725 118.256477) (end 163.170854 118.284918) (width 0.1) (layer "B.Cu") (net 155))
  (segment (start 163.556 118.35) (end 163.552239 118.316622) (width 0.1) (layer "B.Cu") (net 155))
  (segment (start 161.658578 118.8) (end 159.005 116.146422) (width 0.1) (layer "B.Cu") (net 155))
  (segment (start 159.005 116.146422) (end 159.005 116.035) (width 0.1) (layer "B.Cu") (net 155))
  (segment (start 153.39125 112.405) (end 153.135 112.66125) (width 0.1) (layer "B.Cu") (net 155))
  (segment (start 153.523578 112.405) (end 153.39125 112.405) (width 0.1) (layer "B.Cu") (net 155))
  (segment (start 162.685775 119.4) (end 162.612393 119.391731) (width 0.1) (layer "B.Cu") (net 155))
  (segment (start 163.240917 118.214855) (end 163.212476 118.232726) (width 0.1) (layer "B.Cu") (net 155))
  (segment (start 163.541145 118.284918) (end 163.523274 118.256477) (width 0.1) (layer "B.Cu") (net 155))
  (segment (start 162.612393 119.391731) (end 162.542691 119.367341) (width 0.1) (layer "B.Cu") (net 155))
  (segment (start 158.63212 115.888494) (end 158.589239 115.845613) (width 0.1) (layer "B.Cu") (net 155))
  (segment (start 165.478 119.0625) (end 165.2155 118.8) (width 0.1) (layer "B.Cu") (net 155))
  (segment (start 158.955509 115.956235) (end 158.937032 115.949769) (width 0.1) (layer "B.Cu") (net 155))
  (segment (start 158.800969 115.347578) (end 158.917578 115.347578) (width 0.1) (layer "B.Cu") (net 155))
  (segment (start 162.239378 118.80376) (end 162.206 118.8) (width 0.1) (layer "B.Cu") (net 155))
  (segment (start 158.536945 115.737025) (end 158.530155 115.676764) (width 0.1) (layer "B.Cu") (net 155))
  (segment (start 163.15976 118.316622) (end 163.156 118.35) (width 0.1) (layer "B.Cu") (net 155))
  (segment (start 158.972085 115.328505) (end 158.985928 115.314662) (width 0.1) (layer "B.Cu") (net 155))
  (segment (start 158.589239 115.449542) (end 158.63212 115.406661) (width 0.1) (layer "B.Cu") (net 155))
  (segment (start 163.306 118.2) (end 163.272621 118.203761) (width 0.1) (layer "B.Cu") (net 155))
  (segment (start 158.917578 115.947578) (end 158.800969 115.947578) (width 0.1) (layer "B.Cu") (net 155))
  (segment (start 162.341145 118.884917) (end 162.323274 118.856476) (width 0.1) (layer "B.Cu") (net 155))
  (segment (start 158.488578 114.31) (end 154.968578 114.31) (width 0.1) (layer "B.Cu") (net 155))
  (segment (start 162.299523 118.832725) (end 162.271082 118.814854) (width 0.1) (layer "B.Cu") (net 155))
  (segment (start 163.499523 118.232726) (end 163.471082 118.214855) (width 0.1) (layer "B.Cu") (net 155))
  (segment (start 163.742691 118.767342) (end 163.680163 118.728054) (width 0.1) (layer "B.Cu") (net 155))
  (segment (start 162.352239 118.916621) (end 162.341145 118.884917) (width 0.1) (layer "B.Cu") (net 155))
  (segment (start 163.439378 118.203761) (end 163.406 118.2) (width 0.1) (layer "B.Cu") (net 155))
  (segment (start 158.63212 115.406661) (end 158.683468 115.374396) (width 0.1) (layer "B.Cu") (net 155))
  (segment (start 163.812393 118.791732) (end 163.742691 118.767342) (width 0.1) (layer "B.Cu") (net 155))
  (segment (start 158.996343 115.298086) (end 159.002809 115.279609) (width 0.1) (layer "B.Cu") (net 155))
  (segment (start 163.156 118.35) (end 163.156 119.070224) (width 0.1) (layer "B.Cu") (net 155))
  (segment (start 163.147731 119.143606) (end 163.123341 119.213308) (width 0.1) (layer "B.Cu") (net 155))
  (segment (start 162.206 118.8) (end 161.658578 118.8) (width 0.1) (layer "B.Cu") (net 155))
  (segment (start 159.005 115.260156) (end 159.005 114.826422) (width 0.1) (layer "B.Cu") (net 155))
  (segment (start 158.996343 115.997069) (end 158.985928 115.980493) (width 0.1) (layer "B.Cu") (net 155))
  (segment (start 163.627946 118.675837) (end 163.588658 118.613309) (width 0.1) (layer "B.Cu") (net 155))
  (segment (start 163.170854 118.284918) (end 163.15976 118.316622) (width 0.1) (layer "B.Cu") (net 155))
  (segment (start 163.471082 118.214855) (end 163.439378 118.203761) (width 0.1) (layer "B.Cu") (net 155))
  (segment (start 158.589239 115.845613) (end 158.556974 115.794265) (width 0.1) (layer "B.Cu") (net 155))
  (segment (start 158.683468 115.374396) (end 158.740708 115.354367) (width 0.1) (layer "B.Cu") (net 155))
  (segment (start 163.885775 118.8) (end 163.812393 118.791732) (width 0.1) (layer "B.Cu") (net 155))
  (segment (start 162.427946 119.275836) (end 162.388658 119.213308) (width 0.1) (layer "B.Cu") (net 155))
  (segment (start 158.985928 115.980493) (end 158.972085 115.96665) (width 0.1) (layer "B.Cu") (net 155))
  (segment (start 159.005 114.826422) (end 158.488578 114.31) (width 0.1) (layer "B.Cu") (net 155))
  (segment (start 163.680163 118.728054) (end 163.627946 118.675837) (width 0.1) (layer "B.Cu") (net 155))
  (segment (start 158.683468 115.920759) (end 158.63212 115.888494) (width 0.1) (layer "B.Cu") (net 155))
  (segment (start 163.564268 118.543607) (end 163.556 118.470225) (width 0.1) (layer "B.Cu") (net 155))
  (segment (start 162.356 119.070224) (end 162.356 118.95) (width 0.1) (layer "B.Cu") (net 155))
  (segment (start 162.323274 118.856476) (end 162.299523 118.832725) (width 0.1) (layer "B.Cu") (net 155))
  (segment (start 158.955509 115.33892) (end 158.972085 115.328505) (width 0.1) (layer "B.Cu") (net 155))
  (segment (start 163.406 118.2) (end 163.306 118.2) (width 0.1) (layer "B.Cu") (net 155))
  (segment (start 163.552239 118.316622) (end 163.541145 118.284918) (width 0.1) (layer "B.Cu") (net 155))
  (segment (start 162.899606 119.391731) (end 162.826224 119.4) (width 0.1) (layer "B.Cu") (net 155))
  (segment (start 158.556974 115.50089) (end 158.589239 115.449542) (width 0.1) (layer "B.Cu") (net 155))
  (segment (start 159.002809 116.015546) (end 158.996343 115.997069) (width 0.1) (layer "B.Cu") (net 155))
  (segment (start 153.795 112.676422) (end 153.523578 112.405) (width 0.1) (layer "B.Cu") (net 155))
  (segment (start 158.972085 115.96665) (end 158.955509 115.956235) (width 0.1) (layer "B.Cu") (net 155))
  (segment (start 163.272621 118.203761) (end 163.240917 118.214855) (width 0.1) (layer "B.Cu") (net 155))
  (segment (start 162.356 118.95) (end 162.352239 118.916621) (width 0.1) (layer "B.Cu") (net 155))
  (segment (start 162.969308 119.367341) (end 162.899606 119.391731) (width 0.1) (layer "B.Cu") (net 155))
  (segment (start 162.388658 119.213308) (end 162.364268 119.143606) (width 0.1) (layer "B.Cu") (net 155))
  (segment (start 151.00875 112.2) (end 151.265 111.94375) (width 0.1) (layer "F.Cu") (net 156))
  (segment (start 148.07 112.74) (end 148.07 112.388578) (width 0.1) (layer "F.Cu") (net 156))
  (segment (start 147.845 112.965) (end 148.07 112.74) (width 0.1) (layer "F.Cu") (net 156))
  (segment (start 163.500001 118.45) (end 163.650001 118.6) (width 0.1) (layer "F.Cu") (net 156))
  (segment (start 148.07 112.388578) (end 148.258578 112.2) (width 0.1) (layer "F.Cu") (net 156))
  (segment (start 165.2155 118.6) (end 165.478 118.3375) (width 0.1) (layer "F.Cu") (net 156))
  (segment (start 162.6 118.45) (end 163.500001 118.45) (width 0.1) (layer "F.Cu") (net 156))
  (segment (start 148.258578 112.2) (end 151.00875 112.2) (width 0.1) (layer "F.Cu") (net 156))
  (segment (start 163.650001 118.6) (end 165.2155 118.6) (width 0.1) (layer "F.Cu") (net 156))
  (via (at 165.478 118.3375) (size 0.55) (drill 0.15) (layers "F.Cu" "B.Cu") (net 156))
  (via (at 151.265 111.94375) (size 0.55) (drill 0.15) (layers "F.Cu" "B.Cu") (net 156))
  (via (at 153.135 111.94875) (size 0.55) (drill 0.15) (layers "F.Cu" "B.Cu") (net 156))
  (segment (start 153.135 111.94875) (end 152.97125 112.1125) (width 0.15) (layer "In3.Cu") (net 156))
  (segment (start 152.97125 112.1125) (end 151.43375 112.1125) (width 0.15) (layer "In3.Cu") (net 156))
  (segment (start 151.43375 112.1125) (end 151.265 111.94375) (width 0.15) (layer "In3.Cu") (net 156))
  (segment (start 162.839378 119.196239) (end 162.806 119.2) (width 0.1) (layer "B.Cu") (net 156))
  (segment (start 158.798124 115.745386) (end 158.779647 115.73892) (width 0.1) (layer "B.Cu") (net 156))
  (segment (start 165.478 118.3375) (end 165.2155 118.6) (width 0.1) (layer "B.Cu") (net 156))
  (segment (start 162.956 118.329776) (end 162.956 119.05) (width 0.1) (layer "B.Cu") (net 156))
  (segment (start 162.640917 119.185145) (end 162.612476 119.167274) (width 0.1) (layer "B.Cu") (net 156))
  (segment (start 162.523341 118.786691) (end 162.484053 118.724163) (width 0.1) (layer "B.Cu") (net 156))
  (segment (start 159.178182 115.394265) (end 159.198211 115.337025) (width 0.1) (layer "B.Cu") (net 156))
  (segment (start 163.756 118.329776) (end 163.747731 118.256394) (width 0.1) (layer "B.Cu") (net 156))
  (segment (start 163.285775 118) (end 163.212393 118.008269) (width 0.1) (layer "B.Cu") (net 156))
  (segment (start 159.198211 115.95813) (end 159.178182 115.90089) (width 0.1) (layer "B.Cu") (net 156))
  (segment (start 162.299606 118.608268) (end 162.226224 118.6) (width 0.1) (layer "B.Cu") (net 156))
  (segment (start 162.899523 119.167274) (end 162.871082 119.185145) (width 0.1) (layer "B.Cu") (net 156))
  (segment (start 163.569308 118.032659) (end 163.499606 118.008269) (width 0.1) (layer "B.Cu") (net 156))
  (segment (start 158.934187 115.547578) (end 158.994448 115.540788) (width 0.1) (layer "B.Cu") (net 156))
  (segment (start 163.840917 118.585146) (end 163.812476 118.567275) (width 0.1) (layer "B.Cu") (net 156))
  (segment (start 162.871082 119.185145) (end 162.839378 119.196239) (width 0.1) (layer "B.Cu") (net 156))
  (segment (start 162.988658 118.186692) (end 162.964268 118.256394) (width 0.1) (layer "B.Cu") (net 156))
  (segment (start 158.571422 114.11) (end 155.051422 114.11) (width 0.1) (layer "B.Cu") (net 156))
  (segment (start 162.806 119.2) (end 162.706 119.2) (width 0.1) (layer "B.Cu") (net 156))
  (segment (start 163.212393 118.008269) (end 163.142691 118.032659) (width 0.1) (layer "B.Cu") (net 156))
  (segment (start 162.672621 119.196239) (end 162.640917 119.185145) (width 0.1) (layer "B.Cu") (net 156))
  (segment (start 163.499606 118.008269) (end 163.426224 118) (width 0.1) (layer "B.Cu") (net 156))
  (segment (start 162.547731 118.856393) (end 162.523341 118.786691) (width 0.1) (layer "B.Cu") (net 156))
  (segment (start 155.051422 114.11) (end 153.995 113.053578) (width 0.1) (layer "B.Cu") (net 156))
  (segment (start 163.872621 118.59624) (end 163.840917 118.585146) (width 0.1) (layer "B.Cu") (net 156))
  (segment (start 163.684053 118.124164) (end 163.631836 118.071947) (width 0.1) (layer "B.Cu") (net 156))
  (segment (start 163.080163 118.071947) (end 163.027946 118.124164) (width 0.1) (layer "B.Cu") (net 156))
  (segment (start 158.779647 115.73892) (end 158.763071 115.728505) (width 0.1) (layer "B.Cu") (net 156))
  (segment (start 158.763071 115.56665) (end 158.779647 115.556235) (width 0.1) (layer "B.Cu") (net 156))
  (segment (start 159.145917 115.849542) (end 159.103036 115.806661) (width 0.1) (layer "B.Cu") (net 156))
  (segment (start 158.763071 115.728505) (end 158.749228 115.714662) (width 0.1) (layer "B.Cu") (net 156))
  (segment (start 163.812476 118.567275) (end 163.788725 118.543524) (width 0.1) (layer "B.Cu") (net 156))
  (segment (start 163.027946 118.124164) (end 162.988658 118.186692) (width 0.1) (layer "B.Cu") (net 156))
  (segment (start 162.964268 118.256394) (end 162.956 118.329776) (width 0.1) (layer "B.Cu") (net 156))
  (segment (start 158.738813 115.698086) (end 158.732347 115.679609) (width 0.1) (layer "B.Cu") (net 156))
  (segment (start 159.051688 115.774396) (end 158.994448 115.754367) (width 0.1) (layer "B.Cu") (net 156))
  (segment (start 158.732347 115.615546) (end 158.738813 115.597069) (width 0.1) (layer "B.Cu") (net 156))
  (segment (start 159.103036 115.806661) (end 159.051688 115.774396) (width 0.1) (layer "B.Cu") (net 156))
  (segment (start 163.788725 118.543524) (end 163.770854 118.515083) (width 0.1) (layer "B.Cu") (net 156))
  (segment (start 163.426224 118) (end 163.285775 118) (width 0.1) (layer "B.Cu") (net 156))
  (segment (start 162.952239 119.083378) (end 162.941145 119.115082) (width 0.1) (layer "B.Cu") (net 156))
  (segment (start 159.205 116.063578) (end 159.205 116.018391) (width 0.1) (layer "B.Cu") (net 156))
  (segment (start 159.198211 115.337025) (end 159.205 115.276764) (width 0.1) (layer "B.Cu") (net 156))
  (segment (start 158.934187 115.747578) (end 158.817577 115.747578) (width 0.1) (layer "B.Cu") (net 156))
  (segment (start 158.749228 115.580493) (end 158.763071 115.56665) (width 0.1) (layer "B.Cu") (net 156))
  (segment (start 159.178182 115.90089) (end 159.145917 115.849542) (width 0.1) (layer "B.Cu") (net 156))
  (segment (start 158.779647 115.556235) (end 158.798124 115.549769) (width 0.1) (layer "B.Cu") (net 156))
  (segment (start 162.706 119.2) (end 162.672621 119.196239) (width 0.1) (layer "B.Cu") (net 156))
  (segment (start 153.995 113.053578) (end 153.995 112.593578) (width 0.1) (layer "B.Cu") (net 156))
  (segment (start 163.770854 118.515083) (end 163.75976 118.483379) (width 0.1) (layer "B.Cu") (net 156))
  (segment (start 162.556 118.929775) (end 162.547731 118.856393) (width 0.1) (layer "B.Cu") (net 156))
  (segment (start 153.39125 112.205) (end 153.135 111.94875) (width 0.1) (layer "B.Cu") (net 156))
  (segment (start 163.747731 118.256394) (end 163.723341 118.186692) (width 0.1) (layer "B.Cu") (net 156))
  (segment (start 162.612476 119.167274) (end 162.588725 119.143523) (width 0.1) (layer "B.Cu") (net 156))
  (segment (start 163.906 118.6) (end 163.872621 118.59624) (width 0.1) (layer "B.Cu") (net 156))
  (segment (start 153.606422 112.205) (end 153.39125 112.205) (width 0.1) (layer "B.Cu") (net 156))
  (segment (start 159.145917 115.445613) (end 159.178182 115.394265) (width 0.1) (layer "B.Cu") (net 156))
  (segment (start 162.923274 119.143523) (end 162.899523 119.167274) (width 0.1) (layer "B.Cu") (net 156))
  (segment (start 162.226224 118.6) (end 161.741422 118.6) (width 0.1) (layer "B.Cu") (net 156))
  (segment (start 162.556 119.05) (end 162.556 118.929775) (width 0.1) (layer "B.Cu") (net 156))
  (segment (start 162.484053 118.724163) (end 162.431836 118.671946) (width 0.1) (layer "B.Cu") (net 156))
  (segment (start 158.730155 115.635) (end 158.732347 115.615546) (width 0.1) (layer "B.Cu") (net 156))
  (segment (start 158.749228 115.714662) (end 158.738813 115.698086) (width 0.1) (layer "B.Cu") (net 156))
  (segment (start 158.817577 115.547578) (end 158.934187 115.547578) (width 0.1) (layer "B.Cu") (net 156))
  (segment (start 161.741422 118.6) (end 159.205 116.063578) (width 0.1) (layer "B.Cu") (net 156))
  (segment (start 158.730155 115.660156) (end 158.730155 115.635) (width 0.1) (layer "B.Cu") (net 156))
  (segment (start 159.205 114.743578) (end 158.571422 114.11) (width 0.1) (layer "B.Cu") (net 156))
  (segment (start 158.798124 115.549769) (end 158.817577 115.547578) (width 0.1) (layer "B.Cu") (net 156))
  (segment (start 159.205 115.276764) (end 159.205 114.743578) (width 0.1) (layer "B.Cu") (net 156))
  (segment (start 165.2155 118.6) (end 163.906 118.6) (width 0.1) (layer "B.Cu") (net 156))
  (segment (start 162.956 119.05) (end 162.952239 119.083378) (width 0.1) (layer "B.Cu") (net 156))
  (segment (start 159.051688 115.520759) (end 159.103036 115.488494) (width 0.1) (layer "B.Cu") (net 156))
  (segment (start 163.756 118.45) (end 163.756 118.329776) (width 0.1) (layer "B.Cu") (net 156))
  (segment (start 162.588725 119.143523) (end 162.570854 119.115082) (width 0.1) (layer "B.Cu") (net 156))
  (segment (start 163.142691 118.032659) (end 163.080163 118.071947) (width 0.1) (layer "B.Cu") (net 156))
  (segment (start 163.75976 118.483379) (end 163.756 118.45) (width 0.1) (layer "B.Cu") (net 156))
  (segment (start 162.55976 119.083378) (end 162.556 119.05) (width 0.1) (layer "B.Cu") (net 156))
  (segment (start 158.817577 115.747578) (end 158.798124 115.745386) (width 0.1) (layer "B.Cu") (net 156))
  (segment (start 162.369308 118.632658) (end 162.299606 118.608268) (width 0.1) (layer "B.Cu") (net 156))
  (segment (start 159.205 116.018391) (end 159.198211 115.95813) (width 0.1) (layer "B.Cu") (net 156))
  (segment (start 163.631836 118.071947) (end 163.569308 118.032659) (width 0.1) (layer "B.Cu") (net 156))
  (segment (start 162.431836 118.671946) (end 162.369308 118.632658) (width 0.1) (layer "B.Cu") (net 156))
  (segment (start 163.723341 118.186692) (end 163.684053 118.124164) (width 0.1) (layer "B.Cu") (net 156))
  (segment (start 162.941145 119.115082) (end 162.923274 119.143523) (width 0.1) (layer "B.Cu") (net 156))
  (segment (start 159.103036 115.488494) (end 159.145917 115.445613) (width 0.1) (layer "B.Cu") (net 156))
  (segment (start 158.738813 115.597069) (end 158.749228 115.580493) (width 0.1) (layer "B.Cu") (net 156))
  (segment (start 158.994448 115.754367) (end 158.934187 115.747578) (width 0.1) (layer "B.Cu") (net 156))
  (segment (start 162.570854 119.115082) (end 162.55976 119.083378) (width 0.1) (layer "B.Cu") (net 156))
  (segment (start 158.994448 115.540788) (end 159.051688 115.520759) (width 0.1) (layer "B.Cu") (net 156))
  (segment (start 158.732347 115.679609) (end 158.730155 115.660156) (width 0.1) (layer "B.Cu") (net 156))
  (segment (start 153.995 112.593578) (end 153.606422 112.205) (width 0.1) (layer "B.Cu") (net 156))
  (segment (start 152.046422 114.335) (end 152.256422 114.335) (width 0.1) (layer "F.Cu") (net 157))
  (segment (start 151.346422 114.588858) (end 151.348929 114.61111) (width 0.1) (layer "F.Cu") (net 157))
  (segment (start 151.50877 114.667041) (end 151.524605 114.651206) (width 0.1) (layer "F.Cu") (net 157))
  (segment (start 163.500001 117.95) (end 162.6 117.95) (width 0.1) (layer "F.Cu") (net 157))
  (segment (start 151.746422 114.588858) (end 151.748929 114.61111) (width 0.1) (layer "F.Cu") (net 157))
  (segment (start 151.48981 114.678954) (end 151.50877 114.667041) (width 0.1) (layer "F.Cu") (net 157))
  (segment (start 151.28981 114.344903) (end 151.30877 114.356816) (width 0.1) (layer "F.Cu") (net 157))
  (segment (start 151.968238 114.372651) (end 151.984073 114.356816) (width 0.1) (layer "F.Cu") (net 157))
  (segment (start 151.946422 114.588858) (end 151.946422 114.435) (width 0.1) (layer "F.Cu") (net 157))
  (segment (start 152.024169 114.337507) (end 152.046422 114.335) (width 0.1) (layer "F.Cu") (net 157))
  (segment (start 151.946422 114.435) (end 151.948929 114.412747) (width 0.1) (layer "F.Cu") (net 157))
  (segment (start 148.495 114.915) (end 149.5725 114.915) (width 0.1) (layer "F.Cu") (net 157))
  (segment (start 151.784073 114.667041) (end 151.803033 114.678954) (width 0.1) (layer "F.Cu") (net 157))
  (segment (start 151.803033 114.678954) (end 151.824169 114.68635) (width 0.1) (layer "F.Cu") (net 157))
  (segment (start 151.68981 114.344903) (end 151.70877 114.356816) (width 0.1) (layer "F.Cu") (net 157))
  (segment (start 151.943914 114.61111) (end 151.946422 114.588858) (width 0.1) (layer "F.Cu") (net 157))
  (segment (start 151.746422 114.435) (end 151.746422 114.588858) (width 0.1) (layer "F.Cu") (net 157))
  (segment (start 151.30877 114.356816) (end 151.324605 114.372651) (width 0.1) (layer "F.Cu") (net 157))
  (segment (start 151.324605 114.372651) (end 151.336518 114.391611) (width 0.1) (layer "F.Cu") (net 157))
  (segment (start 151.824169 114.68635) (end 151.846422 114.688858) (width 0.1) (layer "F.Cu") (net 157))
  (segment (start 151.748929 114.61111) (end 151.756325 114.632246) (width 0.1) (layer "F.Cu") (net 157))
  (segment (start 151.336518 114.391611) (end 151.343914 114.412747) (width 0.1) (layer "F.Cu") (net 157))
  (segment (start 151.546422 114.435) (end 151.548929 114.412747) (width 0.1) (layer "F.Cu") (net 157))
  (segment (start 163.650001 117.8) (end 165.8975 117.8) (width 0.1) (layer "F.Cu") (net 157))
  (segment (start 151.846422 114.688858) (end 151.868674 114.68635) (width 0.1) (layer "F.Cu") (net 157))
  (segment (start 151.346422 114.435) (end 151.346422 114.588858) (width 0.1) (layer "F.Cu") (net 157))
  (segment (start 149.635 114.8525) (end 150.728922 114.8525) (width 0.1) (layer "F.Cu") (net 157))
  (segment (start 151.356325 114.632246) (end 151.368238 114.651206) (width 0.1) (layer "F.Cu") (net 157))
  (segment (start 151.768238 114.651206) (end 151.784073 114.667041) (width 0.1) (layer "F.Cu") (net 157))
  (segment (start 151.956325 114.391611) (end 151.968238 114.372651) (width 0.1) (layer "F.Cu") (net 157))
  (segment (start 152.256422 114.335) (end 152.614515 113.976907) (width 0.1) (layer "F.Cu") (net 157))
  (segment (start 151.743914 114.412747) (end 151.746422 114.435) (width 0.1) (layer "F.Cu") (net 157))
  (segment (start 151.90877 114.667041) (end 151.924605 114.651206) (width 0.1) (layer "F.Cu") (net 157))
  (segment (start 151.584073 114.356816) (end 151.603033 114.344903) (width 0.1) (layer "F.Cu") (net 157))
  (segment (start 151.936518 114.632246) (end 151.943914 114.61111) (width 0.1) (layer "F.Cu") (net 157))
  (segment (start 151.384073 114.667041) (end 151.403033 114.678954) (width 0.1) (layer "F.Cu") (net 157))
  (segment (start 151.724605 114.372651) (end 151.736518 114.391611) (width 0.1) (layer "F.Cu") (net 157))
  (segment (start 151.543914 114.61111) (end 151.546422 114.588858) (width 0.1) (layer "F.Cu") (net 157))
  (segment (start 151.468674 114.68635) (end 151.48981 114.678954) (width 0.1) (layer "F.Cu") (net 157))
  (segment (start 151.268674 114.337507) (end 151.28981 114.344903) (width 0.1) (layer "F.Cu") (net 157))
  (segment (start 151.70877 114.356816) (end 151.724605 114.372651) (width 0.1) (layer "F.Cu") (net 157))
  (segment (start 151.736518 114.391611) (end 151.743914 114.412747) (width 0.1) (layer "F.Cu") (net 157))
  (segment (start 151.668674 114.337507) (end 151.68981 114.344903) (width 0.1) (layer "F.Cu") (net 157))
  (segment (start 149.5725 114.915) (end 149.635 114.8525) (width 0.1) (layer "F.Cu") (net 157))
  (segment (start 151.756325 114.632246) (end 151.768238 114.651206) (width 0.1) (layer "F.Cu") (net 157))
  (segment (start 152.003033 114.344903) (end 152.024169 114.337507) (width 0.1) (layer "F.Cu") (net 157))
  (segment (start 151.524605 114.651206) (end 151.536518 114.632246) (width 0.1) (layer "F.Cu") (net 157))
  (segment (start 151.246422 114.335) (end 151.268674 114.337507) (width 0.1) (layer "F.Cu") (net 157))
  (segment (start 151.343914 114.412747) (end 151.346422 114.435) (width 0.1) (layer "F.Cu") (net 157))
  (segment (start 151.646422 114.335) (end 151.668674 114.337507) (width 0.1) (layer "F.Cu") (net 157))
  (segment (start 151.368238 114.651206) (end 151.384073 114.667041) (width 0.1) (layer "F.Cu") (net 157))
  (segment (start 151.984073 114.356816) (end 152.003033 114.344903) (width 0.1) (layer "F.Cu") (net 157))
  (segment (start 151.424169 114.68635) (end 151.446422 114.688858) (width 0.1) (layer "F.Cu") (net 157))
  (segment (start 165.8975 117.8) (end 166.16 118.0625) (width 0.1) (layer "F.Cu") (net 157))
  (segment (start 151.348929 114.61111) (end 151.356325 114.632246) (width 0.1) (layer "F.Cu") (net 157))
  (segment (start 151.88981 114.678954) (end 151.90877 114.667041) (width 0.1) (layer "F.Cu") (net 157))
  (segment (start 151.556325 114.391611) (end 151.568238 114.372651) (width 0.1) (layer "F.Cu") (net 157))
  (segment (start 151.536518 114.632246) (end 151.543914 114.61111) (width 0.1) (layer "F.Cu") (net 157))
  (segment (start 151.624169 114.337507) (end 151.646422 114.335) (width 0.1) (layer "F.Cu") (net 157))
  (segment (start 151.446422 114.688858) (end 151.468674 114.68635) (width 0.1) (layer "F.Cu") (net 157))
  (segment (start 151.548929 114.412747) (end 151.556325 114.391611) (width 0.1) (layer "F.Cu") (net 157))
  (segment (start 151.924605 114.651206) (end 151.936518 114.632246) (width 0.1) (layer "F.Cu") (net 157))
  (segment (start 151.868674 114.68635) (end 151.88981 114.678954) (width 0.1) (layer "F.Cu") (net 157))
  (segment (start 163.650001 117.8) (end 163.500001 117.95) (width 0.1) (layer "F.Cu") (net 157))
  (segment (start 152.614515 113.976907) (end 152.976907 113.976907) (width 0.1) (layer "F.Cu") (net 157))
  (segment (start 151.546422 114.588858) (end 151.546422 114.435) (width 0.1) (layer "F.Cu") (net 157))
  (segment (start 151.603033 114.344903) (end 151.624169 114.337507) (width 0.1) (layer "F.Cu") (net 157))
  (segment (start 151.948929 114.412747) (end 151.956325 114.391611) (width 0.1) (layer "F.Cu") (net 157))
  (segment (start 151.403033 114.678954) (end 151.424169 114.68635) (width 0.1) (layer "F.Cu") (net 157))
  (segment (start 150.728922 114.8525) (end 151.246422 114.335) (width 0.1) (layer "F.Cu") (net 157))
  (segment (start 151.568238 114.372651) (end 151.584073 114.356816) (width 0.1) (layer "F.Cu") (net 157))
  (via (at 155.695 112.56625) (size 0.55) (drill 0.15) (layers "F.Cu" "B.Cu") (net 157))
  (via (at 152.976907 113.976907) (size 0.55) (drill 0.15) (layers "F.Cu" "B.Cu") (net 157))
  (via (at 166.16 118.0625) (size 0.55) (drill 0.15) (layers "F.Cu" "B.Cu") (net 157))
  (segment (start 153.105721 113.848093) (end 152.976907 113.976907) (width 0.15) (layer "In3.Cu") (net 157))
  (segment (start 155.52625 112.3975) (end 154.427666 112.3975) (width 0.15) (layer "In3.Cu") (net 157))
  (segment (start 154.1425 112.682666) (end 154.1425 113.362666) (width 0.15) (layer "In3.Cu") (net 157))
  (segment (start 155.695 112.56625) (end 155.52625 112.3975) (width 0.15) (layer "In3.Cu") (net 157))
  (segment (start 154.1425 113.362666) (end 153.657073 113.848093) (width 0.15) (layer "In3.Cu") (net 157))
  (segment (start 154.427666 112.3975) (end 154.1425 112.682666) (width 0.15) (layer "In3.Cu") (net 157))
  (segment (start 153.657073 113.848093) (end 153.105721 113.848093) (width 0.15) (layer "In3.Cu") (net 157))
  (segment (start 155.95125 112.31) (end 155.695 112.56625) (width 0.1) (layer "B.Cu") (net 157))
  (segment (start 166.16 118.0625) (end 165.8975 117.8) (width 0.1) (layer "B.Cu") (net 157))
  (segment (start 159.655 115.946422) (end 159.655 113.066422) (width 0.1) (layer "B.Cu") (net 157))
  (segment (start 158.898578 112.31) (end 155.95125 112.31) (width 0.1) (layer "B.Cu") (net 157))
  (segment (start 165.8975 117.8) (end 161.508578 117.8) (width 0.1) (layer "B.Cu") (net 157))
  (segment (start 159.655 113.066422) (end 158.898578 112.31) (width 0.1) (layer "B.Cu") (net 157))
  (segment (start 161.508578 117.8) (end 159.655 115.946422) (width 0.1) (layer "B.Cu") (net 157))
  (segment (start 149.5725 114.59) (end 149.635 114.6525) (width 0.1) (layer "F.Cu") (net 158))
  (segment (start 148.17 114.59) (end 149.5725 114.59) (width 0.1) (layer "F.Cu") (net 158))
  (segment (start 152.173578 114.135) (end 152.473093 113.835485) (width 0.1) (layer "F.Cu") (net 158))
  (segment (start 163.650001 117.6) (end 165.8975 117.6) (width 0.1) (layer "F.Cu") (net 158))
  (segment (start 151.163578 114.135) (end 152.173578 114.135) (width 0.1) (layer "F.Cu") (net 158))
  (segment (start 163.650001 117.6) (end 163.500001 117.45) (width 0.1) (layer "F.Cu") (net 158))
  (segment (start 150.646078 114.6525) (end 151.163578 114.135) (width 0.1) (layer "F.Cu") (net 158))
  (segment (start 165.8975 117.6) (end 166.16 117.3375) (width 0.1) (layer "F.Cu") (net 158))
  (segment (start 152.473093 113.835485) (end 152.473093 113.473093) (width 0.1) (layer "F.Cu") (net 158))
  (segment (start 149.635 114.6525) (end 150.646078 114.6525) (width 0.1) (layer "F.Cu") (net 158))
  (segment (start 163.500001 117.45) (end 162.6 117.45) (width 0.1) (layer "F.Cu") (net 158))
  (segment (start 147.845 114.915) (end 148.17 114.59) (width 0.1) (layer "F.Cu") (net 158))
  (via (at 152.473093 113.473093) (size 0.55) (drill 0.15) (layers "F.Cu" "B.Cu") (net 158))
  (via (at 166.16 117.3375) (size 0.55) (drill 0.15) (layers "F.Cu" "B.Cu") (net 158))
  (via (at 155.695 111.85375) (size 0.55) (drill 0.15) (layers "F.Cu" "B.Cu") (net 158))
  (segment (start 154.272334 112.0225) (end 153.7675 112.527334) (width 0.15) (layer "In3.Cu") (net 158))
  (segment (start 153.7675 113.207334) (end 153.501741 113.473093) (width 0.15) (layer "In3.Cu") (net 158))
  (segment (start 153.7675 112.527334) (end 153.7675 113.207334) (width 0.15) (layer "In3.Cu") (net 158))
  (segment (start 155.52625 112.0225) (end 154.272334 112.0225) (width 0.15) (layer "In3.Cu") (net 158))
  (segment (start 155.695 111.85375) (end 155.52625 112.0225) (width 0.15) (layer "In3.Cu") (net 158))
  (segment (start 152.473093 113.473093) (end 153.501741 113.473093) (width 0.15) (layer "In3.Cu") (net 158))
  (segment (start 165.8975 117.6) (end 161.591422 117.6) (width 0.1) (layer "B.Cu") (net 158))
  (segment (start 159.855 115.863578) (end 159.855 112.983578) (width 0.1) (layer "B.Cu") (net 158))
  (segment (start 159.855 112.983578) (end 158.981422 112.11) (width 0.1) (layer "B.Cu") (net 158))
  (segment (start 155.95125 112.11) (end 155.695 111.85375) (width 0.1) (layer "B.Cu") (net 158))
  (segment (start 161.591422 117.6) (end 159.855 115.863578) (width 0.1) (layer "B.Cu") (net 158))
  (segment (start 166.16 117.3375) (end 165.8975 117.6) (width 0.1) (layer "B.Cu") (net 158))
  (segment (start 158.981422 112.11) (end 155.95125 112.11) (width 0.1) (layer "B.Cu") (net 158))
  (segment (start 152.466295 112.824903) (end 152.445159 112.817507) (width 0.1) (layer "F.Cu") (net 159))
  (segment (start 152.485255 112.993183) (end 152.50109 112.977348) (width 0.1) (layer "F.Cu") (net 159))
  (segment (start 152.513003 112.871611) (end 152.50109 112.852651) (width 0.1) (layer "F.Cu") (net 159))
  (segment (start 152.002747 113.017507) (end 152.025 113.015) (width 0.1) (layer "F.Cu") (net 159))
  (segment (start 151.927507 112.737252) (end 151.925 112.715) (width 0.1) (layer "F.Cu") (net 159))
  (segment (start 152.025 112.815) (end 152.002747 112.812492) (width 0.1) (layer "F.Cu") (net 159))
  (segment (start 151.946816 112.777348) (end 151.934903 112.758388) (width 0.1) (layer "F.Cu") (net 159))
  (segment (start 163.650001 116.8) (end 163.500001 116.95) (width 0.1) (layer "F.Cu") (net 159))
  (segment (start 151.925 112.715) (end 151.925 111.34125) (width 0.1) (layer "F.Cu") (net 159))
  (segment (start 151.073578 113.775) (end 151.646422 113.775) (width 0.1) (layer "F.Cu") (net 159))
  (segment (start 151.925 111.34125) (end 152.18125 111.085) (width 0.1) (layer "F.Cu") (net 159))
  (segment (start 152.520399 112.892747) (end 152.513003 112.871611) (width 0.1) (layer "F.Cu") (net 159))
  (segment (start 152.520399 112.937252) (end 152.522907 112.915) (width 0.1) (layer "F.Cu") (net 159))
  (segment (start 151.934903 112.758388) (end 151.927507 112.737252) (width 0.1) (layer "F.Cu") (net 159))
  (segment (start 151.981611 113.024903) (end 152.002747 113.017507) (width 0.1) (layer "F.Cu") (net 159))
  (segment (start 152.002747 112.812492) (end 151.981611 112.805096) (width 0.1) (layer "F.Cu") (net 159))
  (segment (start 151.962651 112.793183) (end 151.946816 112.777348) (width 0.1) (layer "F.Cu") (net 159))
  (segment (start 151.934903 113.071611) (end 151.946816 113.052651) (width 0.1) (layer "F.Cu") (net 159))
  (segment (start 152.50109 112.977348) (end 152.513003 112.958388) (width 0.1) (layer "F.Cu") (net 159))
  (segment (start 148.495 113.615) (end 148.976422 113.615) (width 0.1) (layer "F.Cu") (net 159))
  (segment (start 163.500001 116.95) (end 162.6 116.95) (width 0.1) (layer "F.Cu") (net 159))
  (segment (start 152.50109 112.852651) (end 152.485255 112.836816) (width 0.1) (layer "F.Cu") (net 159))
  (segment (start 163.650001 116.8) (end 164.2075 116.8) (width 0.1) (layer "F.Cu") (net 159))
  (segment (start 152.522907 112.915) (end 152.520399 112.892747) (width 0.1) (layer "F.Cu") (net 159))
  (segment (start 151.981611 112.805096) (end 151.962651 112.793183) (width 0.1) (layer "F.Cu") (net 159))
  (segment (start 152.422907 113.015) (end 152.445159 113.012492) (width 0.1) (layer "F.Cu") (net 159))
  (segment (start 151.925 113.496422) (end 151.925 113.115) (width 0.1) (layer "F.Cu") (net 159))
  (segment (start 151.925 113.115) (end 151.927507 113.092747) (width 0.1) (layer "F.Cu") (net 159))
  (segment (start 150.293578 112.995) (end 151.073578 113.775) (width 0.1) (layer "F.Cu") (net 159))
  (segment (start 152.422907 112.815) (end 152.025 112.815) (width 0.1) (layer "F.Cu") (net 159))
  (segment (start 152.445159 112.817507) (end 152.422907 112.815) (width 0.1) (layer "F.Cu") (net 159))
  (segment (start 151.962651 113.036816) (end 151.981611 113.024903) (width 0.1) (layer "F.Cu") (net 159))
  (segment (start 164.2075 116.8) (end 164.47 117.0625) (width 0.1) (layer "F.Cu") (net 159))
  (segment (start 151.646422 113.775) (end 151.925 113.496422) (width 0.1) (layer "F.Cu") (net 159))
  (segment (start 152.466295 113.005096) (end 152.485255 112.993183) (width 0.1) (layer "F.Cu") (net 159))
  (segment (start 151.927507 113.092747) (end 151.934903 113.071611) (width 0.1) (layer "F.Cu") (net 159))
  (segment (start 149.596422 112.995) (end 150.293578 112.995) (width 0.1) (layer "F.Cu") (net 159))
  (segment (start 152.025 113.015) (end 152.422907 113.015) (width 0.1) (layer "F.Cu") (net 159))
  (segment (start 148.976422 113.615) (end 149.596422 112.995) (width 0.1) (layer "F.Cu") (net 159))
  (segment (start 152.445159 113.012492) (end 152.466295 113.005096) (width 0.1) (layer "F.Cu") (net 159))
  (segment (start 152.513003 112.958388) (end 152.520399 112.937252) (width 0.1) (layer "F.Cu") (net 159))
  (segment (start 152.485255 112.836816) (end 152.466295 112.824903) (width 0.1) (layer "F.Cu") (net 159))
  (segment (start 151.946816 113.052651) (end 151.962651 113.036816) (width 0.1) (layer "F.Cu") (net 159))
  (via (at 152.18125 111.085) (size 0.55) (drill 0.15) (layers "F.Cu" "B.Cu") (net 159))
  (via (at 164.47 117.0625) (size 0.55) (drill 0.15) (layers "F.Cu" "B.Cu") (net 159))
  (via (at 155.655 110.56625) (size 0.55) (drill 0.15) (layers "F.Cu" "B.Cu") (net 159))
  (segment (start 152.0125 110.91625) (end 152.18125 111.085) (width 0.15) (layer "In3.Cu") (net 159))
  (segment (start 155.655 110.56625) (end 155.48625 110.3975) (width 0.15) (layer "In3.Cu") (net 159))
  (segment (start 152.247666 110.3975) (end 152.0125 110.632666) (width 0.15) (layer "In3.Cu") (net 159))
  (segment (start 152.0125 110.632666) (end 152.0125 110.91625) (width 0.15) (layer "In3.Cu") (net 159))
  (segment (start 155.48625 110.3975) (end 152.247666 110.3975) (width 0.15) (layer "In3.Cu") (net 159))
  (segment (start 164.2075 116.8) (end 161.288578 116.8) (width 0.1) (layer "B.Cu") (net 159))
  (segment (start 160.245 115.756422) (end 160.245 111.766422) (width 0.1) (layer "B.Cu") (net 159))
  (segment (start 158.788578 110.31) (end 155.91125 110.31) (width 0.1) (layer "B.Cu") (net 159))
  (segment (start 160.245 111.766422) (end 158.788578 110.31) (width 0.1) (layer "B.Cu") (net 159))
  (segment (start 155.91125 110.31) (end 155.655 110.56625) (width 0.1) (layer "B.Cu") (net 159))
  (segment (start 161.288578 116.8) (end 160.245 115.756422) (width 0.1) (layer "B.Cu") (net 159))
  (segment (start 164.47 117.0625) (end 164.2075 116.8) (width 0.1) (layer "B.Cu") (net 159))
  (segment (start 151.563578 113.575) (end 151.725 113.413578) (width 0.1) (layer "F.Cu") (net 160))
  (segment (start 163.500001 116.45) (end 162.6 116.45) (width 0.1) (layer "F.Cu") (net 160))
  (segment (start 151.725 111.34125) (end 151.46875 111.085) (width 0.1) (layer "F.Cu") (net 160))
  (segment (start 164.2075 116.6) (end 164.47 116.3375) (width 0.1) (layer "F.Cu") (net 160))
  (segment (start 163.650001 116.6) (end 164.2075 116.6) (width 0.1) (layer "F.Cu") (net 160))
  (segment (start 151.725 113.413578) (end 151.725 111.34125) (width 0.1) (layer "F.Cu") (net 160))
  (segment (start 150.376422 112.795) (end 151.156422 113.575) (width 0.1) (layer "F.Cu") (net 160))
  (segment (start 147.845 113.615) (end 148.17 113.29) (width 0.1) (layer "F.Cu") (net 160))
  (segment (start 163.650001 116.6) (end 163.500001 116.45) (width 0.1) (layer "F.Cu") (net 160))
  (segment (start 149.513578 112.795) (end 150.376422 112.795) (width 0.1) (layer "F.Cu") (net 160))
  (segment (start 148.17 113.29) (end 149.018578 113.29) (width 0.1) (layer "F.Cu") (net 160))
  (segment (start 151.156422 113.575) (end 151.563578 113.575) (width 0.1) (layer "F.Cu") (net 160))
  (segment (start 149.018578 113.29) (end 149.513578 112.795) (width 0.1) (layer "F.Cu") (net 160))
  (via (at 164.47 116.3375) (size 0.55) (drill 0.15) (layers "F.Cu" "B.Cu") (net 160))
  (via (at 151.46875 111.085) (size 0.55) (drill 0.15) (layers "F.Cu" "B.Cu") (net 160))
  (via (at 155.655 109.85375) (size 0.55) (drill 0.15) (layers "F.Cu" "B.Cu") (net 160))
  (segment (start 155.655 109.85375) (end 155.48625 110.0225) (width 0.15) (layer "In3.Cu") (net 160))
  (segment (start 151.6375 110.91625) (end 151.46875 111.085) (width 0.15) (layer "In3.Cu") (net 160))
  (segment (start 151.6375 110.477334) (end 151.6375 110.91625) (width 0.15) (layer "In3.Cu") (net 160))
  (segment (start 155.48625 110.0225) (end 152.092334 110.0225) (width 0.15) (layer "In3.Cu") (net 160))
  (segment (start 152.092334 110.0225) (end 151.6375 110.477334) (width 0.15) (layer "In3.Cu") (net 160))
  (segment (start 164.2075 116.6) (end 161.371422 116.6) (width 0.1) (layer "B.Cu") (net 160))
  (segment (start 164.47 116.3375) (end 164.2075 116.6) (width 0.1) (layer "B.Cu") (net 160))
  (segment (start 161.371422 116.6) (end 160.445 115.673578) (width 0.1) (layer "B.Cu") (net 160))
  (segment (start 160.445 111.683578) (end 158.871422 110.11) (width 0.1) (layer "B.Cu") (net 160))
  (segment (start 158.871422 110.11) (end 155.91125 110.11) (width 0.1) (layer "B.Cu") (net 160))
  (segment (start 160.445 115.673578) (end 160.445 111.683578) (width 0.1) (layer "B.Cu") (net 160))
  (segment (start 155.91125 110.11) (end 155.655 109.85375) (width 0.1) (layer "B.Cu") (net 160))
  (segment (start 149.241373 114.193305) (end 149.237675 114.203873) (width 0.1) (layer "F.Cu") (net 161))
  (segment (start 148.855247 114.175908) (end 148.84733 114.183825) (width 0.1) (layer "F.Cu") (net 161))
  (segment (start 149.84733 114.246174) (end 149.841373 114.236694) (width 0.1) (layer "F.Cu") (net 161))
  (segment (start 163.650001 115.3) (end 163.7875 115.3) (width 0.1) (layer "F.Cu") (net 161))
  (segment (start 149.43147 114.193305) (end 149.425513 114.183825) (width 0.1) (layer "F.Cu") (net 161))
  (segment (start 149.036422 114.215) (end 149.035168 114.203873) (width 0.1) (layer "F.Cu") (net 161))
  (segment (start 149.841373 114.236694) (end 149.837675 114.226126) (width 0.1) (layer "F.Cu") (net 161))
  (segment (start 149.086422 114.365) (end 149.075295 114.363747) (width 0.1) (layer "F.Cu") (net 161))
  (segment (start 149.275295 114.166253) (end 149.264727 114.169951) (width 0.1) (layer "F.Cu") (net 161))
  (segment (start 149.235168 114.326127) (end 149.23147 114.336695) (width 0.1) (layer "F.Cu") (net 161))
  (segment (start 148.841373 114.193305) (end 148.837675 114.203873) (width 0.1) (layer "F.Cu") (net 161))
  (segment (start 149.808116 114.169951) (end 149.797548 114.166253) (width 0.1) (layer "F.Cu") (net 161))
  (segment (start 149.486422 114.365) (end 149.475295 114.363747) (width 0.1) (layer "F.Cu") (net 161))
  (segment (start 149.655247 114.175908) (end 149.64733 114.183825) (width 0.1) (layer "F.Cu") (net 161))
  (segment (start 149.208116 114.360049) (end 149.197548 114.363747) (width 0.1) (layer "F.Cu") (net 161))
  (segment (start 149.03147 114.193305) (end 149.025513 114.183825) (width 0.1) (layer "F.Cu") (net 161))
  (segment (start 149.635168 114.326127) (end 149.63147 114.336695) (width 0.1) (layer "F.Cu") (net 161))
  (segment (start 149.864727 114.260048) (end 149.855247 114.254091) (width 0.1) (layer "F.Cu") (net 161))
  (segment (start 149.455247 114.354092) (end 149.44733 114.346175) (width 0.1) (layer "F.Cu") (net 161))
  (segment (start 149.44733 114.346175) (end 149.441373 114.336695) (width 0.1) (layer "F.Cu") (net 161))
  (segment (start 149.436422 114.215) (end 149.435168 114.203873) (width 0.1) (layer "F.Cu") (net 161))
  (segment (start 149.23147 114.336695) (end 149.225513 114.346175) (width 0.1) (layer "F.Cu") (net 161))
  (segment (start 149.186422 114.365) (end 149.086422 114.365) (width 0.1) (layer "F.Cu") (net 161))
  (segment (start 149.008116 114.169951) (end 148.997548 114.166253) (width 0.1) (layer "F.Cu") (net 161))
  (segment (start 149.63147 114.336695) (end 149.625513 114.346175) (width 0.1) (layer "F.Cu") (net 161))
  (segment (start 148.797548 114.263746) (end 148.786422 114.265) (width 0.1) (layer "F.Cu") (net 161))
  (segment (start 149.835168 114.203873) (end 149.83147 114.193305) (width 0.1) (layer "F.Cu") (net 161))
  (segment (start 149.217596 114.354092) (end 149.208116 114.360049) (width 0.1) (layer "F.Cu") (net 161))
  (segment (start 149.875295 114.263746) (end 149.864727 114.260048) (width 0.1) (layer "F.Cu") (net 161))
  (segment (start 149.855247 114.254091) (end 149.84733 114.246174) (width 0.1) (layer "F.Cu") (net 161))
  (segment (start 149.417596 114.175908) (end 149.408116 114.169951) (width 0.1) (layer "F.Cu") (net 161))
  (segment (start 149.197548 114.363747) (end 149.186422 114.365) (width 0.1) (layer "F.Cu") (net 161))
  (segment (start 149.436422 114.315) (end 149.436422 114.215) (width 0.1) (layer "F.Cu") (net 161))
  (segment (start 149.035168 114.203873) (end 149.03147 114.193305) (width 0.1) (layer "F.Cu") (net 161))
  (segment (start 149.786422 114.165) (end 149.686422 114.165) (width 0.1) (layer "F.Cu") (net 161))
  (segment (start 148.786422 114.265) (end 148.499525 114.265) (width 0.1) (layer "F.Cu") (net 161))
  (segment (start 149.597548 114.363747) (end 149.586422 114.365) (width 0.1) (layer "F.Cu") (net 161))
  (segment (start 148.886422 114.165) (end 148.875295 114.166253) (width 0.1) (layer "F.Cu") (net 161))
  (segment (start 149.055247 114.354092) (end 149.04733 114.346175) (width 0.1) (layer "F.Cu") (net 161))
  (segment (start 148.817596 114.254091) (end 148.808116 114.260048) (width 0.1) (layer "F.Cu") (net 161))
  (segment (start 149.617596 114.354092) (end 149.608116 114.360049) (width 0.1) (layer "F.Cu") (net 161))
  (segment (start 149.625513 114.346175) (end 149.617596 114.354092) (width 0.1) (layer "F.Cu") (net 161))
  (segment (start 149.286422 114.165) (end 149.275295 114.166253) (width 0.1) (layer "F.Cu") (net 161))
  (segment (start 148.83147 114.236694) (end 148.825513 114.246174) (width 0.1) (layer "F.Cu") (net 161))
  (segment (start 149.825513 114.183825) (end 149.817596 114.175908) (width 0.1) (layer "F.Cu") (net 161))
  (segment (start 149.255247 114.175908) (end 149.24733 114.183825) (width 0.1) (layer "F.Cu") (net 161))
  (segment (start 149.797548 114.166253) (end 149.786422 114.165) (width 0.1) (layer "F.Cu") (net 161))
  (segment (start 149.686422 114.165) (end 149.675295 114.166253) (width 0.1) (layer "F.Cu") (net 161))
  (segment (start 149.025513 114.183825) (end 149.017596 114.175908) (width 0.1) (layer "F.Cu") (net 161))
  (segment (start 149.675295 114.166253) (end 149.664727 114.169951) (width 0.1) (layer "F.Cu") (net 161))
  (segment (start 149.608116 114.360049) (end 149.597548 114.363747) (width 0.1) (layer "F.Cu") (net 161))
  (segment (start 148.997548 114.166253) (end 148.986422 114.165) (width 0.1) (layer "F.Cu") (net 161))
  (segment (start 149.064727 114.360049) (end 149.055247 114.354092) (width 0.1) (layer "F.Cu") (net 161))
  (segment (start 149.83147 114.193305) (end 149.825513 114.183825) (width 0.1) (layer "F.Cu") (net 161))
  (segment (start 149.437675 114.326127) (end 149.436422 114.315) (width 0.1) (layer "F.Cu") (net 161))
  (segment (start 148.825513 114.246174) (end 148.817596 114.254091) (width 0.1) (layer "F.Cu") (net 161))
  (segment (start 148.986422 114.165) (end 148.886422 114.165) (width 0.1) (layer "F.Cu") (net 161))
  (segment (start 149.236422 114.315) (end 149.235168 114.326127) (width 0.1) (layer "F.Cu") (net 161))
  (segment (start 163.500001 115.45) (end 163.650001 115.3) (width 0.1) (layer "F.Cu") (net 161))
  (segment (start 149.637675 114.203873) (end 149.636422 114.215) (width 0.1) (layer "F.Cu") (net 161))
  (segment (start 149.886422 114.265) (end 149.875295 114.263746) (width 0.1) (layer "F.Cu") (net 161))
  (segment (start 149.264727 114.169951) (end 149.255247 114.175908) (width 0.1) (layer "F.Cu") (net 161))
  (segment (start 148.864727 114.169951) (end 148.855247 114.175908) (width 0.1) (layer "F.Cu") (net 161))
  (segment (start 149.386422 114.165) (end 149.286422 114.165) (width 0.1) (layer "F.Cu") (net 161))
  (segment (start 149.464727 114.360049) (end 149.455247 114.354092) (width 0.1) (layer "F.Cu") (net 161))
  (segment (start 149.225513 114.346175) (end 149.217596 114.354092) (width 0.1) (layer "F.Cu") (net 161))
  (segment (start 149.425513 114.183825) (end 149.417596 114.175908) (width 0.1) (layer "F.Cu") (net 161))
  (segment (start 163.7875 115.3) (end 164.05 115.5625) (width 0.1) (layer "F.Cu") (net 161))
  (segment (start 148.499525 114.265) (end 148.495 114.265) (width 0.1) (layer "F.Cu") (net 161))
  (segment (start 149.475295 114.363747) (end 149.464727 114.360049) (width 0.1) (layer "F.Cu") (net 161))
  (segment (start 148.808116 114.260048) (end 148.797548 114.263746) (width 0.1) (layer "F.Cu") (net 161))
  (segment (start 149.397548 114.166253) (end 149.386422 114.165) (width 0.1) (layer "F.Cu") (net 161))
  (segment (start 149.037675 114.326127) (end 149.036422 114.315) (width 0.1) (layer "F.Cu") (net 161))
  (segment (start 148.837675 114.203873) (end 148.835168 114.226126) (width 0.1) (layer "F.Cu") (net 161))
  (segment (start 149.435168 114.203873) (end 149.43147 114.193305) (width 0.1) (layer "F.Cu") (net 161))
  (segment (start 149.075295 114.363747) (end 149.064727 114.360049) (width 0.1) (layer "F.Cu") (net 161))
  (segment (start 149.408116 114.169951) (end 149.397548 114.166253) (width 0.1) (layer "F.Cu") (net 161))
  (segment (start 149.017596 114.175908) (end 149.008116 114.169951) (width 0.1) (layer "F.Cu") (net 161))
  (segment (start 149.24733 114.183825) (end 149.241373 114.193305) (width 0.1) (layer "F.Cu") (net 161))
  (segment (start 148.875295 114.166253) (end 148.864727 114.169951) (width 0.1) (layer "F.Cu") (net 161))
  (segment (start 148.84733 114.183825) (end 148.841373 114.193305) (width 0.1) (layer "F.Cu") (net 161))
  (segment (start 149.586422 114.365) (end 149.486422 114.365) (width 0.1) (layer "F.Cu") (net 161))
  (segment (start 150.114515 114.036907) (end 149.886422 114.265) (width 0.1) (layer "F.Cu") (net 161))
  (segment (start 149.817596 114.175908) (end 149.808116 114.169951) (width 0.1) (layer "F.Cu") (net 161))
  (segment (start 149.04733 114.346175) (end 149.041373 114.336695) (width 0.1) (layer "F.Cu") (net 161))
  (segment (start 149.64733 114.183825) (end 149.641373 114.193305) (width 0.1) (layer "F.Cu") (net 161))
  (segment (start 149.236422 114.215) (end 149.236422 114.315) (width 0.1) (layer "F.Cu") (net 161))
  (segment (start 149.441373 114.336695) (end 149.437675 114.326127) (width 0.1) (layer "F.Cu") (net 161))
  (segment (start 150.476907 114.036907) (end 150.114515 114.036907) (width 0.1) (layer "F.Cu") (net 161))
  (segment (start 162.6 115.45) (end 163.500001 115.45) (width 0.1) (layer "F.Cu") (net 161))
  (segment (start 148.835168 114.226126) (end 148.83147 114.236694) (width 0.1) (layer "F.Cu") (net 161))
  (segment (start 149.237675 114.203873) (end 149.236422 114.215) (width 0.1) (layer "F.Cu") (net 161))
  (segment (start 149.041373 114.336695) (end 149.037675 114.326127) (width 0.1) (layer "F.Cu") (net 161))
  (segment (start 149.636422 114.315) (end 149.635168 114.326127) (width 0.1) (layer "F.Cu") (net 161))
  (segment (start 149.036422 114.315) (end 149.036422 114.215) (width 0.1) (layer "F.Cu") (net 161))
  (segment (start 149.641373 114.193305) (end 149.637675 114.203873) (width 0.1) (layer "F.Cu") (net 161))
  (segment (start 149.837675 114.226126) (end 149.835168 114.203873) (width 0.1) (layer "F.Cu") (net 161))
  (segment (start 149.636422 114.215) (end 149.636422 114.315) (width 0.1) (layer "F.Cu") (net 161))
  (segment (start 149.664727 114.169951) (end 149.655247 114.175908) (width 0.1) (layer "F.Cu") (net 161))
  (via (at 155.665 108.56625) (size 0.55) (drill 0.15) (layers "F.Cu" "B.Cu") (net 161))
  (via (at 164.05 115.5625) (size 0.55) (drill 0.15) (layers "F.Cu" "B.Cu") (net 161))
  (via (at 150.476907 114.036907) (size 0.55) (drill 0.15) (layers "F.Cu" "B.Cu") (net 161))
  (segment (start 150.476907 113.798259) (end 150.476907 114.036907) (width 0.15) (layer "In3.Cu") (net 161))
  (segment (start 153.067666 108.3975) (end 150.6625 110.802666) (width 0.15) (layer "In3.Cu") (net 161))
  (segment (start 150.6625 110.802666) (end 150.6625 113.612666) (width 0.15) (layer "In3.Cu") (net 161))
  (segment (start 150.6625 113.612666) (end 150.476907 113.798259) (width 0.15) (layer "In3.Cu") (net 161))
  (segment (start 155.49625 108.3975) (end 153.067666 108.3975) (width 0.15) (layer "In3.Cu") (net 161))
  (segment (start 155.665 108.56625) (end 155.49625 108.3975) (width 0.15) (layer "In3.Cu") (net 161))
  (segment (start 164.05 115.5625) (end 163.7875 115.3) (width 0.1) (layer "B.Cu") (net 161))
  (segment (start 160.825 109.956422) (end 159.178578 108.31) (width 0.1) (layer "B.Cu") (net 161))
  (segment (start 160.825 114.716422) (end 160.825 109.956422) (width 0.1) (layer "B.Cu") (net 161))
  (segment (start 161.408578 115.3) (end 160.825 114.716422) (width 0.1) (layer "B.Cu") (net 161))
  (segment (start 159.178578 108.31) (end 155.92125 108.31) (width 0.1) (layer "B.Cu") (net 161))
  (segment (start 163.7875 115.3) (end 161.408578 115.3) (width 0.1) (layer "B.Cu") (net 161))
  (segment (start 155.92125 108.31) (end 155.665 108.56625) (width 0.1) (layer "B.Cu") (net 161))
  (segment (start 163.7875 115.1) (end 164.05 114.8375) (width 0.1) (layer "F.Cu") (net 162))
  (segment (start 149.973093 113.895485) (end 149.973093 113.533093) (width 0.1) (layer "F.Cu") (net 162))
  (segment (start 148.17 113.94) (end 149.928578 113.94) (width 0.1) (layer "F.Cu") (net 162))
  (segment (start 149.928578 113.94) (end 149.973093 113.895485) (width 0.1) (layer "F.Cu") (net 162))
  (segment (start 163.650001 115.1) (end 163.7875 115.1) (width 0.1) (layer "F.Cu") (net 162))
  (segment (start 147.845 114.265) (end 148.17 113.94) (width 0.1) (layer "F.Cu") (net 162))
  (segment (start 163.500001 114.95) (end 163.650001 115.1) (width 0.1) (layer "F.Cu") (net 162))
  (segment (start 162.6 114.95) (end 163.500001 114.95) (width 0.1) (layer "F.Cu") (net 162))
  (via (at 155.665 107.85375) (size 0.55) (drill 0.15) (layers "F.Cu" "B.Cu") (net 162))
  (via (at 149.973093 113.533093) (size 0.55) (drill 0.15) (layers "F.Cu" "B.Cu") (net 162))
  (via (at 164.05 114.8375) (size 0.55) (drill 0.15) (layers "F.Cu" "B.Cu") (net 162))
  (segment (start 155.49625 108.0225) (end 152.912334 108.0225) (width 0.15) (layer "In3.Cu") (net 162))
  (segment (start 155.665 107.85375) (end 155.49625 108.0225) (width 0.15) (layer "In3.Cu") (net 162))
  (segment (start 150.2875 110.647334) (end 150.2875 113.457334) (width 0.15) (layer "In3.Cu") (net 162))
  (segment (start 152.912334 108.0225) (end 150.2875 110.647334) (width 0.15) (layer "In3.Cu") (net 162))
  (segment (start 150.2875 113.457334) (end 150.211741 113.533093) (width 0.15) (layer "In3.Cu") (net 162))
  (segment (start 150.211741 113.533093) (end 149.973093 113.533093) (width 0.15) (layer "In3.Cu") (net 162))
  (segment (start 159.261422 108.11) (end 155.92125 108.11) (width 0.1) (layer "B.Cu") (net 162))
  (segment (start 161.025 109.873578) (end 159.261422 108.11) (width 0.1) (layer "B.Cu") (net 162))
  (segment (start 164.05 114.8375) (end 163.7875 115.1) (width 0.1) (layer "B.Cu") (net 162))
  (segment (start 163.7875 115.1) (end 161.491422 115.1) (width 0.1) (layer "B.Cu") (net 162))
  (segment (start 161.025 114.633578) (end 161.025 109.873578) (width 0.1) (layer "B.Cu") (net 162))
  (segment (start 155.92125 108.11) (end 155.665 107.85375) (width 0.1) (layer "B.Cu") (net 162))
  (segment (start 161.491422 115.1) (end 161.025 114.633578) (width 0.1) (layer "B.Cu") (net 162))
  (segment (start 125 110.4) (end 132.5 110.4) (width 0.1) (layer "F.Cu") (net 166))
  (segment (start 124.5 110.9) (end 125 110.4) (width 0.1) (layer "F.Cu") (net 166))
  (segment (start 141.330267 114.915) (end 140.820459 114.405192) (width 0.1) (layer "F.Cu") (net 166))
  (segment (start 142.645 114.915) (end 141.330267 114.915) (width 0.1) (layer "F.Cu") (net 166))
  (via (at 140.820459 114.405192) (size 0.55) (drill 0.15) (layers "F.Cu" "B.Cu") (net 166))
  (via (at 132.5 110.4) (size 0.55) (drill 0.15) (layers "F.Cu" "B.Cu") (net 166))
  (segment (start 134.204235 110.774085) (end 134.227936 110.759192) (width 0.125) (layer "In3.Cu") (net 166))
  (segment (start 135.497728 110.0606) (end 135.512621 110.084301) (width 0.125) (layer "In3.Cu") (net 166))
  (segment (start 135.4 110.013536) (end 135.427815 110.016671) (width 0.125) (layer "In3.Cu") (net 166))
  (segment (start 135.15 110.786464) (end 135.177815 110.783329) (width 0.125) (layer "In3.Cu") (net 166))
  (segment (start 133.872184 110.016671) (end 133.9 110.013536) (width 0.125) (layer "In3.Cu") (net 166))
  (segment (start 132.954235 110.412378) (end 132.977936 110.427271) (width 0.125) (layer "In3.Cu") (net 166))
  (segment (start 133.072063 110.759192) (end 133.095764 110.774085) (width 0.125) (layer "In3.Cu") (net 166))
  (segment (start 135.345764 110.025915) (end 135.372184 110.016671) (width 0.125) (layer "In3.Cu") (net 166))
  (segment (start 135.322063 110.040808) (end 135.345764 110.025915) (width 0.125) (layer "In3.Cu") (net 166))
  (segment (start 133.525 110.138536) (end 133.525 110.661464) (width 0.125) (layer "In3.Cu") (net 166))
  (segment (start 133.622184 110.783329) (end 133.65 110.786464) (width 0.125) (layer "In3.Cu") (net 166))
  (segment (start 134.275 110.138536) (end 134.278134 110.110721) (width 0.125) (layer "In3.Cu") (net 166))
  (segment (start 132.927815 110.403134) (end 132.954235 110.412378) (width 0.125) (layer "In3.Cu") (net 166))
  (segment (start 133.787378 110.084301) (end 133.802271 110.0606) (width 0.125) (layer "In3.Cu") (net 166))
  (segment (start 132.9 110.4) (end 132.927815 110.403134) (width 0.125) (layer "In3.Cu") (net 166))
  (segment (start 135.275 110.661464) (end 135.275 110.138536) (width 0.125) (layer "In3.Cu") (net 166))
  (segment (start 134.954235 110.025915) (end 134.977936 110.040808) (width 0.125) (layer "In3.Cu") (net 166))
  (segment (start 134.122184 110.783329) (end 134.15 110.786464) (width 0.125) (layer "In3.Cu") (net 166))
  (segment (start 133.775 110.661464) (end 133.775 110.138536) (width 0.125) (layer "In3.Cu") (net 166))
  (segment (start 135.512621 110.084301) (end 135.521865 110.110721) (width 0.125) (layer "In3.Cu") (net 166))
  (segment (start 133.677815 110.783329) (end 133.704235 110.774085) (width 0.125) (layer "In3.Cu") (net 166))
  (segment (start 133.345764 110.025915) (end 133.372184 110.016671) (width 0.125) (layer "In3.Cu") (net 166))
  (segment (start 134.287378 110.084301) (end 134.302271 110.0606) (width 0.125) (layer "In3.Cu") (net 166))
  (segment (start 134.322063 110.040808) (end 134.345764 110.025915) (width 0.125) (layer "In3.Cu") (net 166))
  (segment (start 135.095764 110.774085) (end 135.122184 110.783329) (width 0.125) (layer "In3.Cu") (net 166))
  (segment (start 134.025 110.138536) (end 134.025 110.661464) (width 0.125) (layer "In3.Cu") (net 166))
  (segment (start 134.4 110.013536) (end 134.427815 110.016671) (width 0.125) (layer "In3.Cu") (net 166))
  (segment (start 135.372184 110.016671) (end 135.4 110.013536) (width 0.125) (layer "In3.Cu") (net 166))
  (segment (start 133.287378 110.084301) (end 133.302271 110.0606) (width 0.125) (layer "In3.Cu") (net 166))
  (segment (start 135.037378 110.715699) (end 135.052271 110.7394) (width 0.125) (layer "In3.Cu") (net 166))
  (segment (start 133.477936 110.040808) (end 133.497728 110.0606) (width 0.125) (layer "In3.Cu") (net 166))
  (segment (start 136.815267 110.4) (end 140.820459 114.405192) (width 0.125) (layer "In3.Cu") (net 166))
  (segment (start 135.072063 110.759192) (end 135.095764 110.774085) (width 0.125) (layer "In3.Cu") (net 166))
  (segment (start 134.677815 110.783329) (end 134.704235 110.774085) (width 0.125) (layer "In3.Cu") (net 166))
  (segment (start 134.537378 110.715699) (end 134.552271 110.7394) (width 0.125) (layer "In3.Cu") (net 166))
  (segment (start 134.822063 110.040808) (end 134.845764 110.025915) (width 0.125) (layer "In3.Cu") (net 166))
  (segment (start 133.521865 110.110721) (end 133.525 110.138536) (width 0.125) (layer "In3.Cu") (net 166))
  (segment (start 133.028134 110.689279) (end 133.037378 110.715699) (width 0.125) (layer "In3.Cu") (net 166))
  (segment (start 133.977936 110.040808) (end 133.997728 110.0606) (width 0.125) (layer "In3.Cu") (net 166))
  (segment (start 135.028134 110.689279) (end 135.037378 110.715699) (width 0.125) (layer "In3.Cu") (net 166))
  (segment (start 134.372184 110.016671) (end 134.4 110.013536) (width 0.125) (layer "In3.Cu") (net 166))
  (segment (start 134.052271 110.7394) (end 134.072063 110.759192) (width 0.125) (layer "In3.Cu") (net 166))
  (segment (start 134.552271 110.7394) (end 134.572063 110.759192) (width 0.125) (layer "In3.Cu") (net 166))
  (segment (start 135.454235 110.025915) (end 135.477936 110.040808) (width 0.125) (layer "In3.Cu") (net 166))
  (segment (start 134.525 110.138536) (end 134.525 110.661464) (width 0.125) (layer "In3.Cu") (net 166))
  (segment (start 134.595764 110.774085) (end 134.622184 110.783329) (width 0.125) (layer "In3.Cu") (net 166))
  (segment (start 133.271865 110.689279) (end 133.275 110.661464) (width 0.125) (layer "In3.Cu") (net 166))
  (segment (start 134.278134 110.110721) (end 134.287378 110.084301) (width 0.125) (layer "In3.Cu") (net 166))
  (segment (start 134.227936 110.759192) (end 134.247728 110.7394) (width 0.125) (layer "In3.Cu") (net 166))
  (segment (start 133.262621 110.715699) (end 133.271865 110.689279) (width 0.125) (layer "In3.Cu") (net 166))
  (segment (start 133.278134 110.110721) (end 133.287378 110.084301) (width 0.125) (layer "In3.Cu") (net 166))
  (segment (start 134.572063 110.759192) (end 134.595764 110.774085) (width 0.125) (layer "In3.Cu") (net 166))
  (segment (start 134.521865 110.110721) (end 134.525 110.138536) (width 0.125) (layer "In3.Cu") (net 166))
  (segment (start 133.427815 110.016671) (end 133.454235 110.025915) (width 0.125) (layer "In3.Cu") (net 166))
  (segment (start 134.65 110.786464) (end 134.677815 110.783329) (width 0.125) (layer "In3.Cu") (net 166))
  (segment (start 134.775 110.661464) (end 134.775 110.138536) (width 0.125) (layer "In3.Cu") (net 166))
  (segment (start 134.747728 110.7394) (end 134.762621 110.715699) (width 0.125) (layer "In3.Cu") (net 166))
  (segment (start 134.787378 110.084301) (end 134.802271 110.0606) (width 0.125) (layer "In3.Cu") (net 166))
  (segment (start 134.271865 110.689279) (end 134.275 110.661464) (width 0.125) (layer "In3.Cu") (net 166))
  (segment (start 135.025 110.138536) (end 135.025 110.661464) (width 0.125) (layer "In3.Cu") (net 166))
  (segment (start 133.037378 110.715699) (end 133.052271 110.7394) (width 0.125) (layer "In3.Cu") (net 166))
  (segment (start 134.262621 110.715699) (end 134.271865 110.689279) (width 0.125) (layer "In3.Cu") (net 166))
  (segment (start 133.775 110.138536) (end 133.778134 110.110721) (width 0.125) (layer "In3.Cu") (net 166))
  (segment (start 133.275 110.138536) (end 133.278134 110.110721) (width 0.125) (layer "In3.Cu") (net 166))
  (segment (start 135.052271 110.7394) (end 135.072063 110.759192) (width 0.125) (layer "In3.Cu") (net 166))
  (segment (start 133.528134 110.689279) (end 133.537378 110.715699) (width 0.125) (layer "In3.Cu") (net 166))
  (segment (start 133.512621 110.084301) (end 133.521865 110.110721) (width 0.125) (layer "In3.Cu") (net 166))
  (segment (start 135.271865 110.689279) (end 135.275 110.661464) (width 0.125) (layer "In3.Cu") (net 166))
  (segment (start 134.762621 110.715699) (end 134.771865 110.689279) (width 0.125) (layer "In3.Cu") (net 166))
  (segment (start 134.345764 110.025915) (end 134.372184 110.016671) (width 0.125) (layer "In3.Cu") (net 166))
  (segment (start 135.622184 110.396866) (end 135.65 110.4) (width 0.125) (layer "In3.Cu") (net 166))
  (segment (start 134.872184 110.016671) (end 134.9 110.013536) (width 0.125) (layer "In3.Cu") (net 166))
  (segment (start 135.287378 110.084301) (end 135.302271 110.0606) (width 0.125) (layer "In3.Cu") (net 166))
  (segment (start 134.15 110.786464) (end 134.177815 110.783329) (width 0.125) (layer "In3.Cu") (net 166))
  (segment (start 134.977936 110.040808) (end 134.997728 110.0606) (width 0.125) (layer "In3.Cu") (net 166))
  (segment (start 135.477936 110.040808) (end 135.497728 110.0606) (width 0.125) (layer "In3.Cu") (net 166))
  (segment (start 134.727936 110.759192) (end 134.747728 110.7394) (width 0.125) (layer "In3.Cu") (net 166))
  (segment (start 134.704235 110.774085) (end 134.727936 110.759192) (width 0.125) (layer "In3.Cu") (net 166))
  (segment (start 133.747728 110.7394) (end 133.762621 110.715699) (width 0.125) (layer "In3.Cu") (net 166))
  (segment (start 133.778134 110.110721) (end 133.787378 110.084301) (width 0.125) (layer "In3.Cu") (net 166))
  (segment (start 135.552271 110.352937) (end 135.572063 110.372729) (width 0.125) (layer "In3.Cu") (net 166))
  (segment (start 134.927815 110.016671) (end 134.954235 110.025915) (width 0.125) (layer "In3.Cu") (net 166))
  (segment (start 133.822063 110.040808) (end 133.845764 110.025915) (width 0.125) (layer "In3.Cu") (net 166))
  (segment (start 134.771865 110.689279) (end 134.775 110.661464) (width 0.125) (layer "In3.Cu") (net 166))
  (segment (start 133.537378 110.715699) (end 133.552271 110.7394) (width 0.125) (layer "In3.Cu") (net 166))
  (segment (start 135.122184 110.783329) (end 135.15 110.786464) (width 0.125) (layer "In3.Cu") (net 166))
  (segment (start 133.095764 110.774085) (end 133.122184 110.783329) (width 0.125) (layer "In3.Cu") (net 166))
  (segment (start 133.704235 110.774085) (end 133.727936 110.759192) (width 0.125) (layer "In3.Cu") (net 166))
  (segment (start 134.845764 110.025915) (end 134.872184 110.016671) (width 0.125) (layer "In3.Cu") (net 166))
  (segment (start 133.802271 110.0606) (end 133.822063 110.040808) (width 0.125) (layer "In3.Cu") (net 166))
  (segment (start 135.572063 110.372729) (end 135.595764 110.387622) (width 0.125) (layer "In3.Cu") (net 166))
  (segment (start 135.528134 110.302816) (end 135.537378 110.329236) (width 0.125) (layer "In3.Cu") (net 166))
  (segment (start 135.012621 110.084301) (end 135.021865 110.110721) (width 0.125) (layer "In3.Cu") (net 166))
  (segment (start 135.521865 110.110721) (end 135.525 110.138536) (width 0.125) (layer "In3.Cu") (net 166))
  (segment (start 134.997728 110.0606) (end 135.012621 110.084301) (width 0.125) (layer "In3.Cu") (net 166))
  (segment (start 134.454235 110.025915) (end 134.477936 110.040808) (width 0.125) (layer "In3.Cu") (net 166))
  (segment (start 133.497728 110.0606) (end 133.512621 110.084301) (width 0.125) (layer "In3.Cu") (net 166))
  (segment (start 134.021865 110.110721) (end 134.025 110.138536) (width 0.125) (layer "In3.Cu") (net 166))
  (segment (start 134.028134 110.689279) (end 134.037378 110.715699) (width 0.125) (layer "In3.Cu") (net 166))
  (segment (start 133.4 110.013536) (end 133.427815 110.016671) (width 0.125) (layer "In3.Cu") (net 166))
  (segment (start 134.247728 110.7394) (end 134.262621 110.715699) (width 0.125) (layer "In3.Cu") (net 166))
  (segment (start 134.275 110.661464) (end 134.275 110.138536) (width 0.125) (layer "In3.Cu") (net 166))
  (segment (start 133.025 110.525) (end 133.025 110.661464) (width 0.125) (layer "In3.Cu") (net 166))
  (segment (start 134.095764 110.774085) (end 134.122184 110.783329) (width 0.125) (layer "In3.Cu") (net 166))
  (segment (start 133.122184 110.783329) (end 133.15 110.786464) (width 0.125) (layer "In3.Cu") (net 166))
  (segment (start 133.322063 110.040808) (end 133.345764 110.025915) (width 0.125) (layer "In3.Cu") (net 166))
  (segment (start 134.497728 110.0606) (end 134.512621 110.084301) (width 0.125) (layer "In3.Cu") (net 166))
  (segment (start 135.275 110.138536) (end 135.278134 110.110721) (width 0.125) (layer "In3.Cu") (net 166))
  (segment (start 135.302271 110.0606) (end 135.322063 110.040808) (width 0.125) (layer "In3.Cu") (net 166))
  (segment (start 134.025 110.661464) (end 134.028134 110.689279) (width 0.125) (layer "In3.Cu") (net 166))
  (segment (start 133.454235 110.025915) (end 133.477936 110.040808) (width 0.125) (layer "In3.Cu") (net 166))
  (segment (start 134.778134 110.110721) (end 134.787378 110.084301) (width 0.125) (layer "In3.Cu") (net 166))
  (segment (start 133.927815 110.016671) (end 133.954235 110.025915) (width 0.125) (layer "In3.Cu") (net 166))
  (segment (start 133.762621 110.715699) (end 133.771865 110.689279) (width 0.125) (layer "In3.Cu") (net 166))
  (segment (start 133.012621 110.470764) (end 133.021865 110.497184) (width 0.125) (layer "In3.Cu") (net 166))
  (segment (start 134.512621 110.084301) (end 134.521865 110.110721) (width 0.125) (layer "In3.Cu") (net 166))
  (segment (start 133.572063 110.759192) (end 133.595764 110.774085) (width 0.125) (layer "In3.Cu") (net 166))
  (segment (start 133.204235 110.774085) (end 133.227936 110.759192) (width 0.125) (layer "In3.Cu") (net 166))
  (segment (start 132.977936 110.427271) (end 132.997728 110.447063) (width 0.125) (layer "In3.Cu") (net 166))
  (segment (start 135.262621 110.715699) (end 135.271865 110.689279) (width 0.125) (layer "In3.Cu") (net 166))
  (segment (start 135.537378 110.329236) (end 135.552271 110.352937) (width 0.125) (layer "In3.Cu") (net 166))
  (segment (start 134.525 110.661464) (end 134.528134 110.689279) (width 0.125) (layer "In3.Cu") (net 166))
  (segment (start 135.204235 110.774085) (end 135.227936 110.759192) (width 0.125) (layer "In3.Cu") (net 166))
  (segment (start 135.227936 110.759192) (end 135.247728 110.7394) (width 0.125) (layer "In3.Cu") (net 166))
  (segment (start 135.278134 110.110721) (end 135.287378 110.084301) (width 0.125) (layer "In3.Cu") (net 166))
  (segment (start 133.302271 110.0606) (end 133.322063 110.040808) (width 0.125) (layer "In3.Cu") (net 166))
  (segment (start 133.552271 110.7394) (end 133.572063 110.759192) (width 0.125) (layer "In3.Cu") (net 166))
  (segment (start 135.247728 110.7394) (end 135.262621 110.715699) (width 0.125) (layer "In3.Cu") (net 166))
  (segment (start 133.275 110.661464) (end 133.275 110.138536) (width 0.125) (layer "In3.Cu") (net 166))
  (segment (start 133.052271 110.7394) (end 133.072063 110.759192) (width 0.125) (layer "In3.Cu") (net 166))
  (segment (start 134.622184 110.783329) (end 134.65 110.786464) (width 0.125) (layer "In3.Cu") (net 166))
  (segment (start 134.427815 110.016671) (end 134.454235 110.025915) (width 0.125) (layer "In3.Cu") (net 166))
  (segment (start 133.372184 110.016671) (end 133.4 110.013536) (width 0.125) (layer "In3.Cu") (net 166))
  (segment (start 133.525 110.661464) (end 133.528134 110.689279) (width 0.125) (layer "In3.Cu") (net 166))
  (segment (start 133.247728 110.7394) (end 133.262621 110.715699) (width 0.125) (layer "In3.Cu") (net 166))
  (segment (start 135.595764 110.387622) (end 135.622184 110.396866) (width 0.125) (layer "In3.Cu") (net 166))
  (segment (start 134.177815 110.783329) (end 134.204235 110.774085) (width 0.125) (layer "In3.Cu") (net 166))
  (segment (start 133.954235 110.025915) (end 133.977936 110.040808) (width 0.125) (layer "In3.Cu") (net 166))
  (segment (start 135.177815 110.783329) (end 135.204235 110.774085) (width 0.125) (layer "In3.Cu") (net 166))
  (segment (start 135.427815 110.016671) (end 135.454235 110.025915) (width 0.125) (layer "In3.Cu") (net 166))
  (segment (start 133.727936 110.759192) (end 133.747728 110.7394) (width 0.125) (layer "In3.Cu") (net 166))
  (segment (start 133.997728 110.0606) (end 134.012621 110.084301) (width 0.125) (layer "In3.Cu") (net 166))
  (segment (start 134.775 110.138536) (end 134.778134 110.110721) (width 0.125) (layer "In3.Cu") (net 166))
  (segment (start 134.528134 110.689279) (end 134.537378 110.715699) (width 0.125) (layer "In3.Cu") (net 166))
  (segment (start 132.997728 110.447063) (end 133.012621 110.470764) (width 0.125) (layer "In3.Cu") (net 166))
  (segment (start 134.302271 110.0606) (end 134.322063 110.040808) (width 0.125) (layer "In3.Cu") (net 166))
  (segment (start 133.15 110.786464) (end 133.177815 110.783329) (width 0.125) (layer "In3.Cu") (net 166))
  (segment (start 135.021865 110.110721) (end 135.025 110.138536) (width 0.125) (layer "In3.Cu") (net 166))
  (segment (start 134.037378 110.715699) (end 134.052271 110.7394) (width 0.125) (layer "In3.Cu") (net 166))
  (segment (start 133.227936 110.759192) (end 133.247728 110.7394) (width 0.125) (layer "In3.Cu") (net 166))
  (segment (start 134.9 110.013536) (end 134.927815 110.016671) (width 0.125) (layer "In3.Cu") (net 166))
  (segment (start 135.025 110.661464) (end 135.028134 110.689279) (width 0.125) (layer "In3.Cu") (net 166))
  (segment (start 135.65 110.4) (end 136.815267 110.4) (width 0.125) (layer "In3.Cu") (net 166))
  (segment (start 134.072063 110.759192) (end 134.095764 110.774085) (width 0.125) (layer "In3.Cu") (net 166))
  (segment (start 133.845764 110.025915) (end 133.872184 110.016671) (width 0.125) (layer "In3.Cu") (net 166))
  (segment (start 133.65 110.786464) (end 133.677815 110.783329) (width 0.125) (layer "In3.Cu") (net 166))
  (segment (start 134.802271 110.0606) (end 134.822063 110.040808) (width 0.125) (layer "In3.Cu") (net 166))
  (segment (start 134.477936 110.040808) (end 134.497728 110.0606) (width 0.125) (layer "In3.Cu") (net 166))
  (segment (start 135.525 110.275) (end 135.528134 110.302816) (width 0.125) (layer "In3.Cu") (net 166))
  (segment (start 133.177815 110.783329) (end 133.204235 110.774085) (width 0.125) (layer "In3.Cu") (net 166))
  (segment (start 133.021865 110.497184) (end 133.025 110.525) (width 0.125) (layer "In3.Cu") (net 166))
  (segment (start 135.525 110.138536) (end 135.525 110.275) (width 0.125) (layer "In3.Cu") (net 166))
  (segment (start 133.025 110.661464) (end 133.028134 110.689279) (width 0.125) (layer "In3.Cu") (net 166))
  (segment (start 133.9 110.013536) (end 133.927815 110.016671) (width 0.125) (layer "In3.Cu") (net 166))
  (segment (start 133.595764 110.774085) (end 133.622184 110.783329) (width 0.125) (layer "In3.Cu") (net 166))
  (segment (start 132.5 110.4) (end 132.9 110.4) (width 0.125) (layer "In3.Cu") (net 166))
  (segment (start 134.012621 110.084301) (end 134.021865 110.110721) (width 0.125) (layer "In3.Cu") (net 166))
  (segment (start 133.771865 110.689279) (end 133.775 110.661464) (width 0.125) (layer "In3.Cu") (net 166))
  (segment (start 129.49 111.4) (end 128.99 110.9) (width 0.1) (layer "F.Cu") (net 167))
  (segment (start 140.19 115.07) (end 140.685 115.565) (width 0.1) (layer "F.Cu") (net 167))
  (segment (start 125.5 110.9) (end 128.99 110.9) (width 0.1) (layer "F.Cu") (net 167))
  (segment (start 129.49 111.4) (end 132.5 111.4) (width 0.1) (layer "F.Cu") (net 167))
  (segment (start 142.645 115.565) (end 140.685 115.565) (width 0.1) (layer "F.Cu") (net 167))
  (via (at 140.19 115.07) (size 0.55) (drill 0.15) (layers "F.Cu" "B.Cu") (net 167))
  (via (at 132.5 111.4) (size 0.55) (drill 0.15) (layers "F.Cu" "B.Cu") (net 167))
  (segment (start 137.248834 111.730612) (end 137.231382 111.752496) (width 0.125) (layer "In3.Cu") (net 167))
  (segment (start 136.61 111.666776) (end 136.518945 111.75783) (width 0.125) (layer "In3.Cu") (net 167))
  (segment (start 138.309481 112.791259) (end 138.292029 112.813143) (width 0.125) (layer "In3.Cu") (net 167))
  (segment (start 138.681402 113.064307) (end 138.681403 113.092299) (width 0.125) (layer "In3.Cu") (net 167))
  (segment (start 136.872494 112.111379) (end 136.855042 112.133263) (width 0.125) (layer "In3.Cu") (net 167))
  (segment (start 138.250864 113.599968) (end 138.250864 113.627959) (width 0.125) (layer "In3.Cu") (net 167))
  (segment (start 138.115253 112.636368) (end 138.137135 112.618914) (width 0.125) (layer "In3.Cu") (net 167))
  (segment (start 138.327854 112.73875) (end 138.321626 112.76604) (width 0.125) (layer "In3.Cu") (net 167))
  (segment (start 137.054606 111.575721) (end 137.076488 111.558267) (width 0.125) (layer "In3.Cu") (net 167))
  (segment (start 137.231382 111.752496) (end 136.872494 112.111379) (width 0.125) (layer "In3.Cu") (net 167))
  (segment (start 136.627452 111.644892) (end 136.61 111.666776) (width 0.125) (layer "In3.Cu") (net 167))
  (segment (start 138.333793 113.731949) (end 138.361082 113.738177) (width 0.125) (layer "In3.Cu") (net 167))
  (segment (start 137.681975 113.031079) (end 137.709265 113.024851) (width 0.125) (layer "In3.Cu") (net 167))
  (segment (start 137.974305 112.385201) (end 137.968077 112.412491) (width 0.125) (layer "In3.Cu") (net 167))
  (segment (start 137.897315 113.27441) (end 137.903544 113.301699) (width 0.125) (layer "In3.Cu") (net 167))
  (segment (start 137.156988 111.539893) (end 137.184277 111.546122) (width 0.125) (layer "In3.Cu") (net 167))
  (segment (start 137.709265 113.024851) (end 137.734484 113.012706) (width 0.125) (layer "In3.Cu") (net 167))
  (segment (start 137.248834 111.597604) (end 137.260979 111.622823) (width 0.125) (layer "In3.Cu") (net 167))
  (segment (start 137.601476 113.012706) (end 137.626695 113.024851) (width 0.125) (layer "In3.Cu") (net 167))
  (segment (start 137.808805 112.25322) (end 137.836096 112.246992) (width 0.125) (layer "In3.Cu") (net 167))
  (segment (start 138.890619 113.766186) (end 138.908071 113.78807) (width 0.125) (layer "In3.Cu") (net 167))
  (segment (start 137.510537 111.893442) (end 137.537826 111.899671) (width 0.125) (layer "In3.Cu") (net 167))
  (segment (start 137.076488 111.558267) (end 137.101707 111.546122) (width 0.125) (layer "In3.Cu") (net 167))
  (segment (start 138.515903 112.960318) (end 138.543194 112.95409) (width 0.125) (layer "In3.Cu") (net 167))
  (segment (start 139.034952 113.445848) (end 139.028724 113.473138) (width 0.125) (layer "In3.Cu") (net 167))
  (segment (start 138.896743 113.307639) (end 138.924733 113.307638) (width 0.125) (layer "In3.Cu") (net 167))
  (segment (start 138.257093 113.655248) (end 138.269238 113.680467) (width 0.125) (layer "In3.Cu") (net 167))
  (segment (start 138.908071 113.78807) (end 140.19 115.07) (width 0.125) (layer "In3.Cu") (net 167))
  (segment (start 136.518945 111.75783) (end 136.501493 111.779714) (width 0.125) (layer "In3.Cu") (net 167))
  (segment (start 136.501493 111.912722) (end 136.518945 111.934606) (width 0.125) (layer "In3.Cu") (net 167))
  (segment (start 136.61 111.49) (end 136.627452 111.511884) (width 0.125) (layer "In3.Cu") (net 167))
  (segment (start 137.620756 112.031652) (end 137.614528 112.058942) (width 0.125) (layer "In3.Cu") (net 167))
  (segment (start 138.924733 113.307638) (end 138.952022 113.313867) (width 0.125) (layer "In3.Cu") (net 167))
  (segment (start 137.190217 112.567312) (end 137.196446 112.594601) (width 0.125) (layer "In3.Cu") (net 167))
  (segment (start 138.28669 113.702352) (end 138.308574 113.719804) (width 0.125) (layer "In3.Cu") (net 167))
  (segment (start 138.681403 113.092299) (end 138.675175 113.119589) (width 0.125) (layer "In3.Cu") (net 167))
  (segment (start 137.231382 111.57572) (end 137.248834 111.597604) (width 0.125) (layer "In3.Cu") (net 167))
  (segment (start 137.602383 112.084161) (end 137.584931 112.106045) (width 0.125) (layer "In3.Cu") (net 167))
  (segment (start 137.482547 111.893443) (end 137.510537 111.893442) (width 0.125) (layer "In3.Cu") (net 167))
  (segment (start 137.226043 112.641705) (end 137.247927 112.659157) (width 0.125) (layer "In3.Cu") (net 167))
  (segment (start 137.128998 111.539894) (end 137.156988 111.539893) (width 0.125) (layer "In3.Cu") (net 167))
  (segment (start 138.623692 112.972463) (end 138.645578 112.989916) (width 0.125) (layer "In3.Cu") (net 167))
  (segment (start 136.489348 111.887503) (end 136.501493 111.912722) (width 0.125) (layer "In3.Cu") (net 167))
  (segment (start 138.244924 112.606769) (end 138.270143 112.618914) (width 0.125) (layer "In3.Cu") (net 167))
  (segment (start 137.190217 112.539321) (end 137.190217 112.567312) (width 0.125) (layer "In3.Cu") (net 167))
  (segment (start 138.490684 112.972463) (end 138.515903 112.960318) (width 0.125) (layer "In3.Cu") (net 167))
  (segment (start 136.974877 112.323981) (end 137.002167 112.317753) (width 0.125) (layer "In3.Cu") (net 167))
  (segment (start 137.208591 112.486812) (end 137.196446 112.512031) (width 0.125) (layer "In3.Cu") (net 167))
  (segment (start 138.543194 112.95409) (end 138.571184 112.954089) (width 0.125) (layer "In3.Cu") (net 167))
  (segment (start 139.016579 113.498357) (end 138.999127 113.520241) (width 0.125) (layer "In3.Cu") (net 167))
  (segment (start 136.540829 111.952058) (end 136.566048 111.964203) (width 0.125) (layer "In3.Cu") (net 167))
  (segment (start 138.66303 113.144808) (end 138.645578 113.166692) (width 0.125) (layer "In3.Cu") (net 167))
  (segment (start 137.380935 112.659157) (end 137.402819 112.641705) (width 0.125) (layer "In3.Cu") (net 167))
  (segment (start 137.260979 111.622823) (end 137.267206 111.650111) (width 0.125) (layer "In3.Cu") (net 167))
  (segment (start 138.189645 112.600541) (end 138.217635 112.60054) (width 0.125) (layer "In3.Cu") (net 167))
  (segment (start 138.463466 113.702352) (end 138.822351 113.343466) (width 0.125) (layer "In3.Cu") (net 167))
  (segment (start 137.355716 112.671302) (end 137.380935 112.659157) (width 0.125) (layer "In3.Cu") (net 167))
  (segment (start 138.878474 113.658397) (end 138.872247 113.685687) (width 0.125) (layer "In3.Cu") (net 167))
  (segment (start 138.257093 113.572678) (end 138.250864 113.599968) (width 0.125) (layer "In3.Cu") (net 167))
  (segment (start 137.836096 112.246992) (end 137.864086 112.246991) (width 0.125) (layer "In3.Cu") (net 167))
  (segment (start 138.872247 113.713679) (end 138.878474 113.740967) (width 0.125) (layer "In3.Cu") (net 167))
  (segment (start 137.196446 112.512031) (end 137.190217 112.539321) (width 0.125) (layer "In3.Cu") (net 167))
  (segment (start 138.062814 113.3784) (end 138.088033 113.366255) (width 0.125) (layer "In3.Cu") (net 167))
  (segment (start 137.614528 112.058942) (end 137.602383 112.084161) (width 0.125) (layer "In3.Cu") (net 167))
  (segment (start 137.101707 111.546122) (end 137.128998 111.539894) (width 0.125) (layer "In3.Cu") (net 167))
  (segment (start 137.93848 112.282818) (end 137.955932 112.304702) (width 0.125) (layer "In3.Cu") (net 167))
  (segment (start 137.620755 112.00366) (end 137.620756 112.031652) (width 0.125) (layer "In3.Cu") (net 167))
  (segment (start 137.208591 112.61982) (end 137.226043 112.641705) (width 0.125) (layer "In3.Cu") (net 167))
  (segment (start 138.598473 112.960318) (end 138.623692 112.972463) (width 0.125) (layer "In3.Cu") (net 167))
  (segment (start 138.869452 113.313867) (end 138.896743 113.307639) (width 0.125) (layer "In3.Cu") (net 167))
  (segment (start 136.48312 111.832222) (end 136.48312 111.860214) (width 0.125) (layer "In3.Cu") (net 167))
  (segment (start 138.675175 113.119589) (end 138.66303 113.144808) (width 0.125) (layer "In3.Cu") (net 167))
  (segment (start 137.184277 111.546122) (end 137.209496 111.558267) (width 0.125) (layer "In3.Cu") (net 167))
  (segment (start 137.027386 112.305608) (end 137.04927 112.288156) (width 0.125) (layer "In3.Cu") (net 167))
  (segment (start 137.260979 111.705393) (end 137.248834 111.730612) (width 0.125) (layer "In3.Cu") (net 167))
  (segment (start 136.52 111.4) (end 136.61 111.49) (width 0.125) (layer "In3.Cu") (net 167))
  (segment (start 138.137135 112.618914) (end 138.162354 112.606769) (width 0.125) (layer "In3.Cu") (net 167))
  (segment (start 136.842897 112.158482) (end 136.836668 112.185772) (width 0.125) (layer "In3.Cu") (net 167))
  (segment (start 136.621328 111.970431) (end 136.648618 111.964203) (width 0.125) (layer "In3.Cu") (net 167))
  (segment (start 136.919597 112.317753) (end 136.946886 112.323981) (width 0.125) (layer "In3.Cu") (net 167))
  (segment (start 138.908071 113.611294) (end 138.890619 113.633178) (width 0.125) (layer "In3.Cu") (net 167))
  (segment (start 136.872494 112.288156) (end 136.894378 112.305608) (width 0.125) (layer "In3.Cu") (net 167))
  (segment (start 137.614528 111.976372) (end 137.620755 112.00366) (width 0.125) (layer "In3.Cu") (net 167))
  (segment (start 138.822351 113.343466) (end 138.844233 113.326012) (width 0.125) (layer "In3.Cu") (net 167))
  (segment (start 136.842897 112.241052) (end 136.855042 112.266271) (width 0.125) (layer "In3.Cu") (net 167))
  (segment (start 139.028724 113.390568) (end 139.034951 113.417856) (width 0.125) (layer "In3.Cu") (net 167))
  (segment (start 138.571184 112.954089) (end 138.598473 112.960318) (width 0.125) (layer "In3.Cu") (net 167))
  (segment (start 138.269238 113.680467) (end 138.28669 113.702352) (width 0.125) (layer "In3.Cu") (net 167))
  (segment (start 137.602383 111.951153) (end 137.614528 111.976372) (width 0.125) (layer "In3.Cu") (net 167))
  (segment (start 137.002167 112.317753) (end 137.027386 112.305608) (width 0.125) (layer "In3.Cu") (net 167))
  (segment (start 137.955025 113.366255) (end 137.980244 113.3784) (width 0.125) (layer "In3.Cu") (net 167))
  (segment (start 137.543766 112.920861) (end 137.549995 112.94815) (width 0.125) (layer "In3.Cu") (net 167))
  (segment (start 136.894378 112.305608) (end 136.919597 112.317753) (width 0.125) (layer "In3.Cu") (net 167))
  (segment (start 137.974304 112.357209) (end 137.974305 112.385201) (width 0.125) (layer "In3.Cu") (net 167))
  (segment (start 136.489348 111.804933) (end 136.48312 111.832222) (width 0.125) (layer "In3.Cu") (net 167))
  (segment (start 136.695721 111.934606) (end 137.054606 111.575721) (width 0.125) (layer "In3.Cu") (net 167))
  (segment (start 138.999127 113.520241) (end 138.908071 113.611294) (width 0.125) (layer "In3.Cu") (net 167))
  (segment (start 137.955932 112.304702) (end 137.968077 112.329921) (width 0.125) (layer "In3.Cu") (net 167))
  (segment (start 138.035524 113.384628) (end 138.062814 113.3784) (width 0.125) (layer "In3.Cu") (net 167))
  (segment (start 137.455256 111.899671) (end 137.482547 111.893443) (width 0.125) (layer "In3.Cu") (net 167))
  (segment (start 136.673837 111.952058) (end 136.695721 111.934606) (width 0.125) (layer "In3.Cu") (net 167))
  (segment (start 138.361082 113.738177) (end 138.389073 113.738177) (width 0.125) (layer "In3.Cu") (net 167))
  (segment (start 138.645578 113.166692) (end 138.28669 113.525575) (width 0.125) (layer "In3.Cu") (net 167))
  (segment (start 137.226043 112.464928) (end 137.208591 112.486812) (width 0.125) (layer "In3.Cu") (net 167))
  (segment (start 137.93848 112.459594) (end 137.579592 112.818477) (width 0.125) (layer "In3.Cu") (net 167))
  (segment (start 137.328426 112.67753) (end 137.355716 112.671302) (width 0.125) (layer "In3.Cu") (net 167))
  (segment (start 137.408155 111.92927) (end 137.430037 111.911816) (width 0.125) (layer "In3.Cu") (net 167))
  (segment (start 138.389073 113.738177) (end 138.416363 113.731949) (width 0.125) (layer "In3.Cu") (net 167))
  (segment (start 138.162354 112.606769) (end 138.189645 112.600541) (width 0.125) (layer "In3.Cu") (net 167))
  (segment (start 138.441582 113.719804) (end 138.463466 113.702352) (width 0.125) (layer "In3.Cu") (net 167))
  (segment (start 138.269238 113.547459) (end 138.257093 113.572678) (width 0.125) (layer "In3.Cu") (net 167))
  (segment (start 137.563045 111.911816) (end 137.584931 111.929269) (width 0.125) (layer "In3.Cu") (net 167))
  (segment (start 138.675175 113.037019) (end 138.681402 113.064307) (width 0.125) (layer "In3.Cu") (net 167))
  (segment (start 137.56214 112.973369) (end 137.579592 112.995254) (width 0.125) (layer "In3.Cu") (net 167))
  (segment (start 137.537826 111.899671) (end 137.563045 111.911816) (width 0.125) (layer "In3.Cu") (net 167))
  (segment (start 137.549995 112.94815) (end 137.56214 112.973369) (width 0.125) (layer "In3.Cu") (net 167))
  (segment (start 138.321626 112.68347) (end 138.327853 112.710758) (width 0.125) (layer "In3.Cu") (net 167))
  (segment (start 136.645825 111.592383) (end 136.639597 111.619673) (width 0.125) (layer "In3.Cu") (net 167))
  (segment (start 136.946886 112.323981) (end 136.974877 112.323981) (width 0.125) (layer "In3.Cu") (net 167))
  (segment (start 138.109917 113.348803) (end 138.468802 112.989917) (width 0.125) (layer "In3.Cu") (net 167))
  (segment (start 137.56214 112.840361) (end 137.549995 112.86558) (width 0.125) (layer "In3.Cu") (net 167))
  (segment (start 137.933141 113.348803) (end 137.955025 113.366255) (width 0.125) (layer "In3.Cu") (net 167))
  (segment (start 139.028724 113.473138) (end 139.016579 113.498357) (width 0.125) (layer "In3.Cu") (net 167))
  (segment (start 138.28669 113.525575) (end 138.269238 113.547459) (width 0.125) (layer "In3.Cu") (net 167))
  (segment (start 138.952022 113.313867) (end 138.977241 113.326012) (width 0.125) (layer "In3.Cu") (net 167))
  (segment (start 138.292029 112.813143) (end 137.933141 113.172026) (width 0.125) (layer "In3.Cu") (net 167))
  (segment (start 138.270143 112.618914) (end 138.292029 112.636367) (width 0.125) (layer "In3.Cu") (net 167))
  (segment (start 138.309481 112.658251) (end 138.321626 112.68347) (width 0.125) (layer "In3.Cu") (net 167))
  (segment (start 137.209496 111.558267) (end 137.231382 111.57572) (width 0.125) (layer "In3.Cu") (net 167))
  (segment (start 136.855042 112.133263) (end 136.842897 112.158482) (width 0.125) (layer "In3.Cu") (net 167))
  (segment (start 136.501493 111.779714) (end 136.489348 111.804933) (width 0.125) (layer "In3.Cu") (net 167))
  (segment (start 138.308574 113.719804) (end 138.333793 113.731949) (width 0.125) (layer "In3.Cu") (net 167))
  (segment (start 137.579592 112.818477) (end 137.56214 112.840361) (width 0.125) (layer "In3.Cu") (net 167))
  (segment (start 136.645825 111.564392) (end 136.645825 111.592383) (width 0.125) (layer "In3.Cu") (net 167))
  (segment (start 138.327853 112.710758) (end 138.327854 112.73875) (width 0.125) (layer "In3.Cu") (net 167))
  (segment (start 138.416363 113.731949) (end 138.441582 113.719804) (width 0.125) (layer "In3.Cu") (net 167))
  (segment (start 138.217635 112.60054) (end 138.244924 112.606769) (width 0.125) (layer "In3.Cu") (net 167))
  (segment (start 138.007533 113.384628) (end 138.035524 113.384628) (width 0.125) (layer "In3.Cu") (net 167))
  (segment (start 137.783586 112.265365) (end 137.808805 112.25322) (width 0.125) (layer "In3.Cu") (net 167))
  (segment (start 137.267207 111.678103) (end 137.260979 111.705393) (width 0.125) (layer "In3.Cu") (net 167))
  (segment (start 136.836668 112.213763) (end 136.842897 112.241052) (width 0.125) (layer "In3.Cu") (net 167))
  (segment (start 136.593337 111.970431) (end 136.621328 111.970431) (width 0.125) (layer "In3.Cu") (net 167))
  (segment (start 137.891375 112.25322) (end 137.916594 112.265365) (width 0.125) (layer "In3.Cu") (net 167))
  (segment (start 137.273146 112.671302) (end 137.300435 112.67753) (width 0.125) (layer "In3.Cu") (net 167))
  (segment (start 137.968077 112.329921) (end 137.974304 112.357209) (width 0.125) (layer "In3.Cu") (net 167))
  (segment (start 137.543766 112.89287) (end 137.543766 112.920861) (width 0.125) (layer "In3.Cu") (net 167))
  (segment (start 136.836668 112.185772) (end 136.836668 112.213763) (width 0.125) (layer "In3.Cu") (net 167))
  (segment (start 136.855042 112.266271) (end 136.872494 112.288156) (width 0.125) (layer "In3.Cu") (net 167))
  (segment (start 138.844233 113.326012) (end 138.869452 113.313867) (width 0.125) (layer "In3.Cu") (net 167))
  (segment (start 137.980244 113.3784) (end 138.007533 113.384628) (width 0.125) (layer "In3.Cu") (net 167))
  (segment (start 139.034951 113.417856) (end 139.034952 113.445848) (width 0.125) (layer "In3.Cu") (net 167))
  (segment (start 132.5 111.4) (end 136.52 111.4) (width 0.125) (layer "In3.Cu") (net 167))
  (segment (start 138.250864 113.627959) (end 138.257093 113.655248) (width 0.125) (layer "In3.Cu") (net 167))
  (segment (start 137.968077 112.412491) (end 137.955932 112.43771) (width 0.125) (layer "In3.Cu") (net 167))
  (segment (start 138.292029 112.636367) (end 138.309481 112.658251) (width 0.125) (layer "In3.Cu") (net 167))
  (segment (start 137.915689 113.19391) (end 137.903544 113.219129) (width 0.125) (layer "In3.Cu") (net 167))
  (segment (start 137.761704 112.282819) (end 137.783586 112.265365) (width 0.125) (layer "In3.Cu") (net 167))
  (segment (start 137.897315 113.246419) (end 137.897315 113.27441) (width 0.125) (layer "In3.Cu") (net 167))
  (segment (start 136.566048 111.964203) (end 136.593337 111.970431) (width 0.125) (layer "In3.Cu") (net 167))
  (segment (start 137.734484 113.012706) (end 137.756368 112.995254) (width 0.125) (layer "In3.Cu") (net 167))
  (segment (start 137.247927 112.659157) (end 137.273146 112.671302) (width 0.125) (layer "In3.Cu") (net 167))
  (segment (start 138.890619 113.633178) (end 138.878474 113.658397) (width 0.125) (layer "In3.Cu") (net 167))
  (segment (start 138.878474 113.740967) (end 138.890619 113.766186) (width 0.125) (layer "In3.Cu") (net 167))
  (segment (start 137.04927 112.288156) (end 137.408155 111.92927) (width 0.125) (layer "In3.Cu") (net 167))
  (segment (start 139.016579 113.365349) (end 139.028724 113.390568) (width 0.125) (layer "In3.Cu") (net 167))
  (segment (start 137.903544 113.219129) (end 137.897315 113.246419) (width 0.125) (layer "In3.Cu") (net 167))
  (segment (start 137.864086 112.246991) (end 137.891375 112.25322) (width 0.125) (layer "In3.Cu") (net 167))
  (segment (start 138.999127 113.343465) (end 139.016579 113.365349) (width 0.125) (layer "In3.Cu") (net 167))
  (segment (start 136.518945 111.934606) (end 136.540829 111.952058) (width 0.125) (layer "In3.Cu") (net 167))
  (segment (start 138.468802 112.989917) (end 138.490684 112.972463) (width 0.125) (layer "In3.Cu") (net 167))
  (segment (start 137.196446 112.594601) (end 137.208591 112.61982) (width 0.125) (layer "In3.Cu") (net 167))
  (segment (start 137.300435 112.67753) (end 137.328426 112.67753) (width 0.125) (layer "In3.Cu") (net 167))
  (segment (start 136.639597 111.537103) (end 136.645825 111.564392) (width 0.125) (layer "In3.Cu") (net 167))
  (segment (start 138.66303 113.0118) (end 138.675175 113.037019) (width 0.125) (layer "In3.Cu") (net 167))
  (segment (start 138.088033 113.366255) (end 138.109917 113.348803) (width 0.125) (layer "In3.Cu") (net 167))
  (segment (start 138.645578 112.989916) (end 138.66303 113.0118) (width 0.125) (layer "In3.Cu") (net 167))
  (segment (start 136.48312 111.860214) (end 136.489348 111.887503) (width 0.125) (layer "In3.Cu") (net 167))
  (segment (start 137.584931 112.106045) (end 137.226043 112.464928) (width 0.125) (layer "In3.Cu") (net 167))
  (segment (start 136.648618 111.964203) (end 136.673837 111.952058) (width 0.125) (layer "In3.Cu") (net 167))
  (segment (start 137.402819 112.641705) (end 137.761704 112.282819) (width 0.125) (layer "In3.Cu") (net 167))
  (segment (start 138.872247 113.685687) (end 138.872247 113.713679) (width 0.125) (layer "In3.Cu") (net 167))
  (segment (start 138.977241 113.326012) (end 138.999127 113.343465) (width 0.125) (layer "In3.Cu") (net 167))
  (segment (start 137.579592 112.995254) (end 137.601476 113.012706) (width 0.125) (layer "In3.Cu") (net 167))
  (segment (start 137.756368 112.995254) (end 138.115253 112.636368) (width 0.125) (layer "In3.Cu") (net 167))
  (segment (start 137.584931 111.929269) (end 137.602383 111.951153) (width 0.125) (layer "In3.Cu") (net 167))
  (segment (start 137.916594 112.265365) (end 137.93848 112.282818) (width 0.125) (layer "In3.Cu") (net 167))
  (segment (start 137.267206 111.650111) (end 137.267207 111.678103) (width 0.125) (layer "In3.Cu") (net 167))
  (segment (start 136.627452 111.511884) (end 136.639597 111.537103) (width 0.125) (layer "In3.Cu") (net 167))
  (segment (start 137.653984 113.031079) (end 137.681975 113.031079) (width 0.125) (layer "In3.Cu") (net 167))
  (segment (start 137.933141 113.172026) (end 137.915689 113.19391) (width 0.125) (layer "In3.Cu") (net 167))
  (segment (start 138.321626 112.76604) (end 138.309481 112.791259) (width 0.125) (layer "In3.Cu") (net 167))
  (segment (start 137.955932 112.43771) (end 137.93848 112.459594) (width 0.125) (layer "In3.Cu") (net 167))
  (segment (start 137.549995 112.86558) (end 137.543766 112.89287) (width 0.125) (layer "In3.Cu") (net 167))
  (segment (start 137.915689 113.326918) (end 137.933141 113.348803) (width 0.125) (layer "In3.Cu") (net 167))
  (segment (start 137.626695 113.024851) (end 137.653984 113.031079) (width 0.125) (layer "In3.Cu") (net 167))
  (segment (start 137.430037 111.911816) (end 137.455256 111.899671) (width 0.125) (layer "In3.Cu") (net 167))
  (segment (start 137.903544 113.301699) (end 137.915689 113.326918) (width 0.125) (layer "In3.Cu") (net 167))
  (segment (start 136.639597 111.619673) (end 136.627452 111.644892) (width 0.125) (layer "In3.Cu") (net 167))
  (segment (start 141.109293 113.458443) (end 141.91585 114.265) (width 0.1) (layer "F.Cu") (net 168))
  (segment (start 123.5 111.9) (end 124 111.4) (width 0.1) (layer "F.Cu") (net 168))
  (segment (start 124 110.4) (end 124.393 110.007) (width 0.1) (layer "F.Cu") (net 168))
  (segment (start 124 111.4) (end 124 110.4) (width 0.1) (layer "F.Cu") (net 168))
  (segment (start 129.52 110.007) (end 130.127 109.4) (width 0.1) (layer "F.Cu") (net 168))
  (segment (start 142.645 114.265) (end 141.91585 114.265) (width 0.1) (layer "F.Cu") (net 168))
  (segment (start 130.127 109.4) (end 132.5 109.4) (width 0.1) (layer "F.Cu") (net 168))
  (segment (start 124.393 110.007) (end 129.52 110.007) (width 0.1) (layer "F.Cu") (net 168))
  (via (at 141.109293 113.458443) (size 0.55) (drill 0.15) (layers "F.Cu" "B.Cu") (net 168))
  (via (at 132.5 109.4) (size 0.55) (drill 0.15) (layers "F.Cu" "B.Cu") (net 168))
  (segment (start 137.780477 110.68727) (end 137.802361 110.704722) (width 0.125) (layer "In3.Cu") (net 168))
  (segment (start 137.780477 110.510494) (end 138.161345 110.129628) (width 0.125) (layer "In3.Cu") (net 168))
  (segment (start 137.50132 110.369546) (end 137.529311 110.369546) (width 0.125) (layer "In3.Cu") (net 168))
  (segment (start 138.550719 110.408784) (end 138.544491 110.436074) (width 0.125) (layer "In3.Cu") (net 168))
  (segment (start 137.120483 110.009769) (end 137.147772 110.015997) (width 0.125) (layer "In3.Cu") (net 168))
  (segment (start 138.412849 110.761998) (end 141.10085 113.45) (width 0.125) (layer "In3.Cu") (net 168))
  (segment (start 137.07338 109.803395) (end 137.055928 109.82528) (width 0.125) (layer "In3.Cu") (net 168))
  (segment (start 137.21125 109.626958) (end 137.205022 109.654248) (width 0.125) (layer "In3.Cu") (net 168))
  (segment (start 137.409476 110.311837) (end 137.426928 110.333721) (width 0.125) (layer "In3.Cu") (net 168))
  (segment (start 138.086952 109.917027) (end 138.114242 109.923255) (width 0.125) (layer "In3.Cu") (net 168))
  (segment (start 138.514894 110.483177) (end 138.41285 110.585222) (width 0.125) (layer "In3.Cu") (net 168))
  (segment (start 138.178797 109.974736) (end 138.190942 109.999955) (width 0.125) (layer "In3.Cu") (net 168))
  (segment (start 137.037554 109.877788) (end 137.037554 109.905779) (width 0.125) (layer "In3.Cu") (net 168))
  (segment (start 137.250156 109.980172) (end 137.631022 109.599305) (width 0.125) (layer "In3.Cu") (net 168))
  (segment (start 137.391103 110.231337) (end 137.391103 110.259328) (width 0.125) (layer "In3.Cu") (net 168))
  (segment (start 137.426928 110.156945) (end 137.807796 109.776079) (width 0.125) (layer "In3.Cu") (net 168))
  (segment (start 137.448812 110.351173) (end 137.474031 110.363318) (width 0.125) (layer "In3.Cu") (net 168))
  (segment (start 138.360002 110.288949) (end 138.385221 110.276804) (width 0.125) (layer "In3.Cu") (net 168))
  (segment (start 138.412511 110.270577) (end 138.440501 110.270576) (width 0.125) (layer "In3.Cu") (net 168))
  (segment (start 138.532346 110.461293) (end 138.514894 110.483177) (width 0.125) (layer "In3.Cu") (net 168))
  (segment (start 137.409476 110.178829) (end 137.397331 110.204048) (width 0.125) (layer "In3.Cu") (net 168))
  (segment (start 137.91015 110.716867) (end 137.935369 110.704722) (width 0.125) (layer "In3.Cu") (net 168))
  (segment (start 137.837393 109.646406) (end 137.843622 109.673696) (width 0.125) (layer "In3.Cu") (net 168))
  (segment (start 137.82758 110.716867) (end 137.854869 110.723095) (width 0.125) (layer "In3.Cu") (net 168))
  (segment (start 137.854869 110.723095) (end 137.88286 110.723095) (width 0.125) (layer "In3.Cu") (net 168))
  (segment (start 137.055928 109.82528) (end 137.043783 109.850499) (width 0.125) (layer "In3.Cu") (net 168))
  (segment (start 137.175425 109.701351) (end 137.07338 109.803395) (width 0.125) (layer "In3.Cu") (net 168))
  (segment (start 137.652904 109.581851) (end 137.678123 109.569706) (width 0.125) (layer "In3.Cu") (net 168))
  (segment (start 138.058962 109.917028) (end 138.086952 109.917027) (width 0.125) (layer "In3.Cu") (net 168))
  (segment (start 137.785912 109.581851) (end 137.807796 109.599303) (width 0.125) (layer "In3.Cu") (net 168))
  (segment (start 137.095264 109.997624) (end 137.120483 110.009769) (width 0.125) (layer "In3.Cu") (net 168))
  (segment (start 138.383252 110.632325) (end 138.377023 110.659614) (width 0.125) (layer "In3.Cu") (net 168))
  (segment (start 137.05085 109.4) (end 137.175425 109.524575) (width 0.125) (layer "In3.Cu") (net 168))
  (segment (start 137.397331 110.286618) (end 137.409476 110.311837) (width 0.125) (layer "In3.Cu") (net 168))
  (segment (start 137.391103 110.259328) (end 137.397331 110.286618) (width 0.125) (layer "In3.Cu") (net 168))
  (segment (start 137.837393 109.728976) (end 137.825248 109.754195) (width 0.125) (layer "In3.Cu") (net 168))
  (segment (start 138.395397 110.607106) (end 138.383252 110.632325) (width 0.125) (layer "In3.Cu") (net 168))
  (segment (start 137.175425 109.524575) (end 137.192877 109.546459) (width 0.125) (layer "In3.Cu") (net 168))
  (segment (start 138.114242 109.923255) (end 138.139461 109.9354) (width 0.125) (layer "In3.Cu") (net 168))
  (segment (start 137.75088 110.557597) (end 137.744652 110.584886) (width 0.125) (layer "In3.Cu") (net 168))
  (segment (start 137.763025 110.532378) (end 137.75088 110.557597) (width 0.125) (layer "In3.Cu") (net 168))
  (segment (start 138.190942 110.082525) (end 138.178797 110.107744) (width 0.125) (layer "In3.Cu") (net 168))
  (segment (start 137.205022 109.571678) (end 137.21125 109.598967) (width 0.125) (layer "In3.Cu") (net 168))
  (segment (start 138.49301 110.288949) (end 138.514894 110.306401) (width 0.125) (layer "In3.Cu") (net 168))
  (segment (start 137.07338 109.980172) (end 137.095264 109.997624) (width 0.125) (layer "In3.Cu") (net 168))
  (segment (start 137.529311 110.369546) (end 137.556601 110.363318) (width 0.125) (layer "In3.Cu") (net 168))
  (segment (start 137.780477 110.510494) (end 137.763025 110.532378) (width 0.125) (layer "In3.Cu") (net 168))
  (segment (start 137.192877 109.679467) (end 137.175425 109.701351) (width 0.125) (layer "In3.Cu") (net 168))
  (segment (start 141.10085 113.45) (end 141.109293 113.458443) (width 0.125) (layer "In3.Cu") (net 168))
  (segment (start 138.377024 110.687606) (end 138.383253 110.714895) (width 0.125) (layer "In3.Cu") (net 168))
  (segment (start 137.397331 110.204048) (end 137.391103 110.231337) (width 0.125) (layer "In3.Cu") (net 168))
  (segment (start 138.383253 110.714895) (end 138.395397 110.740114) (width 0.125) (layer "In3.Cu") (net 168))
  (segment (start 137.760693 109.569706) (end 137.785912 109.581851) (width 0.125) (layer "In3.Cu") (net 168))
  (segment (start 138.514894 110.306401) (end 138.532346 110.328285) (width 0.125) (layer "In3.Cu") (net 168))
  (segment (start 137.426928 110.333721) (end 137.448812 110.351173) (width 0.125) (layer "In3.Cu") (net 168))
  (segment (start 137.603704 110.333721) (end 137.984571 109.952854) (width 0.125) (layer "In3.Cu") (net 168))
  (segment (start 137.744652 110.584886) (end 137.744652 110.612877) (width 0.125) (layer "In3.Cu") (net 168))
  (segment (start 137.678123 109.569706) (end 137.705413 109.563479) (width 0.125) (layer "In3.Cu") (net 168))
  (segment (start 137.426928 110.156945) (end 137.409476 110.178829) (width 0.125) (layer "In3.Cu") (net 168))
  (segment (start 138.197171 110.027245) (end 138.19717 110.055235) (width 0.125) (layer "In3.Cu") (net 168))
  (segment (start 137.843622 109.673696) (end 137.843621 109.701686) (width 0.125) (layer "In3.Cu") (net 168))
  (segment (start 138.006453 109.9354) (end 138.031672 109.923255) (width 0.125) (layer "In3.Cu") (net 168))
  (segment (start 137.055928 109.958288) (end 137.07338 109.980172) (width 0.125) (layer "In3.Cu") (net 168))
  (segment (start 137.556601 110.363318) (end 137.58182 110.351173) (width 0.125) (layer "In3.Cu") (net 168))
  (segment (start 138.161345 109.952852) (end 138.178797 109.974736) (width 0.125) (layer "In3.Cu") (net 168))
  (segment (start 137.744652 110.612877) (end 137.75088 110.640167) (width 0.125) (layer "In3.Cu") (net 168))
  (segment (start 137.984571 109.952854) (end 138.006453 109.9354) (width 0.125) (layer "In3.Cu") (net 168))
  (segment (start 138.19717 110.055235) (end 138.190942 110.082525) (width 0.125) (layer "In3.Cu") (net 168))
  (segment (start 137.228272 109.997624) (end 137.250156 109.980172) (width 0.125) (layer "In3.Cu") (net 168))
  (segment (start 137.75088 110.640167) (end 137.763025 110.665386) (width 0.125) (layer "In3.Cu") (net 168))
  (segment (start 138.532346 110.328285) (end 138.544491 110.353504) (width 0.125) (layer "In3.Cu") (net 168))
  (segment (start 138.139461 109.9354) (end 138.161345 109.952852) (width 0.125) (layer "In3.Cu") (net 168))
  (segment (start 137.147772 110.015997) (end 137.175763 110.015997) (width 0.125) (layer "In3.Cu") (net 168))
  (segment (start 138.55072 110.380794) (end 138.550719 110.408784) (width 0.125) (layer "In3.Cu") (net 168))
  (segment (start 137.631022 109.599305) (end 137.652904 109.581851) (width 0.125) (layer "In3.Cu") (net 168))
  (segment (start 137.21125 109.598967) (end 137.21125 109.626958) (width 0.125) (layer "In3.Cu") (net 168))
  (segment (start 137.825248 109.754195) (end 137.807796 109.776079) (width 0.125) (layer "In3.Cu") (net 168))
  (segment (start 137.733403 109.563478) (end 137.760693 109.569706) (width 0.125) (layer "In3.Cu") (net 168))
  (segment (start 137.037554 109.905779) (end 137.043783 109.933068) (width 0.125) (layer "In3.Cu") (net 168))
  (segment (start 138.467791 110.276804) (end 138.49301 110.288949) (width 0.125) (layer "In3.Cu") (net 168))
  (segment (start 137.205022 109.654248) (end 137.192877 109.679467) (width 0.125) (layer "In3.Cu") (net 168))
  (segment (start 137.763025 110.665386) (end 137.780477 110.68727) (width 0.125) (layer "In3.Cu") (net 168))
  (segment (start 137.203053 110.009769) (end 137.228272 109.997624) (width 0.125) (layer "In3.Cu") (net 168))
  (segment (start 137.802361 110.704722) (end 137.82758 110.716867) (width 0.125) (layer "In3.Cu") (net 168))
  (segment (start 137.192877 109.546459) (end 137.205022 109.571678) (width 0.125) (layer "In3.Cu") (net 168))
  (segment (start 137.843621 109.701686) (end 137.837393 109.728976) (width 0.125) (layer "In3.Cu") (net 168))
  (segment (start 137.58182 110.351173) (end 137.603704 110.333721) (width 0.125) (layer "In3.Cu") (net 168))
  (segment (start 138.544491 110.353504) (end 138.55072 110.380794) (width 0.125) (layer "In3.Cu") (net 168))
  (segment (start 138.395397 110.740114) (end 138.412849 110.761998) (width 0.125) (layer "In3.Cu") (net 168))
  (segment (start 137.474031 110.363318) (end 137.50132 110.369546) (width 0.125) (layer "In3.Cu") (net 168))
  (segment (start 138.031672 109.923255) (end 138.058962 109.917028) (width 0.125) (layer "In3.Cu") (net 168))
  (segment (start 138.190942 109.999955) (end 138.197171 110.027245) (width 0.125) (layer "In3.Cu") (net 168))
  (segment (start 137.705413 109.563479) (end 137.733403 109.563478) (width 0.125) (layer "In3.Cu") (net 168))
  (segment (start 138.385221 110.276804) (end 138.412511 110.270577) (width 0.125) (layer "In3.Cu") (net 168))
  (segment (start 137.043783 109.850499) (end 137.037554 109.877788) (width 0.125) (layer "In3.Cu") (net 168))
  (segment (start 137.935369 110.704722) (end 137.957253 110.68727) (width 0.125) (layer "In3.Cu") (net 168))
  (segment (start 137.175763 110.015997) (end 137.203053 110.009769) (width 0.125) (layer "In3.Cu") (net 168))
  (segment (start 132.5 109.4) (end 137.05085 109.4) (width 0.125) (layer "In3.Cu") (net 168))
  (segment (start 137.807796 109.599303) (end 137.825248 109.621187) (width 0.125) (layer "In3.Cu") (net 168))
  (segment (start 138.41285 110.585222) (end 138.395397 110.607106) (width 0.125) (layer "In3.Cu") (net 168))
  (segment (start 138.178797 110.107744) (end 138.161345 110.129628) (width 0.125) (layer "In3.Cu") (net 168))
  (segment (start 137.825248 109.621187) (end 137.837393 109.646406) (width 0.125) (layer "In3.Cu") (net 168))
  (segment (start 138.33812 110.306403) (end 138.360002 110.288949) (width 0.125) (layer "In3.Cu") (net 168))
  (segment (start 138.440501 110.270576) (end 138.467791 110.276804) (width 0.125) (layer "In3.Cu") (net 168))
  (segment (start 137.88286 110.723095) (end 137.91015 110.716867) (width 0.125) (layer "In3.Cu") (net 168))
  (segment (start 138.377023 110.659614) (end 138.377024 110.687606) (width 0.125) (layer "In3.Cu") (net 168))
  (segment (start 137.957253 110.68727) (end 138.33812 110.306403) (width 0.125) (layer "In3.Cu") (net 168))
  (segment (start 138.544491 110.436074) (end 138.532346 110.461293) (width 0.125) (layer "In3.Cu") (net 168))
  (segment (start 137.043783 109.933068) (end 137.055928 109.958288) (width 0.125) (layer "In3.Cu") (net 168))
  (segment (start 129.48 112.4) (end 128.48 111.4) (width 0.1) (layer "F.Cu") (net 169))
  (segment (start 124.5 111.9) (end 125 111.4) (width 0.1) (layer "F.Cu") (net 169))
  (segment (start 129.48 112.4) (end 132.5 112.4) (width 0.1) (layer "F.Cu") (net 169))
  (segment (start 128.48 111.4) (end 125 111.4) (width 0.1) (layer "F.Cu") (net 169))
  (segment (start 142.645 116.215) (end 140.044658 116.215) (width 0.1) (layer "F.Cu") (net 169))
  (segment (start 140.044658 116.215) (end 139.944648 116.11499) (width 0.1) (layer "F.Cu") (net 169))
  (via (at 139.944648 116.11499) (size 0.55) (drill 0.15) (layers "F.Cu" "B.Cu") (net 169))
  (via (at 132.5 112.4) (size 0.55) (drill 0.15) (layers "F.Cu" "B.Cu") (net 169))
  (segment (start 135.025 112.145039) (end 135.025 112.654961) (width 0.125) (layer "In3.Cu") (net 169))
  (segment (start 133.122184 112.776826) (end 133.15 112.779961) (width 0.125) (layer "In3.Cu") (net 169))
  (segment (start 133.762621 112.709196) (end 133.771865 112.682776) (width 0.125) (layer "In3.Cu") (net 169))
  (segment (start 135.525 112.145039) (end 135.525 112.275) (width 0.125) (layer "In3.Cu") (net 169))
  (segment (start 134.247728 112.732897) (end 134.262621 112.709196) (width 0.125) (layer "In3.Cu") (net 169))
  (segment (start 133.262621 112.709196) (end 133.271865 112.682776) (width 0.125) (layer "In3.Cu") (net 169))
  (segment (start 134.778134 112.117224) (end 134.787378 112.090804) (width 0.125) (layer "In3.Cu") (net 169))
  (segment (start 133.537378 112.709196) (end 133.552271 112.732897) (width 0.125) (layer "In3.Cu") (net 169))
  (segment (start 134.052271 112.732897) (end 134.072063 112.752689) (width 0.125) (layer "In3.Cu") (net 169))
  (segment (start 134.954235 112.032418) (end 134.977936 112.047311) (width 0.125) (layer "In3.Cu") (net 169))
  (segment (start 133.872184 112.023174) (end 133.9 112.020039) (width 0.125) (layer "In3.Cu") (net 169))
  (segment (start 133.927815 112.023174) (end 133.954235 112.032418) (width 0.125) (layer "In3.Cu") (net 169))
  (segment (start 134.521865 112.117224) (end 134.525 112.145039) (width 0.125) (layer "In3.Cu") (net 169))
  (segment (start 135.497728 112.067103) (end 135.512621 112.090804) (width 0.125) (layer "In3.Cu") (net 169))
  (segment (start 133.595764 112.767582) (end 133.622184 112.776826) (width 0.125) (layer "In3.Cu") (net 169))
  (segment (start 134.227936 112.752689) (end 134.247728 112.732897) (width 0.125) (layer "In3.Cu") (net 169))
  (segment (start 132.954235 112.412378) (end 132.977936 112.427271) (width 0.125) (layer "In3.Cu") (net 169))
  (segment (start 134.552271 112.732897) (end 134.572063 112.752689) (width 0.125) (layer "In3.Cu") (net 169))
  (segment (start 135.247728 112.732897) (end 135.262621 112.709196) (width 0.125) (layer "In3.Cu") (net 169))
  (segment (start 134.122184 112.776826) (end 134.15 112.779961) (width 0.125) (layer "In3.Cu") (net 169))
  (segment (start 133.622184 112.776826) (end 133.65 112.779961) (width 0.125) (layer "In3.Cu") (net 169))
  (segment (start 133.345764 112.032418) (end 133.372184 112.023174) (width 0.125) (layer "In3.Cu") (net 169))
  (segment (start 133.572063 112.752689) (end 133.595764 112.767582) (width 0.125) (layer "In3.Cu") (net 169))
  (segment (start 134.977936 112.047311) (end 134.997728 112.067103) (width 0.125) (layer "In3.Cu") (net 169))
  (segment (start 133.072063 112.752689) (end 133.095764 112.767582) (width 0.125) (layer "In3.Cu") (net 169))
  (segment (start 133.322063 112.047311) (end 133.345764 112.032418) (width 0.125) (layer "In3.Cu") (net 169))
  (segment (start 135.302271 112.067103) (end 135.322063 112.047311) (width 0.125) (layer "In3.Cu") (net 169))
  (segment (start 134.177815 112.776826) (end 134.204235 112.767582) (width 0.125) (layer "In3.Cu") (net 169))
  (segment (start 133.65 112.779961) (end 133.677815 112.776826) (width 0.125) (layer "In3.Cu") (net 169))
  (segment (start 133.525 112.145039) (end 133.525 112.654961) (width 0.125) (layer "In3.Cu") (net 169))
  (segment (start 133.271865 112.682776) (end 133.275 112.654961) (width 0.125) (layer "In3.Cu") (net 169))
  (segment (start 133.677815 112.776826) (end 133.704235 112.767582) (width 0.125) (layer "In3.Cu") (net 169))
  (segment (start 134.4 112.020039) (end 134.427815 112.023174) (width 0.125) (layer "In3.Cu") (net 169))
  (segment (start 135.4 112.020039) (end 135.427815 112.023174) (width 0.125) (layer "In3.Cu") (net 169))
  (segment (start 134.454235 112.032418) (end 134.477936 112.047311) (width 0.125) (layer "In3.Cu") (net 169))
  (segment (start 134.537378 112.709196) (end 134.552271 112.732897) (width 0.125) (layer "In3.Cu") (net 169))
  (segment (start 133.528134 112.682776) (end 133.537378 112.709196) (width 0.125) (layer "In3.Cu") (net 169))
  (segment (start 134.727936 112.752689) (end 134.747728 112.732897) (width 0.125) (layer "In3.Cu") (net 169))
  (segment (start 134.095764 112.767582) (end 134.122184 112.776826) (width 0.125) (layer "In3.Cu") (net 169))
  (segment (start 133.037378 112.709196) (end 133.052271 112.732897) (width 0.125) (layer "In3.Cu") (net 169))
  (segment (start 133.521865 112.117224) (end 133.525 112.145039) (width 0.125) (layer "In3.Cu") (net 169))
  (segment (start 133.427815 112.023174) (end 133.454235 112.032418) (width 0.125) (layer "In3.Cu") (net 169))
  (segment (start 135.622184 112.396866) (end 135.65 112.4) (width 0.125) (layer "In3.Cu") (net 169))
  (segment (start 135.572063 112.372729) (end 135.595764 112.387622) (width 0.125) (layer "In3.Cu") (net 169))
  (segment (start 133.771865 112.682776) (end 133.775 112.654961) (width 0.125) (layer "In3.Cu") (net 169))
  (segment (start 132.5 112.4) (end 132.9 112.4) (width 0.125) (layer "In3.Cu") (net 169))
  (segment (start 134.372184 112.023174) (end 134.4 112.020039) (width 0.125) (layer "In3.Cu") (net 169))
  (segment (start 133.095764 112.767582) (end 133.122184 112.776826) (width 0.125) (layer "In3.Cu") (net 169))
  (segment (start 133.9 112.020039) (end 133.927815 112.023174) (width 0.125) (layer "In3.Cu") (net 169))
  (segment (start 135.528134 112.302816) (end 135.537378 112.329236) (width 0.125) (layer "In3.Cu") (net 169))
  (segment (start 132.927815 112.403134) (end 132.954235 112.412378) (width 0.125) (layer "In3.Cu") (net 169))
  (segment (start 133.802271 112.067103) (end 133.822063 112.047311) (width 0.125) (layer "In3.Cu") (net 169))
  (segment (start 136.229658 112.4) (end 139.944648 116.11499) (width 0.125) (layer "In3.Cu") (net 169))
  (segment (start 133.778134 112.117224) (end 133.787378 112.090804) (width 0.125) (layer "In3.Cu") (net 169))
  (segment (start 133.525 112.654961) (end 133.528134 112.682776) (width 0.125) (layer "In3.Cu") (net 169))
  (segment (start 134.9 112.020039) (end 134.927815 112.023174) (width 0.125) (layer "In3.Cu") (net 169))
  (segment (start 134.762621 112.709196) (end 134.771865 112.682776) (width 0.125) (layer "In3.Cu") (net 169))
  (segment (start 135.521865 112.117224) (end 135.525 112.145039) (width 0.125) (layer "In3.Cu") (net 169))
  (segment (start 134.775 112.145039) (end 134.778134 112.117224) (width 0.125) (layer "In3.Cu") (net 169))
  (segment (start 134.15 112.779961) (end 134.177815 112.776826) (width 0.125) (layer "In3.Cu") (net 169))
  (segment (start 133.227936 112.752689) (end 133.247728 112.732897) (width 0.125) (layer "In3.Cu") (net 169))
  (segment (start 133.302271 112.067103) (end 133.322063 112.047311) (width 0.125) (layer "In3.Cu") (net 169))
  (segment (start 134.021865 112.117224) (end 134.025 112.145039) (width 0.125) (layer "In3.Cu") (net 169))
  (segment (start 135.275 112.654961) (end 135.275 112.145039) (width 0.125) (layer "In3.Cu") (net 169))
  (segment (start 135.537378 112.329236) (end 135.552271 112.352937) (width 0.125) (layer "In3.Cu") (net 169))
  (segment (start 135.275 112.145039) (end 135.278134 112.117224) (width 0.125) (layer "In3.Cu") (net 169))
  (segment (start 133.552271 112.732897) (end 133.572063 112.752689) (width 0.125) (layer "In3.Cu") (net 169))
  (segment (start 133.477936 112.047311) (end 133.497728 112.067103) (width 0.125) (layer "In3.Cu") (net 169))
  (segment (start 134.787378 112.090804) (end 134.802271 112.067103) (width 0.125) (layer "In3.Cu") (net 169))
  (segment (start 135.525 112.275) (end 135.528134 112.302816) (width 0.125) (layer "In3.Cu") (net 169))
  (segment (start 134.012621 112.090804) (end 134.021865 112.117224) (width 0.125) (layer "In3.Cu") (net 169))
  (segment (start 134.477936 112.047311) (end 134.497728 112.067103) (width 0.125) (layer "In3.Cu") (net 169))
  (segment (start 134.271865 112.682776) (end 134.275 112.654961) (width 0.125) (layer "In3.Cu") (net 169))
  (segment (start 133.012621 112.470764) (end 133.021865 112.497184) (width 0.125) (layer "In3.Cu") (net 169))
  (segment (start 133.954235 112.032418) (end 133.977936 112.047311) (width 0.125) (layer "In3.Cu") (net 169))
  (segment (start 134.595764 112.767582) (end 134.622184 112.776826) (width 0.125) (layer "In3.Cu") (net 169))
  (segment (start 135.204235 112.767582) (end 135.227936 112.752689) (width 0.125) (layer "In3.Cu") (net 169))
  (segment (start 135.477936 112.047311) (end 135.497728 112.067103) (width 0.125) (layer "In3.Cu") (net 169))
  (segment (start 135.177815 112.776826) (end 135.204235 112.767582) (width 0.125) (layer "In3.Cu") (net 169))
  (segment (start 135.322063 112.047311) (end 135.345764 112.032418) (width 0.125) (layer "In3.Cu") (net 169))
  (segment (start 134.287378 112.090804) (end 134.302271 112.067103) (width 0.125) (layer "In3.Cu") (net 169))
  (segment (start 133.845764 112.032418) (end 133.872184 112.023174) (width 0.125) (layer "In3.Cu") (net 169))
  (segment (start 134.525 112.654961) (end 134.528134 112.682776) (width 0.125) (layer "In3.Cu") (net 169))
  (segment (start 135.028134 112.682776) (end 135.037378 112.709196) (width 0.125) (layer "In3.Cu") (net 169))
  (segment (start 134.275 112.654961) (end 134.275 112.145039) (width 0.125) (layer "In3.Cu") (net 169))
  (segment (start 133.787378 112.090804) (end 133.802271 112.067103) (width 0.125) (layer "In3.Cu") (net 169))
  (segment (start 133.512621 112.090804) (end 133.521865 112.117224) (width 0.125) (layer "In3.Cu") (net 169))
  (segment (start 134.525 112.145039) (end 134.525 112.654961) (width 0.125) (layer "In3.Cu") (net 169))
  (segment (start 135.227936 112.752689) (end 135.247728 112.732897) (width 0.125) (layer "In3.Cu") (net 169))
  (segment (start 133.704235 112.767582) (end 133.727936 112.752689) (width 0.125) (layer "In3.Cu") (net 169))
  (segment (start 133.025 112.654961) (end 133.028134 112.682776) (width 0.125) (layer "In3.Cu") (net 169))
  (segment (start 134.997728 112.067103) (end 135.012621 112.090804) (width 0.125) (layer "In3.Cu") (net 169))
  (segment (start 133.727936 112.752689) (end 133.747728 112.732897) (width 0.125) (layer "In3.Cu") (net 169))
  (segment (start 134.025 112.654961) (end 134.028134 112.682776) (width 0.125) (layer "In3.Cu") (net 169))
  (segment (start 134.872184 112.023174) (end 134.9 112.020039) (width 0.125) (layer "In3.Cu") (net 169))
  (segment (start 134.747728 112.732897) (end 134.762621 112.709196) (width 0.125) (layer "In3.Cu") (net 169))
  (segment (start 133.822063 112.047311) (end 133.845764 112.032418) (width 0.125) (layer "In3.Cu") (net 169))
  (segment (start 135.012621 112.090804) (end 135.021865 112.117224) (width 0.125) (layer "In3.Cu") (net 169))
  (segment (start 135.271865 112.682776) (end 135.275 112.654961) (width 0.125) (layer "In3.Cu") (net 169))
  (segment (start 134.704235 112.767582) (end 134.727936 112.752689) (width 0.125) (layer "In3.Cu") (net 169))
  (segment (start 133.052271 112.732897) (end 133.072063 112.752689) (width 0.125) (layer "In3.Cu") (net 169))
  (segment (start 133.021865 112.497184) (end 133.025 112.525) (width 0.125) (layer "In3.Cu") (net 169))
  (segment (start 134.771865 112.682776) (end 134.775 112.654961) (width 0.125) (layer "In3.Cu") (net 169))
  (segment (start 134.204235 112.767582) (end 134.227936 112.752689) (width 0.125) (layer "In3.Cu") (net 169))
  (segment (start 135.122184 112.776826) (end 135.15 112.779961) (width 0.125) (layer "In3.Cu") (net 169))
  (segment (start 134.262621 112.709196) (end 134.271865 112.682776) (width 0.125) (layer "In3.Cu") (net 169))
  (segment (start 135.595764 112.387622) (end 135.622184 112.396866) (width 0.125) (layer "In3.Cu") (net 169))
  (segment (start 134.622184 112.776826) (end 134.65 112.779961) (width 0.125) (layer "In3.Cu") (net 169))
  (segment (start 135.037378 112.709196) (end 135.052271 112.732897) (width 0.125) (layer "In3.Cu") (net 169))
  (segment (start 133.997728 112.067103) (end 134.012621 112.090804) (width 0.125) (layer "In3.Cu") (net 169))
  (segment (start 133.4 112.020039) (end 133.427815 112.023174) (width 0.125) (layer "In3.Cu") (net 169))
  (segment (start 135.287378 112.090804) (end 135.302271 112.067103) (width 0.125) (layer "In3.Cu") (net 169))
  (segment (start 133.775 112.145039) (end 133.778134 112.117224) (width 0.125) (layer "In3.Cu") (net 169))
  (segment (start 134.845764 112.032418) (end 134.872184 112.023174) (width 0.125) (layer "In3.Cu") (net 169))
  (segment (start 134.028134 112.682776) (end 134.037378 112.709196) (width 0.125) (layer "In3.Cu") (net 169))
  (segment (start 133.275 112.145039) (end 133.278134 112.117224) (width 0.125) (layer "In3.Cu") (net 169))
  (segment (start 132.997728 112.447063) (end 133.012621 112.470764) (width 0.125) (layer "In3.Cu") (net 169))
  (segment (start 135.345764 112.032418) (end 135.372184 112.023174) (width 0.125) (layer "In3.Cu") (net 169))
  (segment (start 134.927815 112.023174) (end 134.954235 112.032418) (width 0.125) (layer "In3.Cu") (net 169))
  (segment (start 134.302271 112.067103) (end 134.322063 112.047311) (width 0.125) (layer "In3.Cu") (net 169))
  (segment (start 133.775 112.654961) (end 133.775 112.145039) (width 0.125) (layer "In3.Cu") (net 169))
  (segment (start 134.037378 112.709196) (end 134.052271 112.732897) (width 0.125) (layer "In3.Cu") (net 169))
  (segment (start 133.025 112.525) (end 133.025 112.654961) (width 0.125) (layer "In3.Cu") (net 169))
  (segment (start 133.977936 112.047311) (end 133.997728 112.067103) (width 0.125) (layer "In3.Cu") (net 169))
  (segment (start 133.497728 112.067103) (end 133.512621 112.090804) (width 0.125) (layer "In3.Cu") (net 169))
  (segment (start 133.275 112.654961) (end 133.275 112.145039) (width 0.125) (layer "In3.Cu") (net 169))
  (segment (start 135.278134 112.117224) (end 135.287378 112.090804) (width 0.125) (layer "In3.Cu") (net 169))
  (segment (start 135.552271 112.352937) (end 135.572063 112.372729) (width 0.125) (layer "In3.Cu") (net 169))
  (segment (start 134.677815 112.776826) (end 134.704235 112.767582) (width 0.125) (layer "In3.Cu") (net 169))
  (segment (start 135.072063 112.752689) (end 135.095764 112.767582) (width 0.125) (layer "In3.Cu") (net 169))
  (segment (start 134.65 112.779961) (end 134.677815 112.776826) (width 0.125) (layer "In3.Cu") (net 169))
  (segment (start 135.427815 112.023174) (end 135.454235 112.032418) (width 0.125) (layer "In3.Cu") (net 169))
  (segment (start 135.65 112.4) (end 136.229658 112.4) (width 0.125) (layer "In3.Cu") (net 169))
  (segment (start 134.025 112.145039) (end 134.025 112.654961) (width 0.125) (layer "In3.Cu") (net 169))
  (segment (start 134.822063 112.047311) (end 134.845764 112.032418) (width 0.125) (layer "In3.Cu") (net 169))
  (segment (start 134.345764 112.032418) (end 134.372184 112.023174) (width 0.125) (layer "In3.Cu") (net 169))
  (segment (start 135.025 112.654961) (end 135.028134 112.682776) (width 0.125) (layer "In3.Cu") (net 169))
  (segment (start 132.977936 112.427271) (end 132.997728 112.447063) (width 0.125) (layer "In3.Cu") (net 169))
  (segment (start 134.275 112.145039) (end 134.278134 112.117224) (width 0.125) (layer "In3.Cu") (net 169))
  (segment (start 133.372184 112.023174) (end 133.4 112.020039) (width 0.125) (layer "In3.Cu") (net 169))
  (segment (start 135.454235 112.032418) (end 135.477936 112.047311) (width 0.125) (layer "In3.Cu") (net 169))
  (segment (start 135.512621 112.090804) (end 135.521865 112.117224) (width 0.125) (layer "In3.Cu") (net 169))
  (segment (start 133.204235 112.767582) (end 133.227936 112.752689) (width 0.125) (layer "In3.Cu") (net 169))
  (segment (start 134.528134 112.682776) (end 134.537378 112.709196) (width 0.125) (layer "In3.Cu") (net 169))
  (segment (start 135.052271 112.732897) (end 135.072063 112.752689) (width 0.125) (layer "In3.Cu") (net 169))
  (segment (start 133.287378 112.090804) (end 133.302271 112.067103) (width 0.125) (layer "In3.Cu") (net 169))
  (segment (start 134.072063 112.752689) (end 134.095764 112.767582) (width 0.125) (layer "In3.Cu") (net 169))
  (segment (start 135.262621 112.709196) (end 135.271865 112.682776) (width 0.125) (layer "In3.Cu") (net 169))
  (segment (start 133.454235 112.032418) (end 133.477936 112.047311) (width 0.125) (layer "In3.Cu") (net 169))
  (segment (start 132.9 112.4) (end 132.927815 112.403134) (width 0.125) (layer "In3.Cu") (net 169))
  (segment (start 135.372184 112.023174) (end 135.4 112.020039) (width 0.125) (layer "In3.Cu") (net 169))
  (segment (start 135.15 112.779961) (end 135.177815 112.776826) (width 0.125) (layer "In3.Cu") (net 169))
  (segment (start 133.278134 112.117224) (end 133.287378 112.090804) (width 0.125) (layer "In3.Cu") (net 169))
  (segment (start 134.775 112.654961) (end 134.775 112.145039) (width 0.125) (layer "In3.Cu") (net 169))
  (segment (start 134.572063 112.752689) (end 134.595764 112.767582) (width 0.125) (layer "In3.Cu") (net 169))
  (segment (start 133.15 112.779961) (end 133.177815 112.776826) (width 0.125) (layer "In3.Cu") (net 169))
  (segment (start 134.497728 112.067103) (end 134.512621 112.090804) (width 0.125) (layer "In3.Cu") (net 169))
  (segment (start 135.021865 112.117224) (end 135.025 112.145039) (width 0.125) (layer "In3.Cu") (net 169))
  (segment (start 133.177815 112.776826) (end 133.204235 112.767582) (width 0.125) (layer "In3.Cu") (net 169))
  (segment (start 135.095764 112.767582) (end 135.122184 112.776826) (width 0.125) (layer "In3.Cu") (net 169))
  (segment (start 133.747728 112.732897) (end 133.762621 112.709196) (width 0.125) (layer "In3.Cu") (net 169))
  (segment (start 134.322063 112.047311) (end 134.345764 112.032418) (width 0.125) (layer "In3.Cu") (net 169))
  (segment (start 134.278134 112.117224) (end 134.287378 112.090804) (width 0.125) (layer "In3.Cu") (net 169))
  (segment (start 133.028134 112.682776) (end 133.037378 112.709196) (width 0.125) (layer "In3.Cu") (net 169))
  (segment (start 134.427815 112.023174) (end 134.454235 112.032418) (width 0.125) (layer "In3.Cu") (net 169))
  (segment (start 134.802271 112.067103) (end 134.822063 112.047311) (width 0.125) (layer "In3.Cu") (net 169))
  (segment (start 134.512621 112.090804) (end 134.521865 112.117224) (width 0.125) (layer "In3.Cu") (net 169))
  (segment (start 133.247728 112.732897) (end 133.262621 112.709196) (width 0.125) (layer "In3.Cu") (net 169))
  (segment (start 129.86 113.4) (end 132.5 113.4) (width 0.1) (layer "F.Cu") (net 170))
  (segment (start 142.645 116.865) (end 139.464998 116.865) (width 0.1) (layer "F.Cu") (net 170))
  (segment (start 129.86 113.4) (end 128.36 111.9) (width 0.1) (layer "F.Cu") (net 170))
  (segment (start 125.5 111.9) (end 128.36 111.9) (width 0.1) (layer "F.Cu") (net 170))
  (segment (start 139.464998 116.865) (end 139.339998 116.99) (width 0.1) (layer "F.Cu") (net 170))
  (via (at 139.339998 116.99) (size 0.55) (drill 0.15) (layers "F.Cu" "B.Cu") (net 170))
  (via (at 132.5 113.4) (size 0.55) (drill 0.15) (layers "F.Cu" "B.Cu") (net 170))
  (segment (start 137.957546 115.470108) (end 137.974999 115.448224) (width 0.125) (layer "In3.Cu") (net 170))
  (segment (start 136.134861 113.399248) (end 136.030441 113.503667) (width 0.125) (layer "In3.Cu") (net 170))
  (segment (start 137.703977 114.796019) (end 137.678758 114.783874) (width 0.125) (layer "In3.Cu") (net 170))
  (segment (start 136.944357 114.070534) (end 136.916366 114.070534) (width 0.125) (layer "In3.Cu") (net 170))
  (segment (start 136.301466 114.509427) (end 136.27958 114.491974) (width 0.125) (layer "In3.Cu") (net 170))
  (segment (start 138.109015 115.296701) (end 138.115243 115.269412) (width 0.125) (layer "In3.Cu") (net 170))
  (segment (start 136.262127 114.337081) (end 136.279581 114.315198) (width 0.125) (layer "In3.Cu") (net 170))
  (segment (start 135.890199 114.064026) (end 135.890198 114.036034) (width 0.125) (layer "In3.Cu") (net 170))
  (segment (start 136.289753 113.381795) (end 136.264534 113.36965) (width 0.125) (layer "In3.Cu") (net 170))
  (segment (start 136.353974 114.527801) (end 136.326685 114.521572) (width 0.125) (layer "In3.Cu") (net 170))
  (segment (start 136.243754 114.38959) (end 136.249982 114.3623) (width 0.125) (layer "In3.Cu") (net 170))
  (segment (start 136.249982 114.3623) (end 136.262127 114.337081) (width 0.125) (layer "In3.Cu") (net 170))
  (segment (start 138.079418 115.167028) (end 138.057533 115.149575) (width 0.125) (layer "In3.Cu") (net 170))
  (segment (start 136.237245 113.363422) (end 136.209254 113.363422) (width 0.125) (layer "In3.Cu") (net 170))
  (segment (start 135.928057 113.539492) (end 135.900768 113.533264) (width 0.125) (layer "In3.Cu") (net 170))
  (segment (start 136.841973 114.10636) (end 136.456358 114.491975) (width 0.125) (layer "In3.Cu") (net 170))
  (segment (start 137.340249 115.375866) (end 137.725862 114.990249) (width 0.125) (layer "In3.Cu") (net 170))
  (segment (start 137.061086 115.234913) (end 137.033797 115.228684) (width 0.125) (layer "In3.Cu") (net 170))
  (segment (start 136.809914 114.845531) (end 136.78803 114.862983) (width 0.125) (layer "In3.Cu") (net 170))
  (segment (start 137.054576 114.208744) (end 137.054576 114.180753) (width 0.125) (layer "In3.Cu") (net 170))
  (segment (start 135.926024 114.138418) (end 135.908571 114.116533) (width 0.125) (layer "In3.Cu") (net 170))
  (segment (start 138.115243 115.24142) (end 138.109015 115.214131) (width 0.125) (layer "In3.Cu") (net 170))
  (segment (start 136.70102 113.855188) (end 136.70102 113.827197) (width 0.125) (layer "In3.Cu") (net 170))
  (segment (start 137.401903 114.50702) (end 137.389758 114.481801) (width 0.125) (layer "In3.Cu") (net 170))
  (segment (start 136.53552 113.723206) (end 136.510301 113.735351) (width 0.125) (layer "In3.Cu") (net 170))
  (segment (start 136.32909 113.554141) (end 136.341235 113.528922) (width 0.125) (layer "In3.Cu") (net 170))
  (segment (start 136.78803 114.862983) (end 136.762811 114.875128) (width 0.125) (layer "In3.Cu") (net 170))
  (segment (start 136.950867 115.124694) (end 136.950866 115.096702) (width 0.125) (layer "In3.Cu") (net 170))
  (segment (start 137.755459 114.943146) (end 137.761688 114.915856) (width 0.125) (layer "In3.Cu") (net 170))
  (segment (start 137.623478 114.777646) (end 137.596188 114.783874) (width 0.125) (layer "In3.Cu") (net 170))
  (segment (start 137.048347 114.153464) (end 137.036202 114.128245) (width 0.125) (layer "In3.Cu") (net 170))
  (segment (start 137.651469 114.777646) (end 137.623478 114.777646) (width 0.125) (layer "In3.Cu") (net 170))
  (segment (start 135.973129 114.168016) (end 135.94791 114.155871) (width 0.125) (layer "In3.Cu") (net 170))
  (segment (start 138.09687 115.32192) (end 138.109015 115.296701) (width 0.125) (layer "In3.Cu") (net 170))
  (segment (start 136.156745 113.381795) (end 136.134861 113.399248) (width 0.125) (layer "In3.Cu") (net 170))
  (segment (start 136.694791 113.882478) (end 136.70102 113.855188) (width 0.125) (layer "In3.Cu") (net 170))
  (segment (start 136.030441 113.503667) (end 136.008557 113.521119) (width 0.125) (layer "In3.Cu") (net 170))
  (segment (start 137.036202 114.261253) (end 137.048347 114.236034) (width 0.125) (layer "In3.Cu") (net 170))
  (segment (start 138.079418 115.343804) (end 138.09687 115.32192) (width 0.125) (layer "In3.Cu") (net 170))
  (segment (start 137.974999 115.625001) (end 137.957546 115.603116) (width 0.125) (layer "In3.Cu") (net 170))
  (segment (start 137.304423 115.47825) (end 137.304422 115.450258) (width 0.125) (layer "In3.Cu") (net 170))
  (segment (start 135.908571 114.116533) (end 135.896426 114.091314) (width 0.125) (layer "In3.Cu") (net 170))
  (segment (start 136.341235 113.446352) (end 136.32909 113.421133) (width 0.125) (layer "In3.Cu") (net 170))
  (segment (start 136.56281 113.716978) (end 136.53552 113.723206) (width 0.125) (layer "In3.Cu") (net 170))
  (segment (start 136.603538 114.715856) (end 136.615683 114.690637) (width 0.125) (layer "In3.Cu") (net 170))
  (segment (start 137.977034 115.131202) (end 137.949744 115.13743) (width 0.125) (layer "In3.Cu") (net 170))
  (segment (start 132.5 113.4) (end 135.749998 113.4) (width 0.125) (layer "In3.Cu") (net 170))
  (segment (start 135.956049 113.539492) (end 135.928057 113.539492) (width 0.125) (layer "In3.Cu") (net 170))
  (segment (start 137.743314 114.968365) (end 137.755459 114.943146) (width 0.125) (layer "In3.Cu") (net 170))
  (segment (start 136.986692 115.199086) (end 136.969239 115.177201) (width 0.125) (layer "In3.Cu") (net 170))
  (segment (start 138.115243 115.269412) (end 138.115243 115.24142) (width 0.125) (layer "In3.Cu") (net 170))
  (segment (start 136.000418 114.174245) (end 135.973129 114.168016) (width 0.125) (layer "In3.Cu") (net 170))
  (segment (start 137.01875 114.283137) (end 137.036202 114.261253) (width 0.125) (layer "In3.Cu") (net 170))
  (segment (start 136.682646 113.907697) (end 136.694791 113.882478) (width 0.125) (layer "In3.Cu") (net 170))
  (segment (start 137.389758 114.614809) (end 137.401903 114.58959) (width 0.125) (layer "In3.Cu") (net 170))
  (segment (start 137.033797 115.228684) (end 137.008578 115.216539) (width 0.125) (layer "In3.Cu") (net 170))
  (segment (start 137.414642 115.588469) (end 137.387353 115.58224) (width 0.125) (layer "In3.Cu") (net 170))
  (segment (start 137.755459 114.860576) (end 137.743314 114.835357) (width 0.125) (layer "In3.Cu") (net 170))
  (segment (start 136.615683 114.823645) (end 136.603538 114.798426) (width 0.125) (layer "In3.Cu") (net 170))
  (segment (start 137.16347 115.199087) (end 137.141586 115.216539) (width 0.125) (layer "In3.Cu") (net 170))
  (segment (start 136.950866 115.096702) (end 136.957094 115.069412) (width 0.125) (layer "In3.Cu") (net 170))
  (segment (start 137.340248 115.552642) (end 137.322795 115.530757) (width 0.125) (layer "In3.Cu") (net 170))
  (segment (start 137.389758 114.481801) (end 137.372306 114.459916) (width 0.125) (layer "In3.Cu") (net 170))
  (segment (start 137.116367 115.228684) (end 137.089076 115.234912) (width 0.125) (layer "In3.Cu") (net 170))
  (segment (start 137.725862 114.990249) (end 137.743314 114.968365) (width 0.125) (layer "In3.Cu") (net 170))
  (segment (start 137.517026 115.552643) (end 137.902641 115.167028) (width 0.125) (layer "In3.Cu") (net 170))
  (segment (start 137.372306 114.459916) (end 137.350421 114.442463) (width 0.125) (layer "In3.Cu") (net 170))
  (segment (start 137.408132 114.5623) (end 137.408132 114.534309) (width 0.125) (layer "In3.Cu") (net 170))
  (segment (start 135.875549 113.521119) (end 135.853665 113.503667) (width 0.125) (layer "In3.Cu") (net 170))
  (segment (start 136.028408 114.174244) (end 136.000418 114.174245) (width 0.125) (layer "In3.Cu") (net 170))
  (segment (start 137.442632 115.588468) (end 137.414642 115.588469) (width 0.125) (layer "In3.Cu") (net 170))
  (segment (start 136.957094 115.151982) (end 136.950867 115.124694) (width 0.125) (layer "In3.Cu") (net 170))
  (segment (start 136.102802 114.138419) (end 136.080918 114.155871) (width 0.125) (layer "In3.Cu") (net 170))
  (segment (start 137.957546 115.603116) (end 137.945401 115.577897) (width 0.125) (layer "In3.Cu") (net 170))
  (segment (start 136.603538 114.798426) (end 136.597311 114.771138) (width 0.125) (layer "In3.Cu") (net 170))
  (segment (start 136.080918 114.155871) (end 136.055699 114.168016) (width 0.125) (layer "In3.Cu") (net 170))
  (segment (start 137.322795 115.397749) (end 137.340249 115.375866) (width 0.125) (layer "In3.Cu") (net 170))
  (segment (start 137.570969 114.796019) (end 137.549085 114.813472) (width 0.125) (layer "In3.Cu") (net 170))
  (segment (start 136.347464 113.501632) (end 136.347464 113.473641) (width 0.125) (layer "In3.Cu") (net 170))
  (segment (start 137.387353 115.58224) (end 137.362134 115.570095) (width 0.125) (layer "In3.Cu") (net 170))
  (segment (start 136.341235 113.528922) (end 136.347464 113.501632) (width 0.125) (layer "In3.Cu") (net 170))
  (segment (start 136.326685 114.521572) (end 136.301466 114.509427) (width 0.125) (layer "In3.Cu") (net 170))
  (segment (start 137.31065 115.505538) (end 137.304423 115.47825) (width 0.125) (layer "In3.Cu") (net 170))
  (segment (start 137.325202 114.430318) (end 137.297913 114.42409) (width 0.125) (layer "In3.Cu") (net 170))
  (segment (start 137.743314 114.835357) (end 137.725862 114.813472) (width 0.125) (layer "In3.Cu") (net 170))
  (segment (start 136.27958 114.491974) (end 136.262127 114.470089) (width 0.125) (layer "In3.Cu") (net 170))
  (segment (start 136.863857 114.088907) (end 136.841973 114.10636) (width 0.125) (layer "In3.Cu") (net 170))
  (segment (start 137.761688 114.887865) (end 137.755459 114.860576) (width 0.125) (layer "In3.Cu") (net 170))
  (segment (start 137.939173 115.522617) (end 137.945401 115.495327) (width 0.125) (layer "In3.Cu") (net 170))
  (segment (start 136.59731 114.743146) (end 136.603538 114.715856) (width 0.125) (layer "In3.Cu") (net 170))
  (segment (start 137.350421 114.442463) (end 137.325202 114.430318) (width 0.125) (layer "In3.Cu") (net 170))
  (segment (start 137.495142 115.570095) (end 137.469923 115.58224) (width 0.125) (layer "In3.Cu") (net 170))
  (segment (start 137.036202 114.128245) (end 137.01875 114.10636) (width 0.125) (layer "In3.Cu") (net 170))
  (segment (start 136.694791 113.799908) (end 136.682646 113.774689) (width 0.125) (layer "In3.Cu") (net 170))
  (segment (start 136.633136 114.84553) (end 136.615683 114.823645) (width 0.125) (layer "In3.Cu") (net 170))
  (segment (start 136.279581 114.315198) (end 136.665194 113.929581) (width 0.125) (layer "In3.Cu") (net 170))
  (segment (start 136.055699 114.168016) (end 136.028408 114.174244) (width 0.125) (layer "In3.Cu") (net 170))
  (segment (start 137.596188 114.783874) (end 137.570969 114.796019) (width 0.125) (layer "In3.Cu") (net 170))
  (segment (start 137.008578 115.216539) (end 136.986692 115.199086) (width 0.125) (layer "In3.Cu") (net 170))
  (segment (start 137.945401 115.495327) (end 137.957546 115.470108) (width 0.125) (layer "In3.Cu") (net 170))
  (segment (start 137.939173 115.550608) (end 137.939173 115.522617) (width 0.125) (layer "In3.Cu") (net 170))
  (segment (start 136.70102 113.827197) (end 136.694791 113.799908) (width 0.125) (layer "In3.Cu") (net 170))
  (segment (start 135.908571 113.983525) (end 135.926025 113.961642) (width 0.125) (layer "In3.Cu") (net 170))
  (segment (start 137.195529 114.459916) (end 136.809914 114.845531) (width 0.125) (layer "In3.Cu") (net 170))
  (segment (start 136.510301 113.735351) (end 136.488417 113.752804) (width 0.125) (layer "In3.Cu") (net 170))
  (segment (start 136.643309 113.735351) (end 136.61809 113.723206) (width 0.125) (layer "In3.Cu") (net 170))
  (segment (start 136.971646 114.076762) (end 136.944357 114.070534) (width 0.125) (layer "In3.Cu") (net 170))
  (segment (start 136.243755 114.417582) (end 136.243754 114.38959) (width 0.125) (layer "In3.Cu") (net 170))
  (segment (start 137.048347 114.236034) (end 137.054576 114.208744) (width 0.125) (layer "In3.Cu") (net 170))
  (segment (start 136.969239 115.177201) (end 136.957094 115.151982) (width 0.125) (layer "In3.Cu") (net 170))
  (segment (start 137.304422 115.450258) (end 137.31065 115.422968) (width 0.125) (layer "In3.Cu") (net 170))
  (segment (start 136.986693 115.02231) (end 137.372306 114.636693) (width 0.125) (layer "In3.Cu") (net 170))
  (segment (start 136.655022 114.862983) (end 136.633136 114.84553) (width 0.125) (layer "In3.Cu") (net 170))
  (segment (start 137.949744 115.13743) (end 137.924525 115.149575) (width 0.125) (layer "In3.Cu") (net 170))
  (segment (start 135.900768 113.533264) (end 135.875549 113.521119) (width 0.125) (layer "In3.Cu") (net 170))
  (segment (start 136.264534 113.36965) (end 136.237245 113.363422) (width 0.125) (layer "In3.Cu") (net 170))
  (segment (start 136.73552 114.881356) (end 136.70753 114.881357) (width 0.125) (layer "In3.Cu") (net 170))
  (segment (start 136.311638 113.399248) (end 136.289753 113.381795) (width 0.125) (layer "In3.Cu") (net 170))
  (segment (start 135.983338 113.533264) (end 135.956049 113.539492) (width 0.125) (layer "In3.Cu") (net 170))
  (segment (start 136.957094 115.069412) (end 136.969239 115.044193) (width 0.125) (layer "In3.Cu") (net 170))
  (segment (start 137.31065 115.422968) (end 137.322795 115.397749) (width 0.125) (layer "In3.Cu") (net 170))
  (segment (start 138.09687 115.188912) (end 138.079418 115.167028) (width 0.125) (layer "In3.Cu") (net 170))
  (segment (start 135.853665 113.503667) (end 135.749998 113.4) (width 0.125) (layer "In3.Cu") (net 170))
  (segment (start 136.969239 115.044193) (end 136.986693 115.02231) (width 0.125) (layer "In3.Cu") (net 170))
  (segment (start 137.054576 114.180753) (end 137.048347 114.153464) (width 0.125) (layer "In3.Cu") (net 170))
  (segment (start 135.896426 114.008744) (end 135.908571 113.983525) (width 0.125) (layer "In3.Cu") (net 170))
  (segment (start 136.590801 113.716978) (end 136.56281 113.716978) (width 0.125) (layer "In3.Cu") (net 170))
  (segment (start 136.488417 113.752804) (end 136.102802 114.138419) (width 0.125) (layer "In3.Cu") (net 170))
  (segment (start 136.262127 114.470089) (end 136.249982 114.44487) (width 0.125) (layer "In3.Cu") (net 170))
  (segment (start 136.61809 113.723206) (end 136.590801 113.716978) (width 0.125) (layer "In3.Cu") (net 170))
  (segment (start 137.678758 114.783874) (end 137.651469 114.777646) (width 0.125) (layer "In3.Cu") (net 170))
  (segment (start 137.517026 115.552643) (end 137.495142 115.570095) (width 0.125) (layer "In3.Cu") (net 170))
  (segment (start 136.409255 114.521572) (end 136.381964 114.5278) (width 0.125) (layer "In3.Cu") (net 170))
  (segment (start 136.996865 114.088907) (end 136.971646 114.076762) (width 0.125) (layer "In3.Cu") (net 170))
  (segment (start 136.32909 113.421133) (end 136.311638 113.399248) (width 0.125) (layer "In3.Cu") (net 170))
  (segment (start 136.682646 113.774689) (end 136.665194 113.752804) (width 0.125) (layer "In3.Cu") (net 170))
  (segment (start 136.916366 114.070534) (end 136.889076 114.076762) (width 0.125) (layer "In3.Cu") (net 170))
  (segment (start 135.94791 114.155871) (end 135.926024 114.138418) (width 0.125) (layer "In3.Cu") (net 170))
  (segment (start 136.633137 114.668754) (end 137.01875 114.283137) (width 0.125) (layer "In3.Cu") (net 170))
  (segment (start 137.408132 114.534309) (end 137.401903 114.50702) (width 0.125) (layer "In3.Cu") (net 170))
  (segment (start 139.339998 116.99) (end 137.974999 115.625001) (width 0.125) (layer "In3.Cu") (net 170))
  (segment (start 136.311638 113.576025) (end 136.32909 113.554141) (width 0.125) (layer "In3.Cu") (net 170))
  (segment (start 137.974999 115.448224) (end 138.079418 115.343804) (width 0.125) (layer "In3.Cu") (net 170))
  (segment (start 137.141586 115.216539) (end 137.116367 115.228684) (width 0.125) (layer "In3.Cu") (net 170))
  (segment (start 137.217413 114.442463) (end 137.195529 114.459916) (width 0.125) (layer "In3.Cu") (net 170))
  (segment (start 136.889076 114.076762) (end 136.863857 114.088907) (width 0.125) (layer "In3.Cu") (net 170))
  (segment (start 136.347464 113.473641) (end 136.341235 113.446352) (width 0.125) (layer "In3.Cu") (net 170))
  (segment (start 135.896426 114.091314) (end 135.890199 114.064026) (width 0.125) (layer "In3.Cu") (net 170))
  (segment (start 137.01875 114.10636) (end 136.996865 114.088907) (width 0.125) (layer "In3.Cu") (net 170))
  (segment (start 137.761688 114.915856) (end 137.761688 114.887865) (width 0.125) (layer "In3.Cu") (net 170))
  (segment (start 136.249982 114.44487) (end 136.243755 114.417582) (width 0.125) (layer "In3.Cu") (net 170))
  (segment (start 137.924525 115.149575) (end 137.902641 115.167028) (width 0.125) (layer "In3.Cu") (net 170))
  (segment (start 136.008557 113.521119) (end 135.983338 113.533264) (width 0.125) (layer "In3.Cu") (net 170))
  (segment (start 137.269922 114.42409) (end 137.242632 114.430318) (width 0.125) (layer "In3.Cu") (net 170))
  (segment (start 138.005025 115.131202) (end 137.977034 115.131202) (width 0.125) (layer "In3.Cu") (net 170))
  (segment (start 136.597311 114.771138) (end 136.59731 114.743146) (width 0.125) (layer "In3.Cu") (net 170))
  (segment (start 137.469923 115.58224) (end 137.442632 115.588468) (width 0.125) (layer "In3.Cu") (net 170))
  (segment (start 138.032314 115.13743) (end 138.005025 115.131202) (width 0.125) (layer "In3.Cu") (net 170))
  (segment (start 136.209254 113.363422) (end 136.181964 113.36965) (width 0.125) (layer "In3.Cu") (net 170))
  (segment (start 138.109015 115.214131) (end 138.09687 115.188912) (width 0.125) (layer "In3.Cu") (net 170))
  (segment (start 135.926025 113.961642) (end 136.311638 113.576025) (width 0.125) (layer "In3.Cu") (net 170))
  (segment (start 137.549085 114.813472) (end 137.16347 115.199087) (width 0.125) (layer "In3.Cu") (net 170))
  (segment (start 137.401903 114.58959) (end 137.408132 114.5623) (width 0.125) (layer "In3.Cu") (net 170))
  (segment (start 136.456358 114.491975) (end 136.434474 114.509427) (width 0.125) (layer "In3.Cu") (net 170))
  (segment (start 137.322795 115.530757) (end 137.31065 115.505538) (width 0.125) (layer "In3.Cu") (net 170))
  (segment (start 136.615683 114.690637) (end 136.633137 114.668754) (width 0.125) (layer "In3.Cu") (net 170))
  (segment (start 137.362134 115.570095) (end 137.340248 115.552642) (width 0.125) (layer "In3.Cu") (net 170))
  (segment (start 137.372306 114.636693) (end 137.389758 114.614809) (width 0.125) (layer "In3.Cu") (net 170))
  (segment (start 136.762811 114.875128) (end 136.73552 114.881356) (width 0.125) (layer "In3.Cu") (net 170))
  (segment (start 136.665194 113.929581) (end 136.682646 113.907697) (width 0.125) (layer "In3.Cu") (net 170))
  (segment (start 136.434474 114.509427) (end 136.409255 114.521572) (width 0.125) (layer "In3.Cu") (net 170))
  (segment (start 137.725862 114.813472) (end 137.703977 114.796019) (width 0.125) (layer "In3.Cu") (net 170))
  (segment (start 137.089076 115.234912) (end 137.061086 115.234913) (width 0.125) (layer "In3.Cu") (net 170))
  (segment (start 138.057533 115.149575) (end 138.032314 115.13743) (width 0.125) (layer "In3.Cu") (net 170))
  (segment (start 137.297913 114.42409) (end 137.269922 114.42409) (width 0.125) (layer "In3.Cu") (net 170))
  (segment (start 137.945401 115.577897) (end 137.939173 115.550608) (width 0.125) (layer "In3.Cu") (net 170))
  (segment (start 136.665194 113.752804) (end 136.643309 113.735351) (width 0.125) (layer "In3.Cu") (net 170))
  (segment (start 137.242632 114.430318) (end 137.217413 114.442463) (width 0.125) (layer "In3.Cu") (net 170))
  (segment (start 136.680241 114.875128) (end 136.655022 114.862983) (width 0.125) (layer "In3.Cu") (net 170))
  (segment (start 136.70753 114.881357) (end 136.680241 114.875128) (width 0.125) (layer "In3.Cu") (net 170))
  (segment (start 135.890198 114.036034) (end 135.896426 114.008744) (width 0.125) (layer "In3.Cu") (net 170))
  (segment (start 136.381964 114.5278) (end 136.353974 114.527801) (width 0.125) (layer "In3.Cu") (net 170))
  (segment (start 136.181964 113.36965) (end 136.156745 113.381795) (width 0.125) (layer "In3.Cu") (net 170))
  (segment (start 123.5 112.9) (end 124 112.4) (width 0.15) (layer "F.Cu") (net 171))
  (segment (start 141.69 114.59) (end 141 113.9) (width 0.1) (layer "F.Cu") (net 171))
  (segment (start 132.122252 116.402507) (end 132.1 116.4) (width 0.1) (layer "F.Cu") (net 171))
  (segment (start 133.1 116.754135) (end 133.077747 116.751627) (width 0.1) (layer "F.Cu") (net 171))
  (segment (start 132.943388 116.055769) (end 132.922252 116.048373) (width 0.1) (layer "F.Cu") (net 171))
  (segment (start 132.762348 116.732318) (end 132.743388 116.744231) (width 0.1) (layer "F.Cu") (net 171))
  (segment (start 132.621816 116.716483) (end 132.609903 116.697523) (width 0.1) (layer "F.Cu") (net 171))
  (segment (start 132.609903 116.697523) (end 132.602507 116.676387) (width 0.1) (layer "F.Cu") (net 171))
  (segment (start 132.543388 116.055769) (end 132.522252 116.048373) (width 0.1) (layer "F.Cu") (net 171))
  (segment (start 132.8 116.145865) (end 132.8 116.654135) (width 0.1) (layer "F.Cu") (net 171))
  (segment (start 128.93 115.11) (end 128.93 115.1) (width 0.1) (layer "F.Cu") (net 171))
  (segment (start 142.97 114.59) (end 141.69 114.59) (width 0.1) (layer "F.Cu") (net 171))
  (segment (start 133.456611 116.390097) (end 133.437651 116.378184) (width 0.1) (layer "F.Cu") (net 171))
  (segment (start 132.362348 116.732318) (end 132.343388 116.744231) (width 0.1) (layer "F.Cu") (net 171))
  (segment (start 132.821816 116.083517) (end 132.809903 116.102477) (width 0.1) (layer "F.Cu") (net 171))
  (segment (start 133.002507 116.676387) (end 133 116.654135) (width 0.1) (layer "F.Cu") (net 171))
  (segment (start 133.143388 116.744231) (end 133.122252 116.751627) (width 0.1) (layer "F.Cu") (net 171))
  (segment (start 133.2 116.145865) (end 133.2 116.654135) (width 0.1) (layer "F.Cu") (net 171))
  (segment (start 132.9 116.045865) (end 132.877747 116.048373) (width 0.1) (layer "F.Cu") (net 171))
  (segment (start 133.277747 116.048373) (end 133.256611 116.055769) (width 0.1) (layer "F.Cu") (net 171))
  (segment (start 133.5 116.4) (end 133.477747 116.397493) (width 0.1) (layer "F.Cu") (net 171))
  (segment (start 132.837651 116.067682) (end 132.821816 116.083517) (width 0.1) (layer "F.Cu") (net 171))
  (segment (start 133.322252 116.048373) (end 133.3 116.045865) (width 0.1) (layer "F.Cu") (net 171))
  (segment (start 132.2 116.5) (end 132.197492 116.477747) (width 0.1) (layer "F.Cu") (net 171))
  (segment (start 132.7 116.754135) (end 132.677747 116.751627) (width 0.1) (layer "F.Cu") (net 171))
  (segment (start 132.4 116.145865) (end 132.4 116.654135) (width 0.1) (layer "F.Cu") (net 171))
  (segment (start 133.209903 116.102477) (end 133.202507 116.123613) (width 0.1) (layer "F.Cu") (net 171))
  (segment (start 132.477747 116.048373) (end 132.456611 116.055769) (width 0.1) (layer "F.Cu") (net 171))
  (segment (start 132.677747 116.751627) (end 132.656611 116.744231) (width 0.1) (layer "F.Cu") (net 171))
  (segment (start 132.6 116.145865) (end 132.597492 116.123613) (width 0.1) (layer "F.Cu") (net 171))
  (segment (start 132.256611 116.744231) (end 132.237651 116.732318) (width 0.1) (layer "F.Cu") (net 171))
  (segment (start 132.922252 116.048373) (end 132.9 116.045865) (width 0.1) (layer "F.Cu") (net 171))
  (segment (start 132.2 116.654135) (end 132.2 116.5) (width 0.1) (layer "F.Cu") (net 171))
  (segment (start 132.743388 116.744231) (end 132.722252 116.751627) (width 0.1) (layer "F.Cu") (net 171))
  (segment (start 133.202507 116.123613) (end 133.2 116.145865) (width 0.1) (layer "F.Cu") (net 171))
  (segment (start 135.83 116.4) (end 133.5 116.4) (width 0.1) (layer "F.Cu") (net 171))
  (segment (start 133.237651 116.067682) (end 133.221816 116.083517) (width 0.1) (layer "F.Cu") (net 171))
  (segment (start 132.562348 116.067682) (end 132.543388 116.055769) (width 0.1) (layer "F.Cu") (net 171))
  (segment (start 133.009903 116.697523) (end 133.002507 116.676387) (width 0.1) (layer "F.Cu") (net 171))
  (segment (start 132.602507 116.676387) (end 132.6 116.654135) (width 0.1) (layer "F.Cu") (net 171))
  (segment (start 132.397492 116.676387) (end 132.390096 116.697523) (width 0.1) (layer "F.Cu") (net 171))
  (segment (start 133.477747 116.397493) (end 133.456611 116.390097) (width 0.1) (layer "F.Cu") (net 171))
  (segment (start 133 116.654135) (end 133 116.145865) (width 0.1) (layer "F.Cu") (net 171))
  (segment (start 132.656611 116.744231) (end 132.637651 116.732318) (width 0.1) (layer "F.Cu") (net 171))
  (segment (start 133.343388 116.055769) (end 133.322252 116.048373) (width 0.1) (layer "F.Cu") (net 171))
  (segment (start 132.856611 116.055769) (end 132.837651 116.067682) (width 0.1) (layer "F.Cu") (net 171))
  (segment (start 132.578183 116.083517) (end 132.562348 116.067682) (width 0.1) (layer "F.Cu") (net 171))
  (segment (start 133.437651 116.378184) (end 133.421816 116.362349) (width 0.1) (layer "F.Cu") (net 171))
  (segment (start 133.178183 116.716483) (end 133.162348 116.732318) (width 0.1) (layer "F.Cu") (net 171))
  (segment (start 132.5 116.045865) (end 132.477747 116.048373) (width 0.1) (layer "F.Cu") (net 171))
  (segment (start 130.22 116.4) (end 132.1 116.4) (width 0.1) (layer "F.Cu") (net 171))
  (segment (start 132.143388 116.409903) (end 132.122252 116.402507) (width 0.1) (layer "F.Cu") (net 171))
  (segment (start 130.22 116.4) (end 128.93 115.11) (width 0.1) (layer "F.Cu") (net 171))
  (segment (start 133.077747 116.751627) (end 133.056611 116.744231) (width 0.1) (layer "F.Cu") (net 171))
  (segment (start 133.122252 116.751627) (end 133.1 116.754135) (width 0.1) (layer "F.Cu") (net 171))
  (segment (start 132.997492 116.123613) (end 132.990096 116.102477) (width 0.1) (layer "F.Cu") (net 171))
  (segment (start 132.877747 116.048373) (end 132.856611 116.055769) (width 0.1) (layer "F.Cu") (net 171))
  (segment (start 133.397492 116.123613) (end 133.390096 116.102477) (width 0.1) (layer "F.Cu") (net 171))
  (segment (start 132.221816 116.716483) (end 132.209903 116.697523) (width 0.1) (layer "F.Cu") (net 171))
  (segment (start 138.33 113.9) (end 135.83 116.4) (width 0.1) (layer "F.Cu") (net 171))
  (segment (start 132.322252 116.751627) (end 132.3 116.754135) (width 0.1) (layer "F.Cu") (net 171))
  (segment (start 132.6 116.654135) (end 132.6 116.145865) (width 0.1) (layer "F.Cu") (net 171))
  (segment (start 132.178183 116.437651) (end 132.162348 116.421816) (width 0.1) (layer "F.Cu") (net 171))
  (segment (start 133.2 116.654135) (end 133.197492 116.676387) (width 0.1) (layer "F.Cu") (net 171))
  (segment (start 133.162348 116.732318) (end 133.143388 116.744231) (width 0.1) (layer "F.Cu") (net 171))
  (segment (start 132.409903 116.102477) (end 132.402507 116.123613) (width 0.1) (layer "F.Cu") (net 171))
  (segment (start 132.637651 116.732318) (end 132.621816 116.716483) (width 0.1) (layer "F.Cu") (net 171))
  (segment (start 133.190096 116.697523) (end 133.178183 116.716483) (width 0.1) (layer "F.Cu") (net 171))
  (segment (start 132.8 116.654135) (end 132.797492 116.676387) (width 0.1) (layer "F.Cu") (net 171))
  (segment (start 133.221816 116.083517) (end 133.209903 116.102477) (width 0.1) (layer "F.Cu") (net 171))
  (segment (start 132.456611 116.055769) (end 132.437651 116.067682) (width 0.1) (layer "F.Cu") (net 171))
  (segment (start 133 116.145865) (end 132.997492 116.123613) (width 0.1) (layer "F.Cu") (net 171))
  (segment (start 133.037651 116.732318) (end 133.021816 116.716483) (width 0.1) (layer "F.Cu") (net 171))
  (segment (start 133.378183 116.083517) (end 133.362348 116.067682) (width 0.1) (layer "F.Cu") (net 171))
  (segment (start 132.237651 116.732318) (end 132.221816 116.716483) (width 0.1) (layer "F.Cu") (net 171))
  (segment (start 132.790096 116.697523) (end 132.778183 116.716483) (width 0.1) (layer "F.Cu") (net 171))
  (segment (start 132.797492 116.676387) (end 132.790096 116.697523) (width 0.1) (layer "F.Cu") (net 171))
  (segment (start 132.3 116.754135) (end 132.277747 116.751627) (width 0.1) (layer "F.Cu") (net 171))
  (segment (start 132.809903 116.102477) (end 132.802507 116.123613) (width 0.1) (layer "F.Cu") (net 171))
  (segment (start 133.197492 116.676387) (end 133.190096 116.697523) (width 0.1) (layer "F.Cu") (net 171))
  (segment (start 133.409903 116.343389) (end 133.402507 116.322253) (width 0.1) (layer "F.Cu") (net 171))
  (segment (start 143.295 114.915) (end 142.97 114.59) (width 0.1) (layer "F.Cu") (net 171))
  (segment (start 133.390096 116.102477) (end 133.378183 116.083517) (width 0.1) (layer "F.Cu") (net 171))
  (segment (start 133.402507 116.322253) (end 133.4 116.3) (width 0.1) (layer "F.Cu") (net 171))
  (segment (start 132.590096 116.102477) (end 132.578183 116.083517) (width 0.1) (layer "F.Cu") (net 171))
  (segment (start 132.597492 116.123613) (end 132.590096 116.102477) (width 0.1) (layer "F.Cu") (net 171))
  (segment (start 132.802507 116.123613) (end 132.8 116.145865) (width 0.1) (layer "F.Cu") (net 171))
  (segment (start 141 113.9) (end 138.33 113.9) (width 0.1) (layer "F.Cu") (net 171))
  (segment (start 132.162348 116.421816) (end 132.143388 116.409903) (width 0.1) (layer "F.Cu") (net 171))
  (segment (start 132.421816 116.083517) (end 132.409903 116.102477) (width 0.1) (layer "F.Cu") (net 171))
  (segment (start 132.209903 116.697523) (end 132.202507 116.676387) (width 0.1) (layer "F.Cu") (net 171))
  (segment (start 133.256611 116.055769) (end 133.237651 116.067682) (width 0.1) (layer "F.Cu") (net 171))
  (segment (start 132.778183 116.716483) (end 132.762348 116.732318) (width 0.1) (layer "F.Cu") (net 171))
  (segment (start 132.197492 116.477747) (end 132.190096 116.456611) (width 0.1) (layer "F.Cu") (net 171))
  (segment (start 132.402507 116.123613) (end 132.4 116.145865) (width 0.1) (layer "F.Cu") (net 171))
  (segment (start 133.056611 116.744231) (end 133.037651 116.732318) (width 0.1) (layer "F.Cu") (net 171))
  (segment (start 132.522252 116.048373) (end 132.5 116.045865) (width 0.1) (layer "F.Cu") (net 171))
  (segment (start 132.962348 116.067682) (end 132.943388 116.055769) (width 0.1) (layer "F.Cu") (net 171))
  (segment (start 132.990096 116.102477) (end 132.978183 116.083517) (width 0.1) (layer "F.Cu") (net 171))
  (segment (start 132.978183 116.083517) (end 132.962348 116.067682) (width 0.1) (layer "F.Cu") (net 171))
  (segment (start 133.362348 116.067682) (end 133.343388 116.055769) (width 0.1) (layer "F.Cu") (net 171))
  (segment (start 132.190096 116.456611) (end 132.178183 116.437651) (width 0.1) (layer "F.Cu") (net 171))
  (segment (start 132.277747 116.751627) (end 132.256611 116.744231) (width 0.1) (layer "F.Cu") (net 171))
  (segment (start 132.202507 116.676387) (end 132.2 116.654135) (width 0.1) (layer "F.Cu") (net 171))
  (segment (start 133.3 116.045865) (end 133.277747 116.048373) (width 0.1) (layer "F.Cu") (net 171))
  (segment (start 133.421816 116.362349) (end 133.409903 116.343389) (width 0.1) (layer "F.Cu") (net 171))
  (segment (start 133.4 116.145865) (end 133.397492 116.123613) (width 0.1) (layer "F.Cu") (net 171))
  (segment (start 132.4 116.654135) (end 132.397492 116.676387) (width 0.1) (layer "F.Cu") (net 171))
  (segment (start 133.021816 116.716483) (end 133.009903 116.697523) (width 0.1) (layer "F.Cu") (net 171))
  (segment (start 132.390096 116.697523) (end 132.378183 116.716483) (width 0.1) (layer "F.Cu") (net 171))
  (segment (start 133.4 116.3) (end 133.4 116.145865) (width 0.1) (layer "F.Cu") (net 171))
  (segment (start 132.378183 116.716483) (end 132.362348 116.732318) (width 0.1) (layer "F.Cu") (net 171))
  (segment (start 132.437651 116.067682) (end 132.421816 116.083517) (width 0.1) (layer "F.Cu") (net 171))
  (segment (start 132.343388 116.744231) (end 132.322252 116.751627) (width 0.1) (layer "F.Cu") (net 171))
  (segment (start 132.722252 116.751627) (end 132.7 116.754135) (width 0.1) (layer "F.Cu") (net 171))
  (via (at 124 112.4) (size 0.55) (drill 0.15) (layers "F.Cu" "B.Cu") (net 171))
  (via (at 128.93 115.1) (size 0.55) (drill 0.15) (layers "F.Cu" "B.Cu") (net 171))
  (segment (start 124 112.4) (end 126.23 112.4) (width 0.125) (layer "In2.Cu") (net 171))
  (segment (start 126.23 112.4) (end 128.93 115.1) (width 0.125) (layer "In2.Cu") (net 171))
  (segment (start 145.895 112.965) (end 145.895 111.848148) (width 0.1) (layer "F.Cu") (net 172))
  (segment (start 145.895 111.848148) (end 146.656574 111.086574) (width 0.1) (layer "F.Cu") (net 172))
  (segment (start 125 112.4) (end 124.5 112.9) (width 0.1) (layer "F.Cu") (net 172))
  (segment (start 128.18 112.4) (end 125 112.4) (width 0.1) (layer "F.Cu") (net 172))
  (segment (start 129.6053 113.8495) (end 129.6053 113.8253) (width 0.1) (layer "F.Cu") (net 172))
  (segment (start 129.6053 113.8253) (end 128.18 112.4) (width 0.1) (layer "F.Cu") (net 172))
  (via (at 146.656574 111.086574) (size 0.55) (drill 0.15) (layers "F.Cu" "B.Cu") (net 172))
  (via (at 129.6053 113.8495) (size 0.55) (drill 0.15) (layers "F.Cu" "B.Cu") (net 172))
  (segment (start 130.766 109.398) (end 131.782 108.382) (width 0.125) (layer "In3.Cu") (net 172))
  (segment (start 137.624 108.382) (end 141.434 112.192) (width 0.125) (layer "In3.Cu") (net 172))
  (segment (start 131.782 108.382) (end 137.624 108.382) (width 0.125) (layer "In3.Cu") (net 172))
  (segment (start 130.766 112.6888) (end 130.766 109.398) (width 0.125) (layer "In3.Cu") (net 172))
  (segment (start 129.6053 113.8495) (end 130.766 112.6888) (width 0.125) (layer "In3.Cu") (net 172))
  (segment (start 145.551148 112.192) (end 146.656574 111.086574) (width 0.125) (layer "In3.Cu") (net 172))
  (segment (start 141.434 112.192) (end 145.551148 112.192) (width 0.125) (layer "In3.Cu") (net 172))
  (segment (start 135.337651 115.05364) (end 135.321816 115.069475) (width 0.1) (layer "F.Cu") (net 173))
  (segment (start 134.697492 115.109571) (end 134.690096 115.088435) (width 0.1) (layer "F.Cu") (net 173))
  (segment (start 135.097492 115.109571) (end 135.090096 115.088435) (width 0.1) (layer "F.Cu") (net 173))
  (segment (start 135.82 115.4) (end 135.6 115.4) (width 0.1) (layer "F.Cu") (net 173))
  (segment (start 133.702507 115.109571) (end 133.7 115.131823) (width 0.1) (layer "F.Cu") (net 173))
  (segment (start 133.9 115.131823) (end 133.897492 115.109571) (width 0.1) (layer "F.Cu") (net 173))
  (segment (start 135.022252 115.034331) (end 135 115.031823) (width 0.1) (layer "F.Cu") (net 173))
  (segment (start 134.2 115.031823) (end 134.177747 115.034331) (width 0.1) (layer "F.Cu") (net 173))
  (segment (start 134.478183 115.730525) (end 134.462348 115.74636) (width 0.1) (layer "F.Cu") (net 173))
  (segment (start 133.697492 115.690429) (end 133.690096 115.711565) (width 0.1) (layer "F.Cu") (net 173))
  (segment (start 134.843388 115.758273) (end 134.822252 115.765669) (width 0.1) (layer "F.Cu") (net 173))
  (segment (start 134.321816 115.730525) (end 134.309903 115.711565) (width 0.1) (layer "F.Cu") (net 173))
  (segment (start 135.102507 115.690429) (end 135.1 115.668177) (width 0.1) (layer "F.Cu") (net 173))
  (segment (start 134.897492 115.690429) (end 134.890096 115.711565) (width 0.1) (layer "F.Cu") (net 173))
  (segment (start 135.443388 115.041727) (end 135.422252 115.034331) (width 0.1) (layer "F.Cu") (net 173))
  (segment (start 134.662348 115.05364) (end 134.643388 115.041727) (width 0.1) (layer "F.Cu") (net 173))
  (segment (start 134.043388 115.758273) (end 134.022252 115.765669) (width 0.1) (layer "F.Cu") (net 173))
  (segment (start 134.8 115.768177) (end 134.777747 115.765669) (width 0.1) (layer "F.Cu") (net 173))
  (segment (start 133.756611 115.041727) (end 133.737651 115.05364) (width 0.1) (layer "F.Cu") (net 173))
  (segment (start 133.909903 115.711565) (end 133.902507 115.690429) (width 0.1) (layer "F.Cu") (net 173))
  (segment (start 135.462348 115.05364) (end 135.443388 115.041727) (width 0.1) (layer "F.Cu") (net 173))
  (segment (start 134.643388 115.041727) (end 134.622252 115.034331) (width 0.1) (layer "F.Cu") (net 173))
  (segment (start 134.7 115.668177) (end 134.7 115.131823) (width 0.1) (layer "F.Cu") (net 173))
  (segment (start 135.5 115.3) (end 135.5 115.131823) (width 0.1) (layer "F.Cu") (net 173))
  (segment (start 133.537651 115.74636) (end 133.521816 115.730525) (width 0.1) (layer "F.Cu") (net 173))
  (segment (start 133.462348 115.421816) (end 133.443388 115.409903) (width 0.1) (layer "F.Cu") (net 173))
  (segment (start 134.577747 115.034331) (end 134.556611 115.041727) (width 0.1) (layer "F.Cu") (net 173))
  (segment (start 135.577747 115.397493) (end 135.556611 115.390097) (width 0.1) (layer "F.Cu") (net 173))
  (segment (start 134.556611 115.041727) (end 134.537651 115.05364) (width 0.1) (layer "F.Cu") (net 173))
  (segment (start 134.890096 115.711565) (end 134.878183 115.730525) (width 0.1) (layer "F.Cu") (net 173))
  (segment (start 134.422252 115.765669) (end 134.4 115.768177) (width 0.1) (layer "F.Cu") (net 173))
  (segment (start 142.97 113.94) (end 142.219852 113.94) (width 0.1) (layer "F.Cu") (net 173))
  (segment (start 133.443388 115.409903) (end 133.422252 115.402507) (width 0.1) (layer "F.Cu") (net 173))
  (segment (start 133.8 115.031823) (end 133.777747 115.034331) (width 0.1) (layer "F.Cu") (net 173))
  (segment (start 135.509903 115.343389) (end 135.502507 115.322253) (width 0.1) (layer "F.Cu") (net 173))
  (segment (start 134.377747 115.765669) (end 134.356611 115.758273) (width 0.1) (layer "F.Cu") (net 173))
  (segment (start 135.177747 115.765669) (end 135.156611 115.758273) (width 0.1) (layer "F.Cu") (net 173))
  (segment (start 134.097492 115.690429) (end 134.090096 115.711565) (width 0.1) (layer "F.Cu") (net 173))
  (segment (start 142.219852 113.94) (end 141.279852 113) (width 0.1) (layer "F.Cu") (net 173))
  (segment (start 133.7 115.131823) (end 133.7 115.668177) (width 0.1) (layer "F.Cu") (net 173))
  (segment (start 134.5 115.668177) (end 134.497492 115.690429) (width 0.1) (layer "F.Cu") (net 173))
  (segment (start 135.521816 115.362349) (end 135.509903 115.343389) (width 0.1) (layer "F.Cu") (net 173))
  (segment (start 134.137651 115.05364) (end 134.121816 115.069475) (width 0.1) (layer "F.Cu") (net 173))
  (segment (start 133.521816 115.730525) (end 133.509903 115.711565) (width 0.1) (layer "F.Cu") (net 173))
  (segment (start 135.278183 115.730525) (end 135.262348 115.74636) (width 0.1) (layer "F.Cu") (net 173))
  (segment (start 133.737651 115.05364) (end 133.721816 115.069475) (width 0.1) (layer "F.Cu") (net 173))
  (segment (start 134.5 115.131823) (end 134.5 115.668177) (width 0.1) (layer "F.Cu") (net 173))
  (segment (start 134.356611 115.758273) (end 134.337651 115.74636) (width 0.1) (layer "F.Cu") (net 173))
  (segment (start 135.377747 115.034331) (end 135.356611 115.041727) (width 0.1) (layer "F.Cu") (net 173))
  (segment (start 133.6 115.768177) (end 133.577747 115.765669) (width 0.1) (layer "F.Cu") (net 173))
  (segment (start 134.222252 115.034331) (end 134.2 115.031823) (width 0.1) (layer "F.Cu") (net 173))
  (segment (start 133.7 115.668177) (end 133.697492 115.690429) (width 0.1) (layer "F.Cu") (net 173))
  (segment (start 133.937651 115.74636) (end 133.921816 115.730525) (width 0.1) (layer "F.Cu") (net 173))
  (segment (start 133.709903 115.088435) (end 133.702507 115.109571) (width 0.1) (layer "F.Cu") (net 173))
  (segment (start 134.177747 115.034331) (end 134.156611 115.041727) (width 0.1) (layer "F.Cu") (net 173))
  (segment (start 135.121816 115.730525) (end 135.109903 115.711565) (width 0.1) (layer "F.Cu") (net 173))
  (segment (start 134.1 115.131823) (end 134.1 115.668177) (width 0.1) (layer "F.Cu") (net 173))
  (segment (start 134.462348 115.74636) (end 134.443388 115.758273) (width 0.1) (layer "F.Cu") (net 173))
  (segment (start 135.156611 115.758273) (end 135.137651 115.74636) (width 0.1) (layer "F.Cu") (net 173))
  (segment (start 133.502507 115.690429) (end 133.5 115.668177) (width 0.1) (layer "F.Cu") (net 173))
  (segment (start 133.690096 115.711565) (end 133.678183 115.730525) (width 0.1) (layer "F.Cu") (net 173))
  (segment (start 135.137651 115.74636) (end 135.121816 115.730525) (width 0.1) (layer "F.Cu") (net 173))
  (segment (start 134 115.768177) (end 133.977747 115.765669) (width 0.1) (layer "F.Cu") (net 173))
  (segment (start 133.422252 115.402507) (end 133.4 115.4) (width 0.1) (layer "F.Cu") (net 173))
  (segment (start 135.109903 115.711565) (end 135.102507 115.690429) (width 0.1) (layer "F.Cu") (net 173))
  (segment (start 125.5 112.9) (end 127.72 112.9) (width 0.1) (layer "F.Cu") (net 173))
  (segment (start 134.777747 115.765669) (end 134.756611 115.758273) (width 0.1) (layer "F.Cu") (net 173))
  (segment (start 135.2 115.768177) (end 135.177747 115.765669) (width 0.1) (layer "F.Cu") (net 173))
  (segment (start 134.490096 115.711565) (end 134.478183 115.730525) (width 0.1) (layer "F.Cu") (net 173))
  (segment (start 133.490096 115.456611) (end 133.478183 115.437651) (width 0.1) (layer "F.Cu") (net 173))
  (segment (start 135.502507 115.322253) (end 135.5 115.3) (width 0.1) (layer "F.Cu") (net 173))
  (segment (start 135.490096 115.088435) (end 135.478183 115.069475) (width 0.1) (layer "F.Cu") (net 173))
  (segment (start 135.6 115.4) (end 135.577747 115.397493) (width 0.1) (layer "F.Cu") (net 173))
  (segment (start 135.356611 115.041727) (end 135.337651 115.05364) (width 0.1) (layer "F.Cu") (net 173))
  (segment (start 130.22 115.4) (end 133.4 115.4) (width 0.1) (layer "F.Cu") (net 173))
  (segment (start 133.577747 115.765669) (end 133.556611 115.758273) (width 0.1) (layer "F.Cu") (net 173))
  (segment (start 135.478183 115.069475) (end 135.462348 115.05364) (width 0.1) (layer "F.Cu") (net 173))
  (segment (start 134.497492 115.690429) (end 134.490096 115.711565) (width 0.1) (layer "F.Cu") (net 173))
  (segment (start 134.622252 115.034331) (end 134.6 115.031823) (width 0.1) (layer "F.Cu") (net 173))
  (segment (start 134.309903 115.711565) (end 134.302507 115.690429) (width 0.1) (layer "F.Cu") (net 173))
  (segment (start 134.022252 115.765669) (end 134 115.768177) (width 0.1) (layer "F.Cu") (net 173))
  (segment (start 134.822252 115.765669) (end 134.8 115.768177) (width 0.1) (layer "F.Cu") (net 173))
  (segment (start 134.678183 115.069475) (end 134.662348 115.05364) (width 0.1) (layer "F.Cu") (net 173))
  (segment (start 135.3 115.668177) (end 135.297492 115.690429) (width 0.1) (layer "F.Cu") (net 173))
  (segment (start 135.290096 115.711565) (end 135.278183 115.730525) (width 0.1) (layer "F.Cu") (net 173))
  (segment (start 134.909903 115.088435) (end 134.902507 115.109571) (width 0.1) (layer "F.Cu") (net 173))
  (segment (start 134.3 115.668177) (end 134.3 115.131823) (width 0.1) (layer "F.Cu") (net 173))
  (segment (start 135.4 115.031823) (end 135.377747 115.034331) (width 0.1) (layer "F.Cu") (net 173))
  (segment (start 133.862348 115.05364) (end 133.843388 115.041727) (width 0.1) (layer "F.Cu") (net 173))
  (segment (start 135.3 115.131823) (end 135.3 115.668177) (width 0.1) (layer "F.Cu") (net 173))
  (segment (start 134.902507 115.109571) (end 134.9 115.131823) (width 0.1) (layer "F.Cu") (net 173))
  (segment (start 134.278183 115.069475) (end 134.262348 115.05364) (width 0.1) (layer "F.Cu") (net 173))
  (segment (start 134.121816 115.069475) (end 134.109903 115.088435) (width 0.1) (layer "F.Cu") (net 173))
  (segment (start 135.222252 115.765669) (end 135.2 115.768177) (width 0.1) (layer "F.Cu") (net 173))
  (segment (start 134.290096 115.088435) (end 134.278183 115.069475) (width 0.1) (layer "F.Cu") (net 173))
  (segment (start 133.956611 115.758273) (end 133.937651 115.74636) (width 0.1) (layer "F.Cu") (net 173))
  (segment (start 133.497492 115.477747) (end 133.490096 115.456611) (width 0.1) (layer "F.Cu") (net 173))
  (segment (start 134.537651 115.05364) (end 134.521816 115.069475) (width 0.1) (layer "F.Cu") (net 173))
  (segment (start 133.921816 115.730525) (end 133.909903 115.711565) (width 0.1) (layer "F.Cu") (net 173))
  (segment (start 133.777747 115.034331) (end 133.756611 115.041727) (width 0.1) (layer "F.Cu") (net 173))
  (segment (start 135.090096 115.088435) (end 135.078183 115.069475) (width 0.1) (layer "F.Cu") (net 173))
  (segment (start 134.337651 115.74636) (end 134.321816 115.730525) (width 0.1) (layer "F.Cu") (net 173))
  (segment (start 135.078183 115.069475) (end 135.062348 115.05364) (width 0.1) (layer "F.Cu") (net 173))
  (segment (start 134.102507 115.109571) (end 134.1 115.131823) (width 0.1) (layer "F.Cu") (net 173))
  (segment (start 135.043388 115.041727) (end 135.022252 115.034331) (width 0.1) (layer "F.Cu") (net 173))
  (segment (start 133.9 115.668177) (end 133.9 115.131823) (width 0.1) (layer "F.Cu") (net 173))
  (segment (start 135.062348 115.05364) (end 135.043388 115.041727) (width 0.1) (layer "F.Cu") (net 173))
  (segment (start 133.643388 115.758273) (end 133.622252 115.765669) (width 0.1) (layer "F.Cu") (net 173))
  (segment (start 134.878183 115.730525) (end 134.862348 115.74636) (width 0.1) (layer "F.Cu") (net 173))
  (segment (start 133.678183 115.730525) (end 133.662348 115.74636) (width 0.1) (layer "F.Cu") (net 173))
  (segment (start 133.5 115.668177) (end 133.5 115.5) (width 0.1) (layer "F.Cu") (net 173))
  (segment (start 133.890096 115.088435) (end 133.878183 115.069475) (width 0.1) (layer "F.Cu") (net 173))
  (segment (start 133.822252 115.034331) (end 133.8 115.031823) (width 0.1) (layer "F.Cu") (net 173))
  (segment (start 135.302507 115.109571) (end 135.3 115.131823) (width 0.1) (layer "F.Cu") (net 173))
  (segment (start 133.977747 115.765669) (end 133.956611 115.758273) (width 0.1) (layer "F.Cu") (net 173))
  (segment (start 133.5 115.5) (end 133.497492 115.477747) (width 0.1) (layer "F.Cu") (net 173))
  (segment (start 134.090096 115.711565) (end 134.078183 115.730525) (width 0.1) (layer "F.Cu") (net 173))
  (segment (start 135.497492 115.109571) (end 135.490096 115.088435) (width 0.1) (layer "F.Cu") (net 173))
  (segment (start 133.662348 115.74636) (end 133.643388 115.758273) (width 0.1) (layer "F.Cu") (net 173))
  (segment (start 134.709903 115.711565) (end 134.702507 115.690429) (width 0.1) (layer "F.Cu") (net 173))
  (segment (start 134.243388 115.041727) (end 134.222252 115.034331) (width 0.1) (layer "F.Cu") (net 173))
  (segment (start 134.502507 115.109571) (end 134.5 115.131823) (width 0.1) (layer "F.Cu") (net 173))
  (segment (start 135.297492 115.690429) (end 135.290096 115.711565) (width 0.1) (layer "F.Cu") (net 173))
  (segment (start 133.509903 115.711565) (end 133.502507 115.690429) (width 0.1) (layer "F.Cu") (net 173))
  (segment (start 134.862348 115.74636) (end 134.843388 115.758273) (width 0.1) (layer "F.Cu") (net 173))
  (segment (start 134.521816 115.069475) (end 134.509903 115.088435) (width 0.1) (layer "F.Cu") (net 173))
  (segment (start 134.7 115.131823) (end 134.697492 115.109571) (width 0.1) (layer "F.Cu") (net 173))
  (segment (start 134.156611 115.041727) (end 134.137651 115.05364) (width 0.1) (layer "F.Cu") (net 173))
  (segment (start 134.937651 115.05364) (end 134.921816 115.069475) (width 0.1) (layer "F.Cu") (net 173))
  (segment (start 135.262348 115.74636) (end 135.243388 115.758273) (width 0.1) (layer "F.Cu") (net 173))
  (segment (start 134.6 115.031823) (end 134.577747 115.034331) (width 0.1) (layer "F.Cu") (net 173))
  (segment (start 135.309903 115.088435) (end 135.302507 115.109571) (width 0.1) (layer "F.Cu") (net 173))
  (segment (start 134.977747 115.034331) (end 134.956611 115.041727) (width 0.1) (layer "F.Cu") (net 173))
  (segment (start 134.509903 115.088435) (end 134.502507 115.109571) (width 0.1) (layer "F.Cu") (net 173))
  (segment (start 134.702507 115.690429) (end 134.7 115.668177) (width 0.1) (layer "F.Cu") (net 173))
  (segment (start 134.4 115.768177) (end 134.377747 115.765669) (width 0.1) (layer "F.Cu") (net 173))
  (segment (start 134.921816 115.069475) (end 134.909903 115.088435) (width 0.1) (layer "F.Cu") (net 173))
  (segment (start 134.297492 115.109571) (end 134.290096 115.088435) (width 0.1) (layer "F.Cu") (net 173))
  (segment (start 134.109903 115.088435) (end 134.102507 115.109571) (width 0.1) (layer "F.Cu") (net 173))
  (segment (start 134.062348 115.74636) (end 134.043388 115.758273) (width 0.1) (layer "F.Cu") (net 173))
  (segment (start 135 115.031823) (end 134.977747 115.034331) (width 0.1) (layer "F.Cu") (net 173))
  (segment (start 133.897492 115.109571) (end 133.890096 115.088435) (width 0.1) (layer "F.Cu") (net 173))
  (segment (start 135.537651 115.378184) (end 135.521816 115.362349) (width 0.1) (layer "F.Cu") (net 173))
  (segment (start 133.721816 115.069475) (end 133.709903 115.088435) (width 0.1) (layer "F.Cu") (net 173))
  (segment (start 135.1 115.668177) (end 135.1 115.131823) (width 0.1) (layer "F.Cu") (net 173))
  (segment (start 134.721816 115.730525) (end 134.709903 115.711565) (width 0.1) (layer "F.Cu") (net 173))
  (segment (start 135.243388 115.758273) (end 135.222252 115.765669) (width 0.1) (layer "F.Cu") (net 173))
  (segment (start 133.878183 115.069475) (end 133.862348 115.05364) (width 0.1) (layer "F.Cu") (net 173))
  (segment (start 134.956611 115.041727) (end 134.937651 115.05364) (width 0.1) (layer "F.Cu") (net 173))
  (segment (start 134.737651 115.74636) (end 134.721816 115.730525) (width 0.1) (layer "F.Cu") (net 173))
  (segment (start 135.556611 115.390097) (end 135.537651 115.378184) (width 0.1) (layer "F.Cu") (net 173))
  (segment (start 133.843388 115.041727) (end 133.822252 115.034331) (width 0.1) (layer "F.Cu") (net 173))
  (segment (start 134.9 115.668177) (end 134.897492 115.690429) (width 0.1) (layer "F.Cu") (net 173))
  (segment (start 135.1 115.131823) (end 135.097492 115.109571) (width 0.1) (layer "F.Cu") (net 173))
  (segment (start 133.622252 115.765669) (end 133.6 115.768177) (width 0.1) (layer "F.Cu") (net 173))
  (segment (start 134.1 115.668177) (end 134.097492 115.690429) (width 0.1) (layer "F.Cu") (net 173))
  (segment (start 135.5 115.131823) (end 135.497492 115.109571) (width 0.1) (layer "F.Cu") (net 173))
  (segment (start 133.478183 115.437651) (end 133.462348 115.421816) (width 0.1) (layer "F.Cu") (net 173))
  (segment (start 141.279852 113) (end 138.22 113) (width 0.1) (layer "F.Cu") (net 173))
  (segment (start 134.078183 115.730525) (end 134.062348 115.74636) (width 0.1) (layer "F.Cu") (net 173))
  (segment (start 130.22 115.4) (end 127.72 112.9) (width 0.1) (layer "F.Cu") (net 173))
  (segment (start 134.302507 115.690429) (end 134.3 115.668177) (width 0.1) (layer "F.Cu") (net 173))
  (segment (start 134.262348 115.05364) (end 134.243388 115.041727) (width 0.1) (layer "F.Cu") (net 173))
  (segment (start 134.443388 115.758273) (end 134.422252 115.765669) (width 0.1) (layer "F.Cu") (net 173))
  (segment (start 133.902507 115.690429) (end 133.9 115.668177) (width 0.1) (layer "F.Cu") (net 173))
  (segment (start 133.556611 115.758273) (end 133.537651 115.74636) (width 0.1) (layer "F.Cu") (net 173))
  (segment (start 134.3 115.131823) (end 134.297492 115.109571) (width 0.1) (layer "F.Cu") (net 173))
  (segment (start 134.756611 115.758273) (end 134.737651 115.74636) (width 0.1) (layer "F.Cu") (net 173))
  (segment (start 135.321816 115.069475) (end 135.309903 115.088435) (width 0.1) (layer "F.Cu") (net 173))
  (segment (start 135.422252 115.034331) (end 135.4 115.031823) (width 0.1) (layer "F.Cu") (net 173))
  (segment (start 138.22 113) (end 135.82 115.4) (width 0.1) (layer "F.Cu") (net 173))
  (segment (start 143.295 114.265) (end 142.97 113.94) (width 0.1) (layer "F.Cu") (net 173))
  (segment (start 134.9 115.131823) (end 134.9 115.668177) (width 0.1) (layer "F.Cu") (net 173))
  (segment (start 134.690096 115.088435) (end 134.678183 115.069475) (width 0.1) (layer "F.Cu") (net 173))
  (segment (start 133.721816 118.437651) (end 133.709903 118.456611) (width 0.1) (layer "F.Cu") (net 174))
  (segment (start 132.297492 118.477747) (end 132.290096 118.456611) (width 0.1) (layer "F.Cu") (net 174))
  (segment (start 133.156611 118.770961) (end 133.137651 118.759048) (width 0.1) (layer "F.Cu") (net 174))
  (segment (start 132.662348 118.040952) (end 132.643388 118.029039) (width 0.1) (layer "F.Cu") (net 174))
  (segment (start 132.537651 118.040952) (end 132.521816 118.056787) (width 0.1) (layer "F.Cu") (net 174))
  (segment (start 132.490096 118.724253) (end 132.478183 118.743213) (width 0.1) (layer "F.Cu") (net 174))
  (segment (start 132.822252 118.778357) (end 132.8 118.780865) (width 0.1) (layer "F.Cu") (net 174))
  (segment (start 132.721816 118.743213) (end 132.709903 118.724253) (width 0.1) (layer "F.Cu") (net 174))
  (segment (start 133.097492 118.096883) (end 133.090096 118.075747) (width 0.1) (layer "F.Cu") (net 174))
  (segment (start 133.1 118.119135) (end 133.097492 118.096883) (width 0.1) (layer "F.Cu") (net 174))
  (segment (start 133.302507 118.096883) (end 133.3 118.119135) (width 0.1) (layer "F.Cu") (net 174))
  (segment (start 133.243388 118.770961) (end 133.222252 118.778357) (width 0.1) (layer "F.Cu") (net 174))
  (segment (start 133.3 118.119135) (end 133.3 118.680865) (width 0.1) (layer "F.Cu") (net 174))
  (segment (start 132.4 118.780865) (end 132.377747 118.778357) (width 0.1) (layer "F.Cu") (net 174))
  (segment (start 132.3 118.680865) (end 132.3 118.5) (width 0.1) (layer "F.Cu") (net 174))
  (segment (start 133.137651 118.759048) (end 133.121816 118.743213) (width 0.1) (layer "F.Cu") (net 174))
  (segment (start 133.377747 118.021643) (end 133.356611 118.029039) (width 0.1) (layer "F.Cu") (net 174))
  (segment (start 132.443388 118.770961) (end 132.422252 118.778357) (width 0.1) (layer "F.Cu") (net 174))
  (segment (start 132.678183 118.056787) (end 132.662348 118.040952) (width 0.1) (layer "F.Cu") (net 174))
  (segment (start 133.121816 118.743213) (end 133.109903 118.724253) (width 0.1) (layer "F.Cu") (net 174))
  (segment (start 133.321816 118.056787) (end 133.309903 118.075747) (width 0.1) (layer "F.Cu") (net 174))
  (segment (start 132.709903 118.724253) (end 132.702507 118.703117) (width 0.1) (layer "F.Cu") (net 174))
  (segment (start 133.356611 118.029039) (end 133.337651 118.040952) (width 0.1) (layer "F.Cu") (net 174))
  (segment (start 132.690096 118.075747) (end 132.678183 118.056787) (width 0.1) (layer "F.Cu") (net 174))
  (segment (start 132.777747 118.778357) (end 132.756611 118.770961) (width 0.1) (layer "F.Cu") (net 174))
  (segment (start 133.109903 118.724253) (end 133.102507 118.703117) (width 0.1) (layer "F.Cu") (net 174))
  (segment (start 132.7 118.119135) (end 132.697492 118.096883) (width 0.1) (layer "F.Cu") (net 174))
  (segment (start 132.278183 118.437651) (end 132.262348 118.421816) (width 0.1) (layer "F.Cu") (net 174))
  (segment (start 132.956611 118.029039) (end 132.937651 118.040952) (width 0.1) (layer "F.Cu") (net 174))
  (segment (start 133.521816 118.743213) (end 133.509903 118.724253) (width 0.1) (layer "F.Cu") (net 174))
  (segment (start 133.662348 118.759048) (end 133.643388 118.770961) (width 0.1) (layer "F.Cu") (net 174))
  (segment (start 133.622252 118.778357) (end 133.6 118.780865) (width 0.1) (layer "F.Cu") (net 174))
  (segment (start 132.521816 118.056787) (end 132.509903 118.075747) (width 0.1) (layer "F.Cu") (net 174))
  (segment (start 132.2 118.4) (end 130.5 118.4) (width 0.1) (layer "F.Cu") (net 174))
  (segment (start 133.478183 118.056787) (end 133.462348 118.040952) (width 0.1) (layer "F.Cu") (net 174))
  (segment (start 133.643388 118.770961) (end 133.622252 118.778357) (width 0.1) (layer "F.Cu") (net 174))
  (segment (start 142.97 115.89) (end 140.59 115.89) (width 0.1) (layer "F.Cu") (net 174))
  (segment (start 132.737651 118.759048) (end 132.721816 118.743213) (width 0.1) (layer "F.Cu") (net 174))
  (segment (start 133.222252 118.778357) (end 133.2 118.780865) (width 0.1) (layer "F.Cu") (net 174))
  (segment (start 132.222252 118.402507) (end 132.2 118.4) (width 0.1) (layer "F.Cu") (net 174))
  (segment (start 132.377747 118.778357) (end 132.356611 118.770961) (width 0.1) (layer "F.Cu") (net 174))
  (segment (start 129.46 117.36) (end 129.46 117.14999) (width 0.1) (layer "F.Cu") (net 174))
  (segment (start 132.8 118.780865) (end 132.777747 118.778357) (width 0.1) (layer "F.Cu") (net 174))
  (segment (start 133.309903 118.075747) (end 133.302507 118.096883) (width 0.1) (layer "F.Cu") (net 174))
  (segment (start 132.937651 118.040952) (end 132.921816 118.056787) (width 0.1) (layer "F.Cu") (net 174))
  (segment (start 125.01 114.39) (end 126.18 114.39) (width 0.15) (layer "F.Cu") (net 174))
  (segment (start 133.462348 118.040952) (end 133.443388 118.029039) (width 0.1) (layer "F.Cu") (net 174))
  (segment (start 133.262348 118.759048) (end 133.243388 118.770961) (width 0.1) (layer "F.Cu") (net 174))
  (segment (start 132.290096 118.456611) (end 132.278183 118.437651) (width 0.1) (layer "F.Cu") (net 174))
  (segment (start 133.290096 118.724253) (end 133.278183 118.743213) (width 0.1) (layer "F.Cu") (net 174))
  (segment (start 133 118.019135) (end 132.977747 118.021643) (width 0.1) (layer "F.Cu") (net 174))
  (segment (start 133.709903 118.456611) (end 133.702507 118.477747) (width 0.1) (layer "F.Cu") (net 174))
  (segment (start 133.102507 118.703117) (end 133.1 118.680865) (width 0.1) (layer "F.Cu") (net 174))
  (segment (start 133.2 118.780865) (end 133.177747 118.778357) (width 0.1) (layer "F.Cu") (net 174))
  (segment (start 133.278183 118.743213) (end 133.262348 118.759048) (width 0.1) (layer "F.Cu") (net 174))
  (segment (start 132.902507 118.096883) (end 132.9 118.119135) (width 0.1) (layer "F.Cu") (net 174))
  (segment (start 132.321816 118.743213) (end 132.309903 118.724253) (width 0.1) (layer "F.Cu") (net 174))
  (segment (start 133.3 118.680865) (end 133.297492 118.703117) (width 0.1) (layer "F.Cu") (net 174))
  (segment (start 132.843388 118.770961) (end 132.822252 118.778357) (width 0.1) (layer "F.Cu") (net 174))
  (segment (start 132.878183 118.743213) (end 132.862348 118.759048) (width 0.1) (layer "F.Cu") (net 174))
  (segment (start 133.8 118.4) (end 133.777747 118.402507) (width 0.1) (layer "F.Cu") (net 174))
  (segment (start 132.337651 118.759048) (end 132.321816 118.743213) (width 0.1) (layer "F.Cu") (net 174))
  (segment (start 133.5 118.119135) (end 133.497492 118.096883) (width 0.1) (layer "F.Cu") (net 174))
  (segment (start 138.150011 115.689989) (end 135.44 118.4) (width 0.1) (layer "F.Cu") (net 174))
  (segment (start 133.5 118.680865) (end 133.5 118.119135) (width 0.1) (layer "F.Cu") (net 174))
  (segment (start 132.243388 118.409903) (end 132.222252 118.402507) (width 0.1) (layer "F.Cu") (net 174))
  (segment (start 132.262348 118.421816) (end 132.243388 118.409903) (width 0.1) (layer "F.Cu") (net 174))
  (segment (start 132.643388 118.029039) (end 132.622252 118.021643) (width 0.1) (layer "F.Cu") (net 174))
  (segment (start 132.702507 118.703117) (end 132.7 118.680865) (width 0.1) (layer "F.Cu") (net 174))
  (segment (start 124.5 114.9) (end 125.01 114.39) (width 0.15) (layer "F.Cu") (net 174))
  (segment (start 133.556611 118.770961) (end 133.537651 118.759048) (width 0.1) (layer "F.Cu") (net 174))
  (segment (start 133.078183 118.056787) (end 133.062348 118.040952) (width 0.1) (layer "F.Cu") (net 174))
  (segment (start 133.756611 118.409903) (end 133.737651 118.421816) (width 0.1) (layer "F.Cu") (net 174))
  (segment (start 133.6 118.780865) (end 133.577747 118.778357) (width 0.1) (layer "F.Cu") (net 174))
  (segment (start 132.302507 118.703117) (end 132.3 118.680865) (width 0.1) (layer "F.Cu") (net 174))
  (segment (start 132.890096 118.724253) (end 132.878183 118.743213) (width 0.1) (layer "F.Cu") (net 174))
  (segment (start 132.422252 118.778357) (end 132.4 118.780865) (width 0.1) (layer "F.Cu") (net 174))
  (segment (start 133.7 118.680865) (end 133.697492 118.703117) (width 0.1) (layer "F.Cu") (net 174))
  (segment (start 132.622252 118.021643) (end 132.6 118.019135) (width 0.1) (layer "F.Cu") (net 174))
  (segment (start 132.756611 118.770961) (end 132.737651 118.759048) (width 0.1) (layer "F.Cu") (net 174))
  (segment (start 132.5 118.119135) (end 132.5 118.680865) (width 0.1) (layer "F.Cu") (net 174))
  (segment (start 132.909903 118.075747) (end 132.902507 118.096883) (width 0.1) (layer "F.Cu") (net 174))
  (segment (start 133.1 118.680865) (end 133.1 118.119135) (width 0.1) (layer "F.Cu") (net 174))
  (segment (start 133.678183 118.743213) (end 133.662348 118.759048) (width 0.1) (layer "F.Cu") (net 174))
  (segment (start 133.502507 118.703117) (end 133.5 118.680865) (width 0.1) (layer "F.Cu") (net 174))
  (segment (start 133.297492 118.703117) (end 133.290096 118.724253) (width 0.1) (layer "F.Cu") (net 174))
  (segment (start 133.702507 118.477747) (end 133.7 118.5) (width 0.1) (layer "F.Cu") (net 174))
  (segment (start 132.6 118.019135) (end 132.577747 118.021643) (width 0.1) (layer "F.Cu") (net 174))
  (segment (start 132.5 118.680865) (end 132.497492 118.703117) (width 0.1) (layer "F.Cu") (net 174))
  (segment (start 132.577747 118.021643) (end 132.556611 118.029039) (width 0.1) (layer "F.Cu") (net 174))
  (segment (start 133.090096 118.075747) (end 133.078183 118.056787) (width 0.1) (layer "F.Cu") (net 174))
  (segment (start 130.5 118.4) (end 129.46 117.36) (width 0.1) (layer "F.Cu") (net 174))
  (segment (start 132.897492 118.703117) (end 132.890096 118.724253) (width 0.1) (layer "F.Cu") (net 174))
  (segment (start 133.337651 118.040952) (end 133.321816 118.056787) (width 0.1) (layer "F.Cu") (net 174))
  (segment (start 132.921816 118.056787) (end 132.909903 118.075747) (width 0.1) (layer "F.Cu") (net 174))
  (segment (start 133.7 118.5) (end 133.7 118.680865) (width 0.1) (layer "F.Cu") (net 174))
  (segment (start 132.556611 118.029039) (end 132.537651 118.040952) (width 0.1) (layer "F.Cu") (net 174))
  (segment (start 133.737651 118.421816) (end 133.721816 118.437651) (width 0.1) (layer "F.Cu") (net 174))
  (segment (start 133.177747 118.778357) (end 133.156611 118.770961) (width 0.1) (layer "F.Cu") (net 174))
  (segment (start 133.062348 118.040952) (end 133.043388 118.029039) (width 0.1) (layer "F.Cu") (net 174))
  (segment (start 132.7 118.680865) (end 132.7 118.119135) (width 0.1) (layer "F.Cu") (net 174))
  (segment (start 132.9 118.119135) (end 132.9 118.680865) (width 0.1) (layer "F.Cu") (net 174))
  (segment (start 133.509903 118.724253) (end 133.502507 118.703117) (width 0.1) (layer "F.Cu") (net 174))
  (segment (start 132.502507 118.096883) (end 132.5 118.119135) (width 0.1) (layer "F.Cu") (net 174))
  (segment (start 132.478183 118.743213) (end 132.462348 118.759048) (width 0.1) (layer "F.Cu") (net 174))
  (segment (start 132.9 118.680865) (end 132.897492 118.703117) (width 0.1) (layer "F.Cu") (net 174))
  (segment (start 133.577747 118.778357) (end 133.556611 118.770961) (width 0.1) (layer "F.Cu") (net 174))
  (segment (start 140.389989 115.689989) (end 138.150011 115.689989) (width 0.1) (layer "F.Cu") (net 174))
  (segment (start 133.697492 118.703117) (end 133.690096 118.724253) (width 0.1) (layer "F.Cu") (net 174))
  (segment (start 132.697492 118.096883) (end 132.690096 118.075747) (width 0.1) (layer "F.Cu") (net 174))
  (segment (start 133.422252 118.021643) (end 133.4 118.019135) (width 0.1) (layer "F.Cu") (net 174))
  (segment (start 140.59 115.89) (end 140.389989 115.689989) (width 0.1) (layer "F.Cu") (net 174))
  (segment (start 133.022252 118.021643) (end 133 118.019135) (width 0.1) (layer "F.Cu") (net 174))
  (segment (start 132.509903 118.075747) (end 132.502507 118.096883) (width 0.1) (layer "F.Cu") (net 174))
  (segment (start 133.490096 118.075747) (end 133.478183 118.056787) (width 0.1) (layer "F.Cu") (net 174))
  (segment (start 133.497492 118.096883) (end 133.490096 118.075747) (width 0.1) (layer "F.Cu") (net 174))
  (segment (start 133.043388 118.029039) (end 133.022252 118.021643) (width 0.1) (layer "F.Cu") (net 174))
  (segment (start 133.4 118.019135) (end 133.377747 118.021643) (width 0.1) (layer "F.Cu") (net 174))
  (segment (start 132.977747 118.021643) (end 132.956611 118.029039) (width 0.1) (layer "F.Cu") (net 174))
  (segment (start 132.3 118.5) (end 132.297492 118.477747) (width 0.1) (layer "F.Cu") (net 174))
  (segment (start 132.356611 118.770961) (end 132.337651 118.759048) (width 0.1) (layer "F.Cu") (net 174))
  (segment (start 132.497492 118.703117) (end 132.490096 118.724253) (width 0.1) (layer "F.Cu") (net 174))
  (segment (start 132.462348 118.759048) (end 132.443388 118.770961) (width 0.1) (layer "F.Cu") (net 174))
  (segment (start 133.537651 118.759048) (end 133.521816 118.743213) (width 0.1) (layer "F.Cu") (net 174))
  (segment (start 132.862348 118.759048) (end 132.843388 118.770961) (width 0.1) (layer "F.Cu") (net 174))
  (segment (start 143.295 116.215) (end 142.97 115.89) (width 0.1) (layer "F.Cu") (net 174))
  (segment (start 132.309903 118.724253) (end 132.302507 118.703117) (width 0.1) (layer "F.Cu") (net 174))
  (segment (start 135.44 118.4) (end 133.8 118.4) (width 0.1) (layer "F.Cu") (net 174))
  (segment (start 133.443388 118.029039) (end 133.422252 118.021643) (width 0.1) (layer "F.Cu") (net 174))
  (segment (start 133.777747 118.402507) (end 133.756611 118.409903) (width 0.1) (layer "F.Cu") (net 174))
  (segment (start 133.690096 118.724253) (end 133.678183 118.743213) (width 0.1) (layer "F.Cu") (net 174))
  (via (at 126.18 114.39) (size 0.55) (drill 0.15) (layers "F.Cu" "B.Cu") (net 174))
  (via (at 129.46 117.14999) (size 0.55) (drill 0.15) (layers "F.Cu" "B.Cu") (net 174))
  (segment (start 126.18 114.39) (end 126.70001 114.39) (width 0.125) (layer "In2.Cu") (net 174))
  (segment (start 126.70001 114.39) (end 129.46 117.14999) (width 0.125) (layer "In2.Cu") (net 174))
  (segment (start 134.678183 117.762348) (end 134.662348 117.778183) (width 0.1) (layer "F.Cu") (net 175))
  (segment (start 133.862348 117.778183) (end 133.843388 117.790096) (width 0.1) (layer "F.Cu") (net 175))
  (segment (start 135.377747 117.797492) (end 135.356611 117.790096) (width 0.1) (layer "F.Cu") (net 175))
  (segment (start 135.537651 117.421816) (end 135.521816 117.437651) (width 0.1) (layer "F.Cu") (net 175))
  (segment (start 134.737651 117.021817) (end 134.721816 117.037652) (width 0.1) (layer "F.Cu") (net 175))
  (segment (start 134.462348 117.021817) (end 134.443388 117.009904) (width 0.1) (layer "F.Cu") (net 175))
  (segment (start 134.3 117.7) (end 134.297492 117.722252) (width 0.1) (layer "F.Cu") (net 175))
  (segment (start 125.5 114.9) (end 128.015 114.9) (width 0.1) (layer "F.Cu") (net 175))
  (segment (start 135.1 117.1) (end 135.1 117.7) (width 0.1) (layer "F.Cu") (net 175))
  (segment (start 135.5 117.5) (end 135.5 117.7) (width 0.1) (layer "F.Cu") (net 175))
  (segment (start 135.502507 117.477747) (end 135.5 117.5) (width 0.1) (layer "F.Cu") (net 175))
  (segment (start 135 117.8) (end 134.977747 117.797492) (width 0.1) (layer "F.Cu") (net 175))
  (segment (start 134.022252 117.002508) (end 134 117) (width 0.1) (layer "F.Cu") (net 175))
  (segment (start 134.902507 117.722252) (end 134.9 117.7) (width 0.1) (layer "F.Cu") (net 175))
  (segment (start 133.843388 117.790096) (end 133.822252 117.797492) (width 0.1) (layer "F.Cu") (net 175))
  (segment (start 133.777747 117.797492) (end 133.756611 117.790096) (width 0.1) (layer "F.Cu") (net 175))
  (segment (start 135.4 117.8) (end 135.377747 117.797492) (width 0.1) (layer "F.Cu") (net 175))
  (segment (start 134.6 117.8) (end 134.577747 117.797492) (width 0.1) (layer "F.Cu") (net 175))
  (segment (start 135.078183 117.762348) (end 135.062348 117.778183) (width 0.1) (layer "F.Cu") (net 175))
  (segment (start 133.909903 117.056612) (end 133.902507 117.077748) (width 0.1) (layer "F.Cu") (net 175))
  (segment (start 134.756611 117.009904) (end 134.737651 117.021817) (width 0.1) (layer "F.Cu") (net 175))
  (segment (start 135.156611 117.009904) (end 135.137651 117.021817) (width 0.1) (layer "F.Cu") (net 175))
  (segment (start 134.102507 117.722252) (end 134.1 117.7) (width 0.1) (layer "F.Cu") (net 175))
  (segment (start 134.577747 117.797492) (end 134.556611 117.790096) (width 0.1) (layer "F.Cu") (net 175))
  (segment (start 135.102507 117.077748) (end 135.1 117.1) (width 0.1) (layer "F.Cu") (net 175))
  (segment (start 135.3 117.7) (end 135.3 117.1) (width 0.1) (layer "F.Cu") (net 175))
  (segment (start 135.1 117.7) (end 135.097492 117.722252) (width 0.1) (layer "F.Cu") (net 175))
  (segment (start 135.109903 117.056612) (end 135.102507 117.077748) (width 0.1) (layer "F.Cu") (net 175))
  (segment (start 135.356611 117.790096) (end 135.337651 117.778183) (width 0.1) (layer "F.Cu") (net 175))
  (segment (start 135.043388 117.790096) (end 135.022252 117.797492) (width 0.1) (layer "F.Cu") (net 175))
  (segment (start 135.062348 117.778183) (end 135.043388 117.790096) (width 0.1) (layer "F.Cu") (net 175))
  (segment (start 134.556611 117.790096) (end 134.537651 117.778183) (width 0.1) (layer "F.Cu") (net 175))
  (segment (start 134.843388 117.009904) (end 134.822252 117.002508) (width 0.1) (layer "F.Cu") (net 175))
  (segment (start 135.337651 117.778183) (end 135.321816 117.762348) (width 0.1) (layer "F.Cu") (net 175))
  (segment (start 135.577747 117.402507) (end 135.556611 117.409903) (width 0.1) (layer "F.Cu") (net 175))
  (segment (start 135.5 117.7) (end 135.497492 117.722252) (width 0.1) (layer "F.Cu") (net 175))
  (segment (start 134.521816 117.762348) (end 134.509903 117.743388) (width 0.1) (layer "F.Cu") (net 175))
  (segment (start 134.422252 117.002508) (end 134.4 117) (width 0.1) (layer "F.Cu") (net 175))
  (segment (start 134.977747 117.797492) (end 134.956611 117.790096) (width 0.1) (layer "F.Cu") (net 175))
  (segment (start 133.702507 117.722252) (end 133.7 117.7) (width 0.1) (layer "F.Cu") (net 175))
  (segment (start 133.9 117.1) (end 133.9 117.7) (width 0.1) (layer "F.Cu") (net 175))
  (segment (start 135.79 117.4) (end 135.6 117.4) (width 0.1) (layer "F.Cu") (net 175))
  (segment (start 135.462348 117.778183) (end 135.443388 117.790096) (width 0.1) (layer "F.Cu") (net 175))
  (segment (start 133.956611 117.009904) (end 133.937651 117.021817) (width 0.1) (layer "F.Cu") (net 175))
  (segment (start 135.290096 117.056612) (end 135.278183 117.037652) (width 0.1) (layer "F.Cu") (net 175))
  (segment (start 134.478183 117.037652) (end 134.462348 117.021817) (width 0.1) (layer "F.Cu") (net 175))
  (segment (start 134.777747 117.002508) (end 134.756611 117.009904) (width 0.1) (layer "F.Cu") (net 175))
  (segment (start 134.297492 117.722252) (end 134.290096 117.743388) (width 0.1) (layer "F.Cu") (net 175))
  (segment (start 133.678183 117.437651) (end 133.662348 117.421816) (width 0.1) (layer "F.Cu") (net 175))
  (segment (start 134.2 117.8) (end 134.177747 117.797492) (width 0.1) (layer "F.Cu") (net 175))
  (segment (start 135.478183 117.762348) (end 135.462348 117.778183) (width 0.1) (layer "F.Cu") (net 175))
  (segment (start 135.243388 117.009904) (end 135.222252 117.002508) (width 0.1) (layer "F.Cu") (net 175))
  (segment (start 141.026265 115.24) (end 140.386265 114.6) (width 0.1) (layer "F.Cu") (net 175))
  (segment (start 134.822252 117.002508) (end 134.8 117) (width 0.1) (layer "F.Cu") (net 175))
  (segment (start 134.137651 117.778183) (end 134.121816 117.762348) (width 0.1) (layer "F.Cu") (net 175))
  (segment (start 135.490096 117.743388) (end 135.478183 117.762348) (width 0.1) (layer "F.Cu") (net 175))
  (segment (start 133.822252 117.797492) (end 133.8 117.8) (width 0.1) (layer "F.Cu") (net 175))
  (segment (start 134.921816 117.762348) (end 134.909903 117.743388) (width 0.1) (layer "F.Cu") (net 175))
  (segment (start 134.177747 117.797492) (end 134.156611 117.790096) (width 0.1) (layer "F.Cu") (net 175))
  (segment (start 133.878183 117.762348) (end 133.862348 117.778183) (width 0.1) (layer "F.Cu") (net 175))
  (segment (start 134.309903 117.056612) (end 134.302507 117.077748) (width 0.1) (layer "F.Cu") (net 175))
  (segment (start 135.097492 117.722252) (end 135.090096 117.743388) (width 0.1) (layer "F.Cu") (net 175))
  (segment (start 134.878183 117.037652) (end 134.862348 117.021817) (width 0.1) (layer "F.Cu") (net 175))
  (segment (start 134.862348 117.021817) (end 134.843388 117.009904) (width 0.1) (layer "F.Cu") (net 175))
  (segment (start 133.921816 117.037652) (end 133.909903 117.056612) (width 0.1) (layer "F.Cu") (net 175))
  (segment (start 134.662348 117.778183) (end 134.643388 117.790096) (width 0.1) (layer "F.Cu") (net 175))
  (segment (start 134.121816 117.762348) (end 134.109903 117.743388) (width 0.1) (layer "F.Cu") (net 175))
  (segment (start 134.709903 117.056612) (end 134.702507 117.077748) (width 0.1) (layer "F.Cu") (net 175))
  (segment (start 134.356611 117.009904) (end 134.337651 117.021817) (width 0.1) (layer "F.Cu") (net 175))
  (segment (start 134.5 117.7) (end 134.5 117.1) (width 0.1) (layer "F.Cu") (net 175))
  (segment (start 135.509903 117.456611) (end 135.502507 117.477747) (width 0.1) (layer "F.Cu") (net 175))
  (segment (start 134.690096 117.743388) (end 134.678183 117.762348) (width 0.1) (layer "F.Cu") (net 175))
  (segment (start 133.697492 117.477747) (end 133.690096 117.456611) (width 0.1) (layer "F.Cu") (net 175))
  (segment (start 134.697492 117.722252) (end 134.690096 117.743388) (width 0.1) (layer "F.Cu") (net 175))
  (segment (start 135.321816 117.762348) (end 135.309903 117.743388) (width 0.1) (layer "F.Cu") (net 175))
  (segment (start 135.137651 117.021817) (end 135.121816 117.037652) (width 0.1) (layer "F.Cu") (net 175))
  (segment (start 134.509903 117.743388) (end 134.502507 117.722252) (width 0.1) (layer "F.Cu") (net 175))
  (segment (start 134.702507 117.077748) (end 134.7 117.1) (width 0.1) (layer "F.Cu") (net 175))
  (segment (start 138.59 114.6) (end 135.79 117.4) (width 0.1) (layer "F.Cu") (net 175))
  (segment (start 133.756611 117.790096) (end 133.737651 117.778183) (width 0.1) (layer "F.Cu") (net 175))
  (segment (start 134.1 117.7) (end 134.1 117.1) (width 0.1) (layer "F.Cu") (net 175))
  (segment (start 133.709903 117.743388) (end 133.702507 117.722252) (width 0.1) (layer "F.Cu") (net 175))
  (segment (start 134.9 117.1) (end 134.897492 117.077748) (width 0.1) (layer "F.Cu") (net 175))
  (segment (start 135.497492 117.722252) (end 135.490096 117.743388) (width 0.1) (layer "F.Cu") (net 175))
  (segment (start 133.937651 117.021817) (end 133.921816 117.037652) (width 0.1) (layer "F.Cu") (net 175))
  (segment (start 133.622252 117.402507) (end 133.6 117.4) (width 0.1) (layer "F.Cu") (net 175))
  (segment (start 134.156611 117.790096) (end 134.137651 117.778183) (width 0.1) (layer "F.Cu") (net 175))
  (segment (start 134.7 117.7) (end 134.697492 117.722252) (width 0.1) (layer "F.Cu") (net 175))
  (segment (start 134.377747 117.002508) (end 134.356611 117.009904) (width 0.1) (layer "F.Cu") (net 175))
  (segment (start 134.278183 117.762348) (end 134.262348 117.778183) (width 0.1) (layer "F.Cu") (net 175))
  (segment (start 133.737651 117.778183) (end 133.721816 117.762348) (width 0.1) (layer "F.Cu") (net 175))
  (segment (start 134.337651 117.021817) (end 134.321816 117.037652) (width 0.1) (layer "F.Cu") (net 175))
  (segment (start 134.4 117) (end 134.377747 117.002508) (width 0.1) (layer "F.Cu") (net 175))
  (segment (start 135.2 117) (end 135.177747 117.002508) (width 0.1) (layer "F.Cu") (net 175))
  (segment (start 143.295 115.565) (end 142.97 115.24) (width 0.1) (layer "F.Cu") (net 175))
  (segment (start 134.5 117.1) (end 134.497492 117.077748) (width 0.1) (layer "F.Cu") (net 175))
  (segment (start 134.622252 117.797492) (end 134.6 117.8) (width 0.1) (layer "F.Cu") (net 175))
  (segment (start 134.062348 117.021817) (end 134.043388 117.009904) (width 0.1) (layer "F.Cu") (net 175))
  (segment (start 134.643388 117.790096) (end 134.622252 117.797492) (width 0.1) (layer "F.Cu") (net 175))
  (segment (start 134.290096 117.743388) (end 134.278183 117.762348) (width 0.1) (layer "F.Cu") (net 175))
  (segment (start 135.556611 117.409903) (end 135.537651 117.421816) (width 0.1) (layer "F.Cu") (net 175))
  (segment (start 135.443388 117.790096) (end 135.422252 117.797492) (width 0.1) (layer "F.Cu") (net 175))
  (segment (start 134.956611 117.790096) (end 134.937651 117.778183) (width 0.1) (layer "F.Cu") (net 175))
  (segment (start 133.721816 117.762348) (end 133.709903 117.743388) (width 0.1) (layer "F.Cu") (net 175))
  (segment (start 134.890096 117.056612) (end 134.878183 117.037652) (width 0.1) (layer "F.Cu") (net 175))
  (segment (start 133.890096 117.743388) (end 133.878183 117.762348) (width 0.1) (layer "F.Cu") (net 175))
  (segment (start 135.309903 117.743388) (end 135.302507 117.722252) (width 0.1) (layer "F.Cu") (net 175))
  (segment (start 134.443388 117.009904) (end 134.422252 117.002508) (width 0.1) (layer "F.Cu") (net 175))
  (segment (start 134.090096 117.056612) (end 134.078183 117.037652) (width 0.1) (layer "F.Cu") (net 175))
  (segment (start 134.502507 117.722252) (end 134.5 117.7) (width 0.1) (layer "F.Cu") (net 175))
  (segment (start 133.8 117.8) (end 133.777747 117.797492) (width 0.1) (layer "F.Cu") (net 175))
  (segment (start 134.490096 117.056612) (end 134.478183 117.037652) (width 0.1) (layer "F.Cu") (net 175))
  (segment (start 134.078183 117.037652) (end 134.062348 117.021817) (width 0.1) (layer "F.Cu") (net 175))
  (segment (start 134.937651 117.778183) (end 134.921816 117.762348) (width 0.1) (layer "F.Cu") (net 175))
  (segment (start 133.9 117.7) (end 133.897492 117.722252) (width 0.1) (layer "F.Cu") (net 175))
  (segment (start 135.297492 117.077748) (end 135.290096 117.056612) (width 0.1) (layer "F.Cu") (net 175))
  (segment (start 130.515 117.4) (end 128.015 114.9) (width 0.1) (layer "F.Cu") (net 175))
  (segment (start 134.537651 117.778183) (end 134.521816 117.762348) (width 0.1) (layer "F.Cu") (net 175))
  (segment (start 133.6 117.4) (end 130.515 117.4) (width 0.1) (layer "F.Cu") (net 175))
  (segment (start 135.262348 117.021817) (end 135.243388 117.009904) (width 0.1) (layer "F.Cu") (net 175))
  (segment (start 142.97 115.24) (end 141.026265 115.24) (width 0.1) (layer "F.Cu") (net 175))
  (segment (start 134.097492 117.077748) (end 134.090096 117.056612) (width 0.1) (layer "F.Cu") (net 175))
  (segment (start 134.1 117.1) (end 134.097492 117.077748) (width 0.1) (layer "F.Cu") (net 175))
  (segment (start 134.7 117.1) (end 134.7 117.7) (width 0.1) (layer "F.Cu") (net 175))
  (segment (start 133.690096 117.456611) (end 133.678183 117.437651) (width 0.1) (layer "F.Cu") (net 175))
  (segment (start 135.302507 117.722252) (end 135.3 117.7) (width 0.1) (layer "F.Cu") (net 175))
  (segment (start 133.7 117.7) (end 133.7 117.5) (width 0.1) (layer "F.Cu") (net 175))
  (segment (start 135.177747 117.002508) (end 135.156611 117.009904) (width 0.1) (layer "F.Cu") (net 175))
  (segment (start 135.521816 117.437651) (end 135.509903 117.456611) (width 0.1) (layer "F.Cu") (net 175))
  (segment (start 134.043388 117.009904) (end 134.022252 117.002508) (width 0.1) (layer "F.Cu") (net 175))
  (segment (start 135.6 117.4) (end 135.577747 117.402507) (width 0.1) (layer "F.Cu") (net 175))
  (segment (start 134.497492 117.077748) (end 134.490096 117.056612) (width 0.1) (layer "F.Cu") (net 175))
  (segment (start 134.109903 117.743388) (end 134.102507 117.722252) (width 0.1) (layer "F.Cu") (net 175))
  (segment (start 135.022252 117.797492) (end 135 117.8) (width 0.1) (layer "F.Cu") (net 175))
  (segment (start 134.321816 117.037652) (end 134.309903 117.056612) (width 0.1) (layer "F.Cu") (net 175))
  (segment (start 133.902507 117.077748) (end 133.9 117.1) (width 0.1) (layer "F.Cu") (net 175))
  (segment (start 135.278183 117.037652) (end 135.262348 117.021817) (width 0.1) (layer "F.Cu") (net 175))
  (segment (start 134.8 117) (end 134.777747 117.002508) (width 0.1) (layer "F.Cu") (net 175))
  (segment (start 134 117) (end 133.977747 117.002508) (width 0.1) (layer "F.Cu") (net 175))
  (segment (start 135.090096 117.743388) (end 135.078183 117.762348) (width 0.1) (layer "F.Cu") (net 175))
  (segment (start 133.643388 117.409903) (end 133.622252 117.402507) (width 0.1) (layer "F.Cu") (net 175))
  (segment (start 134.909903 117.743388) (end 134.902507 117.722252) (width 0.1) (layer "F.Cu") (net 175))
  (segment (start 135.121816 117.037652) (end 135.109903 117.056612) (width 0.1) (layer "F.Cu") (net 175))
  (segment (start 133.977747 117.002508) (end 133.956611 117.009904) (width 0.1) (layer "F.Cu") (net 175))
  (segment (start 134.9 117.7) (end 134.9 117.1) (width 0.1) (layer "F.Cu") (net 175))
  (segment (start 134.897492 117.077748) (end 134.890096 117.056612) (width 0.1) (layer "F.Cu") (net 175))
  (segment (start 133.7 117.5) (end 133.697492 117.477747) (width 0.1) (layer "F.Cu") (net 175))
  (segment (start 140.386265 114.6) (end 138.59 114.6) (width 0.1) (layer "F.Cu") (net 175))
  (segment (start 135.3 117.1) (end 135.297492 117.077748) (width 0.1) (layer "F.Cu") (net 175))
  (segment (start 134.721816 117.037652) (end 134.709903 117.056612) (width 0.1) (layer "F.Cu") (net 175))
  (segment (start 135.222252 117.002508) (end 135.2 117) (width 0.1) (layer "F.Cu") (net 175))
  (segment (start 134.262348 117.778183) (end 134.243388 117.790096) (width 0.1) (layer "F.Cu") (net 175))
  (segment (start 133.662348 117.421816) (end 133.643388 117.409903) (width 0.1) (layer "F.Cu") (net 175))
  (segment (start 134.222252 117.797492) (end 134.2 117.8) (width 0.1) (layer "F.Cu") (net 175))
  (segment (start 134.3 117.1) (end 134.3 117.7) (width 0.1) (layer "F.Cu") (net 175))
  (segment (start 134.243388 117.790096) (end 134.222252 117.797492) (width 0.1) (layer "F.Cu") (net 175))
  (segment (start 133.897492 117.722252) (end 133.890096 117.743388) (width 0.1) (layer "F.Cu") (net 175))
  (segment (start 134.302507 117.077748) (end 134.3 117.1) (width 0.1) (layer "F.Cu") (net 175))
  (segment (start 135.422252 117.797492) (end 135.4 117.8) (width 0.1) (layer "F.Cu") (net 175))

  (zone (net 3) (net_name "GNDA") (layer "F.Cu") (hatch edge 0.508)
    (connect_pads yes (clearance 0.15))
    (min_thickness 0.254) (filled_areas_thickness no)
    (fill yes (thermal_gap 0.508) (thermal_bridge_width 0.508))
    (polygon
      (pts
        (xy 104.6 102.8)
        (xy 98 102.8)
        (xy 98 100.6)
        (xy 104.6 100.6)
      )
    )
  )
  (zone (net 3) (net_name "GNDA") (layer "F.Cu") (hatch edge 0.508)
    (connect_pads yes (clearance 0.15))
    (min_thickness 0.254) (filled_areas_thickness no)
    (fill yes (thermal_gap 0.508) (thermal_bridge_width 0.508))
    (polygon
      (pts
        (xy 104.6 132.4)
        (xy 98 132.4)
        (xy 98 130.2)
        (xy 104.6 130.2)
      )
    )
  )
  (zone (net 3) (net_name "GNDA") (layer "F.Cu") (hatch edge 0.508)
    (connect_pads yes (clearance 0.15))
    (min_thickness 0.254) (filled_areas_thickness no)
    (fill yes (thermal_gap 0.508) (thermal_bridge_width 0.508))
    (polygon
      (pts
        (xy 104.6 113.4)
        (xy 98 113.4)
        (xy 98 111.2)
        (xy 104.6 111.2)
      )
    )
  )
  (zone (net 3) (net_name "GNDA") (layer "F.Cu") (hatch edge 0.508)
    (connect_pads yes (clearance 0.15))
    (min_thickness 0.254) (filled_areas_thickness no)
    (fill yes (thermal_gap 0.508) (thermal_bridge_width 0.508))
    (polygon
      (pts
        (xy 104.6 121.8)
        (xy 98 121.8)
        (xy 98 119.6)
        (xy 104.6 119.6)
      )
    )
  )
  (zone (net 0) (net_name "") (layers "F.Cu" "In1.Cu" "In2.Cu" "In3.Cu" "In4.Cu" "B.Cu") (hatch edge 0.508)
    (connect_pads (clearance 0))
    (min_thickness 0.254) (filled_areas_thickness no)
    (keepout (tracks allowed) (vias not_allowed) (pads allowed) (copperpour allowed) (footprints allowed))
    (fill (thermal_gap 0.508) (thermal_bridge_width 0.508))
    (polygon
      (pts
        (xy 154.3 100.8)
        (xy 140.4 100.8)
        (xy 140.4 97.7)
        (xy 154.3 97.7)
      )
    )
  )
  (zone (net 0) (net_name "") (layers "F.Cu" "In1.Cu" "In2.Cu" "In3.Cu" "In4.Cu" "B.Cu") (hatch edge 0.508)
    (connect_pads (clearance 0))
    (min_thickness 0.15) (filled_areas_thickness no)
    (keepout (tracks allowed) (vias allowed) (pads allowed) (copperpour not_allowed) (footprints allowed))
    (fill (thermal_gap 0.508) (thermal_bridge_width 0.508))
    (polygon
      (pts
        (xy 101 111.25)
        (xy 98 111.25)
        (xy 98 102.75)
        (xy 101 102.75)
      )
    )
  )
  (zone (net 0) (net_name "") (layers "F.Cu" "In1.Cu" "In2.Cu" "In3.Cu" "In4.Cu" "B.Cu") (hatch edge 0.508)
    (connect_pads (clearance 0))
    (min_thickness 0.254) (filled_areas_thickness no)
    (keepout (tracks allowed) (vias not_allowed) (pads allowed) (copperpour allowed) (footprints allowed))
    (fill (thermal_gap 0.508) (thermal_bridge_width 0.508))
    (polygon
      (pts
        (xy 139.9 102.8)
        (xy 134 102.8)
        (xy 134 96.2)
        (xy 139.9 96.2)
      )
    )
  )
  (zone (net 0) (net_name "") (layers "F.Cu" "In1.Cu" "In2.Cu" "In3.Cu" "In4.Cu" "B.Cu") (hatch edge 0.508)
    (connect_pads (clearance 0))
    (min_thickness 0.15) (filled_areas_thickness no)
    (keepout (tracks allowed) (vias allowed) (pads allowed) (copperpour not_allowed) (footprints allowed))
    (fill (thermal_gap 0.508) (thermal_bridge_width 0.508))
    (polygon
      (pts
        (xy 115.2 120.4)
        (xy 113.4 120.4)
        (xy 113.4 118.4)
        (xy 115.2 118.4)
      )
    )
  )
  (zone (net 0) (net_name "") (layers "F.Cu" "In1.Cu" "In2.Cu" "In3.Cu" "In4.Cu" "B.Cu") (hatch edge 0.508)
    (connect_pads (clearance 0))
    (min_thickness 0.15) (filled_areas_thickness no)
    (keepout (tracks allowed) (vias allowed) (pads allowed) (copperpour not_allowed) (footprints allowed))
    (fill (thermal_gap 0.508) (thermal_bridge_width 0.508))
    (polygon
      (pts
        (xy 101 130.25)
        (xy 98 130.25)
        (xy 98 121.75)
        (xy 101 121.75)
      )
    )
  )
  (zone (net 0) (net_name "") (layers "F.Cu" "In1.Cu" "In2.Cu" "In3.Cu" "In4.Cu" "B.Cu") (hatch edge 0.508)
    (connect_pads (clearance 0))
    (min_thickness 0.254) (filled_areas_thickness no)
    (keepout (tracks allowed) (vias not_allowed) (pads allowed) (copperpour allowed) (footprints allowed))
    (fill (thermal_gap 0.508) (thermal_bridge_width 0.508))
    (polygon
      (pts
        (xy 153.075 104)
        (xy 140.5 104)
        (xy 140.5 101.4)
        (xy 153.075 101.4)
      )
    )
  )
  (zone (net 0) (net_name "") (layer "In1.Cu") (hatch edge 0.508)
    (connect_pads (clearance 0))
    (min_thickness 0.15) (filled_areas_thickness no)
    (keepout (tracks allowed) (vias allowed) (pads allowed) (copperpour not_allowed) (footprints allowed))
    (fill (thermal_gap 0.508) (thermal_bridge_width 0.508))
    (polygon
      (pts
        (xy 116 102.75)
        (xy 116 112.5)
        (xy 117 112.5)
        (xy 117 114.25)
        (xy 116 114.25)
        (xy 116 115.25)
        (xy 98 115.25)
        (xy 98 101.5)
        (xy 116 101.5)
      )
    )
  )
  (zone (net 1) (net_name "GNDREF") (layer "In1.Cu") (hatch edge 0.508)
    (connect_pads (clearance 0.15))
    (min_thickness 0.15) (filled_areas_thickness no)
    (fill yes (thermal_gap 0.508) (thermal_bridge_width 0.508))
    (polygon
      (pts
        (xy 168 137.5)
        (xy 98 137.5)
        (xy 98 95.5)
        (xy 119.875 95.5)
        (xy 141.75 95.5)
        (xy 168 95.5)
      )
    )
  )
  (zone (net 0) (net_name "") (layer "In1.Cu") (hatch edge 0.508)
    (connect_pads (clearance 0))
    (min_thickness 0.15) (filled_areas_thickness no)
    (keepout (tracks allowed) (vias allowed) (pads allowed) (copperpour not_allowed) (footprints allowed))
    (fill (thermal_gap 0.508) (thermal_bridge_width 0.508))
    (polygon
      (pts
        (xy 110.25 131.5)
        (xy 98 131.5)
        (xy 98 117.75)
        (xy 110.25 117.75)
      )
    )
  )
  (zone (net 0) (net_name "") (layers "In1.Cu" "In2.Cu" "In3.Cu" "In4.Cu" "B.Cu") (hatch edge 0.508)
    (connect_pads (clearance 0))
    (min_thickness 0.254) (filled_areas_thickness no)
    (keepout (tracks not_allowed) (vias allowed) (pads allowed) (copperpour allowed) (footprints allowed))
    (fill (thermal_gap 0.508) (thermal_bridge_width 0.508))
    (polygon
      (pts
        (xy 124.85 131.25)
        (xy 118.75 131.25)
        (xy 118.76 126.27)
        (xy 124.85 126.27)
      )
    )
  )
  (zone (net 3) (net_name "GNDA") (layer "In2.Cu") (hatch edge 0.508)
    (connect_pads (clearance 0.15))
    (min_thickness 0.15) (filled_areas_thickness no)
    (fill yes (thermal_gap 0.508) (thermal_bridge_width 0.508))
    (polygon
      (pts
        (xy 168 137.5)
        (xy 98 137.5)
        (xy 98 95.5)
        (xy 168 95.5)
      )
    )
  )
  (zone (net 57) (net_name "VDD") (layer "In3.Cu") (hatch edge 0.508)
    (connect_pads (clearance 0.15))
    (min_thickness 0.15) (filled_areas_thickness no)
    (fill yes (thermal_gap 0.508) (thermal_bridge_width 0.508))
    (polygon
      (pts
        (xy 115.25 137.5)
        (xy 98 137.5)
        (xy 98 95.5)
        (xy 115.25 95.5)
      )
    )
  )
  (zone (net 3) (net_name "GNDA") (layer "In3.Cu") (hatch edge 0.508)
    (connect_pads (clearance 0.15))
    (min_thickness 0.15) (filled_areas_thickness no)
    (fill yes (thermal_gap 0.508) (thermal_bridge_width 0.508))
    (polygon
      (pts
        (xy 168 137.5)
        (xy 115.5 137.5)
        (xy 115.5 95.5)
        (xy 168 95.5)
      )
    )
  )
  (zone (net 58) (net_name "/GNDPLL_DPHY") (layer "In3.Cu") (hatch edge 0.508)
    (priority 1)
    (connect_pads (clearance 0.2))
    (min_thickness 0.254) (filled_areas_thickness no)
    (fill yes (thermal_gap 0.508) (thermal_bridge_width 0.508))
    (polygon
      (pts
        (xy 148.5 116.5)
        (xy 145.75 116.5)
        (xy 145.75 118)
        (xy 149.25 118)
        (xy 149.25 107.897)
        (xy 148.5 107.897)
      )
    )
  )
  (zone (net 6) (net_name "+3V3") (layer "In4.Cu") (hatch edge 0.508)
    (connect_pads (clearance 0.2))
    (min_thickness 0.254) (filled_areas_thickness no)
    (fill yes (thermal_gap 0.508) (thermal_bridge_width 0.508))
    (polygon
      (pts
        (xy 168 133)
        (xy 148.8 133)
        (xy 149.054 113)
        (xy 149.054 106)
        (xy 125.25 106)
        (xy 125.25 103.5)
        (xy 105.5 103.5)
        (xy 105.5 128)
        (xy 121.5 128)
        (xy 121.5 133.25)
        (xy 125.25 133.25)
        (xy 125.25 126)
        (xy 130.25 126)
        (xy 130.25 133.25)
        (xy 130.25 137.5)
        (xy 98 137.5)
        (xy 98 95.5)
        (xy 168 95.5)
      )
    )
  )
  (zone (net 5) (net_name "+3.3VA") (layer "In4.Cu") (hatch edge 0.508)
    (connect_pads (clearance 0.2))
    (min_thickness 0.254) (filled_areas_thickness no)
    (fill yes (thermal_gap 0.508) (thermal_bridge_width 0.508))
    (polygon
      (pts
        (xy 125 106)
        (xy 109 106)
        (xy 109 126)
        (xy 125 126)
        (xy 125 133)
        (xy 121.75 133)
        (xy 121.75 127.75)
        (xy 105.75 127.75)
        (xy 105.75 103.75)
        (xy 125 103.75)
      )
    )
  )
  (zone (net 77) (net_name "VCCA_DPHY") (layer "In4.Cu") (hatch edge 0.508)
    (priority 1)
    (connect_pads (clearance 0.15))
    (min_thickness 0.15) (filled_areas_thickness no)
    (fill yes (thermal_gap 0.508) (thermal_bridge_width 0.508))
    (polygon
      (pts
        (xy 149 113)
        (xy 149 118)
        (xy 146 118)
        (xy 146 108.519)
        (xy 128.976 108.519)
        (xy 128.976 106.25)
        (xy 150 106.25)
        (xy 150 113)
      )
    )
  )
  (zone (net 5) (net_name "+3.3VA") (layer "In4.Cu") (hatch edge 0.508)
    (connect_pads (clearance 0.15))
    (min_thickness 0.15) (filled_areas_thickness no)
    (fill yes (thermal_gap 0.508) (thermal_bridge_width 0.508))
    (polygon
      (pts
        (xy 116.75 123)
        (xy 114.75 123)
        (xy 114.75 113.5)
        (xy 116.75 113.5)
      )
    )
  )
  (zone (net 76) (net_name "IO_VDD") (layer "In4.Cu") (hatch edge 0.508)
    (connect_pads (clearance 0.15))
    (min_thickness 0.15) (filled_areas_thickness no)
    (fill yes (thermal_gap 0.508) (thermal_bridge_width 0.508))
    (polygon
      (pts
        (xy 128.694008 117)
        (xy 123.218008 117)
        (xy 123.218008 109.75)
        (xy 114.468008 109.75)
        (xy 114.468008 123.25)
        (xy 133.25 123.25)
        (xy 133.25 135.5)
        (xy 136.75 135.5)
        (xy 136.75 133.25)
        (xy 168 133.25)
        (xy 168 137.5)
        (xy 130.5 137.5)
        (xy 130.5 125.75)
        (xy 109.25 125.75)
        (xy 109.218008 106.25)
        (xy 128.694008 106.25)
      )
    )
  )
  (zone (net 79) (net_name "VCC_IO") (layer "In4.Cu") (hatch edge 0.508)
    (priority 3)
    (connect_pads (clearance 0.2))
    (min_thickness 0.254) (filled_areas_thickness no)
    (fill yes (thermal_gap 0.508) (thermal_bridge_width 0.508))
    (polygon
      (pts
        (xy 145.75 118)
        (xy 140.799 118)
        (xy 140.799 115.24)
        (xy 141.561 114.859)
        (xy 141.561 112.192)
        (xy 140.5 111.049)
        (xy 140.5 109.2)
        (xy 145.75 109.2)
      )
    )
  )
  (zone (net 2) (net_name "+1V2") (layer "In4.Cu") (hatch edge 0.508)
    (priority 2)
    (connect_pads (clearance 0.15))
    (min_thickness 0.15) (filled_areas_thickness no)
    (fill yes (thermal_gap 0.508) (thermal_bridge_width 0.508))
    (polygon
      (pts
        (xy 149.816 121.336)
        (xy 148.8 122.352)
        (xy 148.8 126.162)
        (xy 149.75796 127.178)
        (xy 152.864 127.178)
        (xy 152.864 133)
        (xy 136.5 133)
        (xy 136.5 135.25)
        (xy 133.5 135.25)
        (xy 133.5 128.5)
        (xy 138.5 128.5)
        (xy 138.5 120)
        (xy 120.5 120)
        (xy 120.5 110)
        (xy 123 110)
        (xy 123 117.25)
        (xy 128.849 117.25)
        (xy 128.849 108.128)
        (xy 138.513 108.128)
        (xy 139.402 108.692)
        (xy 141.688 108.692)
        (xy 141.688 118.25)
        (xy 149.816 118.25)
        (xy 150.578 118.796)
        (xy 150.578 120.088897)
        (xy 149.816 120.574)
      )
    )
  )
  (zone (net 4) (net_name "VPP") (layer "In4.Cu") (hatch edge 0.508)
    (connect_pads (clearance 0.15))
    (min_thickness 0.15) (filled_areas_thickness no)
    (fill yes (thermal_gap 0.508) (thermal_bridge_width 0.508))
    (polygon
      (pts
        (xy 120.25 120.25)
        (xy 138.25 120.25)
        (xy 138.25 128.25)
        (xy 133.5 128.25)
        (xy 133.5 123)
        (xy 117 123)
        (xy 117 113.25)
        (xy 114.75 113.25)
        (xy 114.75 110)
        (xy 120.25 110)
      )
    )
  )
  (zone (net 3) (net_name "GNDA") (layer "B.Cu") (hatch edge 0.508)
    (connect_pads yes (clearance 0.15))
    (min_thickness 0.254) (filled_areas_thickness no)
    (fill yes (thermal_gap 0.508) (thermal_bridge_width 0.508))
    (polygon
      (pts
        (xy 104.6 121.8)
        (xy 98 121.8)
        (xy 98 119.6)
        (xy 104.6 119.6)
      )
    )
  )
  (zone (net 3) (net_name "GNDA") (layer "B.Cu") (hatch edge 0.508)
    (connect_pads yes (clearance 0.15))
    (min_thickness 0.254) (filled_areas_thickness no)
    (fill yes (thermal_gap 0.508) (thermal_bridge_width 0.508))
    (polygon
      (pts
        (xy 104.6 132.4)
        (xy 98 132.4)
        (xy 98 130.2)
        (xy 104.6 130.2)
      )
    )
  )
  (zone (net 3) (net_name "GNDA") (layer "B.Cu") (hatch edge 0.508)
    (connect_pads yes (clearance 0.15))
    (min_thickness 0.254) (filled_areas_thickness no)
    (fill yes (thermal_gap 0.508) (thermal_bridge_width 0.508))
    (polygon
      (pts
        (xy 104.6 102.8)
        (xy 98 102.8)
        (xy 98 100.6)
        (xy 104.6 100.6)
      )
    )
  )
  (zone (net 3) (net_name "GNDA") (layer "B.Cu") (hatch edge 0.508)
    (connect_pads yes (clearance 0.15))
    (min_thickness 0.254) (filled_areas_thickness no)
    (fill yes (thermal_gap 0.508) (thermal_bridge_width 0.508))
    (polygon
      (pts
        (xy 104.6 113.4)
        (xy 98 113.4)
        (xy 98 111.2)
        (xy 104.6 111.2)
      )
    )
  )
)
